(kicad_pcb
	(version 20260206)
	(generator "pcbnew")
	(generator_version "10.0")
	(general
		(thickness 1.6)
		(legacy_teardrops no)
	)
	(paper "A4")
	(layers
		(0 "F.Cu" signal "TOP")
		(4 "In1.Cu" signal "L2GND")
		(6 "In2.Cu" signal "L3")
		(8 "In3.Cu" signal "L4VCC")
		(10 "In4.Cu" signal "L5VCC")
		(12 "In5.Cu" signal "L6")
		(14 "In6.Cu" signal "L7GND")
		(2 "B.Cu" signal "BOTTOM")
		(9 "F.Adhes" user "F.Adhesive")
		(11 "B.Adhes" user "B.Adhesive")
		(13 "F.Paste" user "Package Geometry/Pastemask Top")
		(15 "B.Paste" user "Package Geometry/Pastemask Bottom")
		(5 "F.SilkS" user "Ref Des/Silkscreen Top")
		(7 "B.SilkS" user "Ref Des/Silkscreen Bottom")
		(1 "F.Mask" user "Board Geometry/Soldermask Top")
		(3 "B.Mask" user "Board Geometry/Soldermask Bottom")
		(17 "Dwgs.User" user "User.Drawings")
		(19 "Cmts.User" user "User.Comments")
		(21 "Eco1.User" user "User.Eco1")
		(23 "Eco2.User" user "User.Eco2")
		(25 "Edge.Cuts" user "Board Geometry/Outline")
		(27 "Margin" user)
		(31 "F.CrtYd" user "Package Geometry/Place Bound Top")
		(29 "B.CrtYd" user "Package Geometry/Place Bound Bottom")
		(35 "F.Fab" user "Ref Des/Assembly Top")
		(33 "B.Fab" user "Ref Des/Assembly Bottom")
	)
	(setup
		(pad_to_mask_clearance 0)
		(allow_soldermask_bridges_in_footprints no)
		(tenting
			(front yes)
			(back yes)
		)
		(covering
			(front no)
			(back no)
		)
		(plugging
			(front no)
			(back no)
		)
		(capping no)
		(filling no)
		(pcbplotparams
			(layerselection 0x00000000_00000000_55555555_5755f5ff)
			(plot_on_all_layers_selection 0x00000000_00000000_00000000_00000000)
			(disableapertmacros no)
			(usegerberextensions no)
			(usegerberattributes yes)
			(usegerberadvancedattributes yes)
			(creategerberjobfile yes)
			(dashed_line_dash_ratio 12)
			(dashed_line_gap_ratio 3)
			(svgprecision 4)
			(plotframeref no)
			(mode 1)
			(useauxorigin no)
			(pdf_front_fp_property_popups yes)
			(pdf_back_fp_property_popups yes)
			(pdf_metadata yes)
			(pdf_single_document no)
			(dxfpolygonmode yes)
			(dxfimperialunits yes)
			(dxfusepcbnewfont yes)
			(psnegative no)
			(psa4output no)
			(plot_black_and_white yes)
			(sketchpadsonfab no)
			(plotpadnumbers no)
			(hidednponfab no)
			(sketchdnponfab yes)
			(crossoutdnponfab yes)
			(subtractmaskfromsilk no)
			(outputformat 1)
			(mirror no)
			(drillshape 1)
			(scaleselection 1)
			(outputdirectory "")
		)
	)
	(footprint ""
		(layer "F.Cu")
		(at 87.269828 -45.765212)
		(property "Reference" "R16"
			(at 0 0 0)
			(layer "F.SilkS")
			(hide yes)
			(effects
				(font
					(size 1.27 1.27)
				)
			)
		)
		(property "Value" "10KR2F-2-GP"
			(at 0.064008 -3.993896 0)
			(unlocked yes)
			(layer "F.Fab")
			(hide yes)
			(effects
				(font
					(size 1.016 1.016)
					(thickness 0.1524)
				)
			)
		)
		(property "Device Type" "R402H16"
			(at 0.064008 -5.517896 0)
			(unlocked yes)
			(layer "F.Fab")
			(hide yes)
			(effects
				(font
					(size 1.016 1.016)
					(thickness 0.1524)
				)
			)
		)
		(duplicate_pad_numbers_are_jumpers no)
		(fp_line
			(start -0.508 -0.9398)
			(end -0.508 0.9398)
			(stroke
				(width 0.1524)
				(type default)
			)
			(layer "F.SilkS")
		)
		(fp_line
			(start 0.508 -0.9398)
			(end -0.508 -0.9398)
			(stroke
				(width 0.1524)
				(type default)
			)
			(layer "F.SilkS")
		)
		(fp_rect
			(start -0.508 0.9398)
			(end 0.508 -0.9398)
			(stroke
				(width 0)
				(type default)
			)
			(fill no)
			(layer "F.CrtYd")
		)
		(fp_rect
			(start -0.508 0.9398)
			(end 0.508 -0.9398)
			(stroke
				(width 0)
				(type default)
			)
			(fill no)
			(layer "F.Fab")
		)
		(pad "1" smd custom
			(at 0 -0.4445)
			(size 0.1397 0.1397)
			(layers "F.Cu" "F.Mask" "F.Paste")
			(net "P3V3_STBY")
			(options
				(clearance outline)
				(anchor circle)
			)
			(primitives
				(gr_poly
					(pts
						(arc
							(start -0.1778 -0.2794)
							(mid -0.249642 -0.249642)
							(end -0.2794 -0.1778)
						)
						(arc
							(start -0.2794 0.1778)
							(mid -0.249642 0.249642)
							(end -0.1778 0.2794)
						)
						(arc
							(start 0.1778 0.2794)
							(mid 0.249642 0.249642)
							(end 0.2794 0.1778)
						)
						(arc
							(start 0.2794 -0.1778)
							(mid 0.249642 -0.249642)
							(end 0.1778 -0.2794)
						)
					)
					(width 0)
					(fill yes)
				)
			)
		)
		(pad "2" smd custom
			(at 0 0.4445)
			(size 0.1397 0.1397)
			(layers "F.Cu" "F.Mask" "F.Paste")
			(net "MEZZA_PRSNT1_N")
			(options
				(clearance outline)
				(anchor circle)
			)
			(primitives
				(gr_poly
					(pts
						(arc
							(start -0.1778 -0.2794)
							(mid -0.249642 -0.249642)
							(end -0.2794 -0.1778)
						)
						(arc
							(start -0.2794 0.1778)
							(mid -0.249642 0.249642)
							(end -0.1778 0.2794)
						)
						(arc
							(start 0.1778 0.2794)
							(mid 0.249642 0.249642)
							(end 0.2794 0.1778)
						)
						(arc
							(start 0.2794 -0.1778)
							(mid 0.249642 -0.249642)
							(end 0.1778 -0.2794)
						)
					)
					(width 0)
					(fill yes)
				)
			)
		)
	)
	(footprint ""
		(layer "F.Cu")
		(at 84.863178 -72.543416 90)
		(property "Reference" "VIA9"
			(at 0 0 90)
			(layer "F.SilkS")
			(hide yes)
			(effects
				(font
					(size 1.27 1.27)
				)
			)
		)
		(property "Value" "85OHM-8L-1D6MM-L16L18-GP"
			(at 4.064 0.6096 90)
			(unlocked yes)
			(layer "F.Fab")
			(hide yes)
			(effects
				(font
					(size 1.016 1.016)
					(thickness 0.1524)
				)
			)
		)
		(property "Device Type" "VIA-PCIE-4P-368076"
			(at 4.064 -0.9144 90)
			(unlocked yes)
			(layer "F.Fab")
			(hide yes)
			(effects
				(font
					(size 1.016 1.016)
					(thickness 0.1524)
				)
			)
		)
		(duplicate_pad_numbers_are_jumpers no)
		(fp_rect
			(start -1.8415 0.381)
			(end 1.8415 -0.381)
			(stroke
				(width 0)
				(type default)
			)
			(fill no)
			(layer "F.CrtYd")
		)
		(fp_rect
			(start -1.8415 0.381)
			(end 1.8415 -0.381)
			(stroke
				(width 0)
				(type default)
			)
			(fill no)
			(layer "F.Fab")
		)
		(pad "1" thru_hole circle
			(at -1.4605 0 90)
			(size 0.508 0.508)
			(drill 0.254)
			(layers "*.Cu" "*.Mask")
			(remove_unused_layers no)
			(net "GND")
			(clearance 0.127)
			(thermal_gap 0.127)
		)
		(pad "2" thru_hole circle
			(at -0.4445 0 90)
			(size 0.508 0.508)
			(drill 0.254)
			(layers "*.Cu" "*.Mask")
			(remove_unused_layers no)
			(net "PCIE_IOM_TO_COMP_16_DP")
			(clearance 0.127)
			(thermal_gap 0.127)
		)
		(pad "3" thru_hole circle
			(at 0.4445 0 90)
			(size 0.508 0.508)
			(drill 0.254)
			(layers "*.Cu" "*.Mask")
			(remove_unused_layers no)
			(net "PCIE_IOM_TO_COMP_16_DN")
			(clearance 0.127)
			(thermal_gap 0.127)
		)
		(pad "4" thru_hole circle
			(at 1.4605 0 90)
			(size 0.508 0.508)
			(drill 0.254)
			(layers "*.Cu" "*.Mask")
			(remove_unused_layers no)
			(net "GND")
			(clearance 0.127)
			(thermal_gap 0.127)
		)
	)
	(footprint ""
		(layer "F.Cu")
		(at 92.0242 -179.5018 -90)
		(property "Reference" "U106"
			(at 0 0 270)
			(layer "F.SilkS")
			(hide yes)
			(effects
				(font
					(size 1.27 1.27)
				)
			)
		)
		(property "Value" "SNLVC1G14DBVR-GP"
			(at 0 -5.1308 270)
			(unlocked yes)
			(layer "F.Fab")
			(hide yes)
			(effects
				(font
					(size 1.016 1.016)
					(thickness 0.1524)
				)
			)
		)
		(property "Device Type" "SOT-23-5H58"
			(at 0 -6.7564 270)
			(unlocked yes)
			(layer "F.Fab")
			(hide yes)
			(effects
				(font
					(size 1.016 1.016)
					(thickness 0.1524)
				)
			)
		)
		(duplicate_pad_numbers_are_jumpers no)
		(fp_line
			(start -1.778 2.286)
			(end -0.254 2.286)
			(stroke
				(width 0.1524)
				(type default)
			)
			(layer "F.SilkS")
		)
		(fp_line
			(start -1.778 2.286)
			(end 1.778 2.286)
			(stroke
				(width 0.1524)
				(type default)
			)
			(layer "F.SilkS")
		)
		(fp_line
			(start -0.254 2.286)
			(end 1.778 2.286)
			(stroke
				(width 0.1524)
				(type default)
			)
			(layer "F.SilkS")
		)
		(fp_line
			(start 1.778 2.286)
			(end 1.778 -2.286)
			(stroke
				(width 0.1524)
				(type default)
			)
			(layer "F.SilkS")
		)
		(fp_line
			(start -1.7272 2.2352)
			(end -1.7272 0.762)
			(stroke
				(width 0.3302)
				(type default)
			)
			(layer "F.SilkS")
		)
		(fp_line
			(start -0.7112 2.2352)
			(end -1.7272 2.2352)
			(stroke
				(width 0.3302)
				(type default)
			)
			(layer "F.SilkS")
		)
		(fp_line
			(start -1.778 -2.286)
			(end -1.778 2.286)
			(stroke
				(width 0.1524)
				(type default)
			)
			(layer "F.SilkS")
		)
		(fp_line
			(start 1.778 -2.286)
			(end -1.778 -2.286)
			(stroke
				(width 0.1524)
				(type default)
			)
			(layer "F.SilkS")
		)
		(fp_poly
			(pts
				(xy -0.9652 2.4384) (xy -1.3208 2.794) (xy -0.6096 2.794)
			)
			(stroke
				(width 0)
				(type default)
			)
			(fill yes)
			(layer "F.SilkS")
		)
		(fp_rect
			(start -1.778 2.286)
			(end 1.778 -2.286)
			(stroke
				(width 0)
				(type default)
			)
			(fill no)
			(layer "F.CrtYd")
		)
		(fp_rect
			(start -1.778 2.286)
			(end 1.778 -2.286)
			(stroke
				(width 0)
				(type default)
			)
			(fill no)
			(layer "F.Fab")
		)
		(pad "1" smd rect
			(at -0.94996 1.143 270)
			(size 0.508 1.524)
			(layers "F.Cu" "F.Mask" "F.Paste")
			(net "Net_132")
		)
		(pad "2" smd rect
			(at 0 1.143 270)
			(size 0.508 1.524)
			(layers "F.Cu" "F.Mask" "F.Paste")
			(net "PWRGD_P3V3_STBY")
		)
		(pad "3" smd rect
			(at 0.94996 1.143 270)
			(size 0.508 1.524)
			(layers "F.Cu" "F.Mask" "F.Paste")
			(net "GND")
		)
		(pad "4" smd rect
			(at 0.94996 -1.143 270)
			(size 0.508 1.524)
			(layers "F.Cu" "F.Mask" "F.Paste")
			(net "PWRGD_P3V3_STBY_N")
		)
		(pad "5" smd rect
			(at -0.94996 -1.143 270)
			(size 0.508 1.524)
			(layers "F.Cu" "F.Mask" "F.Paste")
			(net "P3V3_STBY")
		)
	)
	(footprint ""
		(layer "F.Cu")
		(at 88.813894 -63.755016 -90)
		(property "Reference" "R8"
			(at 0 0 270)
			(layer "F.SilkS")
			(hide yes)
			(effects
				(font
					(size 1.27 1.27)
				)
			)
		)
		(property "Value" "0R2J-2-GP"
			(at 0.064008 -3.993896 270)
			(unlocked yes)
			(layer "F.Fab")
			(hide yes)
			(effects
				(font
					(size 1.016 1.016)
					(thickness 0.1524)
				)
			)
		)
		(property "Device Type" "R402H16"
			(at 0.064008 -5.517896 270)
			(unlocked yes)
			(layer "F.Fab")
			(hide yes)
			(effects
				(font
					(size 1.016 1.016)
					(thickness 0.1524)
				)
			)
		)
		(duplicate_pad_numbers_are_jumpers no)
		(fp_line
			(start -0.508 -0.9398)
			(end -0.508 0.9398)
			(stroke
				(width 0.1524)
				(type default)
			)
			(layer "F.SilkS")
		)
		(fp_line
			(start 0.508 -0.9398)
			(end -0.508 -0.9398)
			(stroke
				(width 0.1524)
				(type default)
			)
			(layer "F.SilkS")
		)
		(fp_rect
			(start -0.508 0.9398)
			(end 0.508 -0.9398)
			(stroke
				(width 0)
				(type default)
			)
			(fill no)
			(layer "F.CrtYd")
		)
		(fp_rect
			(start -0.508 0.9398)
			(end 0.508 -0.9398)
			(stroke
				(width 0)
				(type default)
			)
			(fill no)
			(layer "F.Fab")
		)
		(pad "1" smd custom
			(at 0 -0.4445 270)
			(size 0.1397 0.1397)
			(layers "F.Cu" "F.Mask" "F.Paste")
			(net "PCIE_COMP_TO_IOM_RST_4")
			(options
				(clearance outline)
				(anchor circle)
			)
			(primitives
				(gr_poly
					(pts
						(arc
							(start -0.1778 -0.2794)
							(mid -0.249642 -0.249642)
							(end -0.2794 -0.1778)
						)
						(arc
							(start -0.2794 0.1778)
							(mid -0.249642 0.249642)
							(end -0.1778 0.2794)
						)
						(arc
							(start 0.1778 0.2794)
							(mid 0.249642 0.249642)
							(end 0.2794 0.1778)
						)
						(arc
							(start 0.2794 -0.1778)
							(mid 0.249642 -0.249642)
							(end 0.1778 -0.2794)
						)
					)
					(width 0)
					(fill yes)
				)
			)
		)
		(pad "2" smd custom
			(at 0 0.4445 270)
			(size 0.1397 0.1397)
			(layers "F.Cu" "F.Mask" "F.Paste")
			(net "PCIE_COMP_TO_IOM_RST_4_R")
			(options
				(clearance outline)
				(anchor circle)
			)
			(primitives
				(gr_poly
					(pts
						(arc
							(start -0.1778 -0.2794)
							(mid -0.249642 -0.249642)
							(end -0.2794 -0.1778)
						)
						(arc
							(start -0.2794 0.1778)
							(mid -0.249642 0.249642)
							(end -0.1778 0.2794)
						)
						(arc
							(start 0.1778 0.2794)
							(mid 0.249642 0.249642)
							(end 0.2794 0.1778)
						)
						(arc
							(start 0.2794 -0.1778)
							(mid 0.249642 -0.249642)
							(end 0.1778 -0.2794)
						)
					)
					(width 0)
					(fill yes)
				)
			)
		)
	)
	(footprint ""
		(layer "F.Cu")
		(at 222.293688 -23.022052 -90)
		(property "Reference" "C168"
			(at 0 0 270)
			(layer "F.SilkS")
			(hide yes)
			(effects
				(font
					(size 1.27 1.27)
				)
			)
		)
		(property "Value" "ST150U16VDM-3-GP"
			(at 0 -9.6012 270)
			(unlocked yes)
			(layer "F.Fab")
			(hide yes)
			(effects
				(font
					(size 1.016 1.016)
					(thickness 0.1524)
				)
			)
		)
		(property "Device Type" "CT7343H119"
			(at 0 -11.1252 270)
			(unlocked yes)
			(layer "F.Fab")
			(hide yes)
			(effects
				(font
					(size 1.016 1.016)
					(thickness 0.1524)
				)
			)
		)
		(duplicate_pad_numbers_are_jumpers no)
		(fp_line
			(start -2.286 4.8768)
			(end -2.286 2.032)
			(stroke
				(width 0.1524)
				(type default)
			)
			(layer "F.SilkS")
		)
		(fp_line
			(start 2.286 4.8768)
			(end -2.286 4.8768)
			(stroke
				(width 0.1524)
				(type default)
			)
			(layer "F.SilkS")
		)
		(fp_line
			(start 2.286 2.032)
			(end 2.286 4.8768)
			(stroke
				(width 0.1524)
				(type default)
			)
			(layer "F.SilkS")
		)
		(fp_line
			(start 2.286 -2.032)
			(end 2.286 -4.8768)
			(stroke
				(width 0.1524)
				(type default)
			)
			(layer "F.SilkS")
		)
		(fp_line
			(start 2.1082 -4.699)
			(end -2.1082 -4.699)
			(stroke
				(width 0.508)
				(type default)
			)
			(layer "F.SilkS")
		)
		(fp_line
			(start -2.286 -4.8768)
			(end -2.286 -2.032)
			(stroke
				(width 0.1524)
				(type default)
			)
			(layer "F.SilkS")
		)
		(fp_line
			(start 2.286 -4.8768)
			(end -2.286 -4.8768)
			(stroke
				(width 0.1524)
				(type default)
			)
			(layer "F.SilkS")
		)
		(fp_rect
			(start -2.1463 3.6449)
			(end 2.1463 -3.6449)
			(stroke
				(width 0)
				(type default)
			)
			(fill no)
			(layer "F.CrtYd")
		)
		(fp_poly
			(pts
				(xy -2.54 4.953) (xy -2.54 4.2926) (xy -3.81 4.2926) (xy -3.81 -4.2926) (xy -2.54 -4.2926) (xy -2.54 -4.953)
				(xy 2.54 -4.953) (xy 2.54 -4.2926) (xy 3.81 -4.2926) (xy 3.81 -1.6256) (xy 2.1463 -1.6256) (xy 2.1463 -3.6449)
				(xy -2.1463 -3.6449) (xy -2.1463 3.6449) (xy 2.1463 3.6449) (xy 2.1463 -1.6129) (xy 3.81 -1.6129)
				(xy 3.81 4.2926) (xy 2.54 4.2926) (xy 2.54 4.953)
			)
			(stroke
				(width 0)
				(type default)
			)
			(fill no)
			(layer "F.CrtYd")
		)
		(fp_rect
			(start -2.54 4.953)
			(end 2.54 -4.953)
			(stroke
				(width 0)
				(type default)
			)
			(fill no)
			(layer "F.Fab")
		)
		(fp_rect
			(start -3.81 4.2926)
			(end -2.54 -4.2926)
			(stroke
				(width 0)
				(type default)
			)
			(fill no)
			(layer "F.Fab")
		)
		(fp_rect
			(start 2.54 4.2926)
			(end 3.81 -4.2926)
			(stroke
				(width 0)
				(type default)
			)
			(fill no)
			(layer "F.Fab")
		)
		(pad "1" smd rect
			(at 0 -3.1496 270)
			(size 2.413 2.286)
			(layers "F.Cu" "F.Mask" "F.Paste")
			(net "P5V_STBY")
		)
		(pad "2" smd rect
			(at 0 3.1496 270)
			(size 2.413 2.286)
			(layers "F.Cu" "F.Mask" "F.Paste")
			(net "GND")
		)
		(zone
			(layer "F.Cu")
			(hatch none 0.5)
			(connect_pads
				(clearance 0)
			)
			(min_thickness 0.25)
			(keepout
				(tracks allowed)
				(vias not_allowed)
				(pads allowed)
				(copperpour not_allowed)
				(footprints allowed)
			)
			(placement
				(enabled no)
				(sheetname "")
			)
			(fill
				(thermal_gap 0.5)
				(thermal_bridge_width 0.5)
				(island_removal_mode 0)
			)
			(polygon
				(pts
					(xy 217.696288 -24.533352) (xy 217.696288 -21.510752) (xy 220.591888 -21.510752) (xy 220.922088 -21.510752)
					(xy 220.922088 -24.533352) (xy 220.591888 -24.533352)
				)
			)
		)
		(zone
			(layer "F.Cu")
			(hatch none 0.5)
			(connect_pads
				(clearance 0)
			)
			(min_thickness 0.25)
			(keepout
				(tracks allowed)
				(vias not_allowed)
				(pads allowed)
				(copperpour not_allowed)
				(footprints allowed)
			)
			(placement
				(enabled no)
				(sheetname "")
			)
			(fill
				(thermal_gap 0.5)
				(thermal_bridge_width 0.5)
				(island_removal_mode 0)
			)
			(polygon
				(pts
					(xy 223.982788 -21.510752) (xy 226.891088 -21.510752) (xy 226.891088 -24.533352) (xy 223.995488 -24.533352)
					(xy 223.665288 -24.533352) (xy 223.665288 -21.510752)
				)
			)
		)
	)
	(footprint ""
		(layer "F.Cu")
		(at 215.266524 -86.42096 -90)
		(property "Reference" "C652"
			(at 0 0 270)
			(layer "F.SilkS")
			(hide yes)
			(effects
				(font
					(size 1.27 1.27)
				)
			)
		)
		(property "Value" "SCD1U50V3KX-GP"
			(at 0 -2.8194 270)
			(unlocked yes)
			(layer "F.Fab")
			(hide yes)
			(effects
				(font
					(size 1.016 1.016)
					(thickness 0.1524)
				)
			)
		)
		(property "Device Type" "C603H36"
			(at 0 -4.3434 270)
			(unlocked yes)
			(layer "F.Fab")
			(hide yes)
			(effects
				(font
					(size 1.016 1.016)
					(thickness 0.1524)
				)
			)
		)
		(duplicate_pad_numbers_are_jumpers no)
		(fp_line
			(start 0.508 0)
			(end -0.508 0)
			(stroke
				(width 0.2032)
				(type default)
			)
			(layer "F.SilkS")
		)
		(fp_rect
			(start -0.5842 1.3335)
			(end 0.5842 -1.3335)
			(stroke
				(width 0)
				(type default)
			)
			(fill no)
			(layer "F.CrtYd")
		)
		(fp_rect
			(start -0.5842 1.3335)
			(end 0.5842 -1.3335)
			(stroke
				(width 0)
				(type default)
			)
			(fill no)
			(layer "F.Fab")
		)
		(pad "1" smd custom
			(at 0 -0.762 270)
			(size 0.2159 0.2159)
			(layers "F.Cu" "F.Mask" "F.Paste")
			(net "P3V3_M2")
			(options
				(clearance outline)
				(anchor circle)
			)
			(primitives
				(gr_poly
					(pts
						(arc
							(start -0.3302 -0.4318)
							(mid -0.402042 -0.402042)
							(end -0.4318 -0.3302)
						)
						(arc
							(start -0.4318 0.3302)
							(mid -0.402042 0.402042)
							(end -0.3302 0.4318)
						)
						(arc
							(start 0.3302 0.4318)
							(mid 0.402042 0.402042)
							(end 0.4318 0.3302)
						)
						(arc
							(start 0.4318 -0.3302)
							(mid 0.402042 -0.402042)
							(end 0.3302 -0.4318)
						)
					)
					(width 0)
					(fill yes)
				)
			)
		)
		(pad "2" smd custom
			(at 0 0.762 270)
			(size 0.2159 0.2159)
			(layers "F.Cu" "F.Mask" "F.Paste")
			(net "P3V3_M2_LL_R")
			(options
				(clearance outline)
				(anchor circle)
			)
			(primitives
				(gr_poly
					(pts
						(arc
							(start -0.3302 -0.4318)
							(mid -0.402042 -0.402042)
							(end -0.4318 -0.3302)
						)
						(arc
							(start -0.4318 0.3302)
							(mid -0.402042 0.402042)
							(end -0.3302 0.4318)
						)
						(arc
							(start 0.3302 0.4318)
							(mid 0.402042 0.402042)
							(end 0.4318 0.3302)
						)
						(arc
							(start 0.4318 -0.3302)
							(mid 0.402042 -0.402042)
							(end 0.3302 -0.4318)
						)
					)
					(width 0)
					(fill yes)
				)
			)
		)
	)
	(footprint ""
		(layer "F.Cu")
		(at 174.60849 -140.54709 -135)
		(property "Reference" "VIA62"
			(at 0 0 225)
			(layer "F.SilkS")
			(hide yes)
			(effects
				(font
					(size 1.27 1.27)
				)
			)
		)
		(property "Value" "85OHM-8L-1D6MM-L16L18-GP"
			(at 4.064105 0.609655 225)
			(unlocked yes)
			(layer "F.Fab")
			(hide yes)
			(effects
				(font
					(size 1.016 1.016)
					(thickness 0.1524)
				)
			)
		)
		(property "Device Type" "VIA-PCIE-4P-368076"
			(at 4.064105 -0.914474 225)
			(unlocked yes)
			(layer "F.Fab")
			(hide yes)
			(effects
				(font
					(size 1.016 1.016)
					(thickness 0.1524)
				)
			)
		)
		(duplicate_pad_numbers_are_jumpers no)
		(fp_poly
			(pts
				(xy -1.841491 -0.381057) (xy 1.841509 -0.381058) (xy 1.841508 0.380942) (xy -1.841491 0.380942)
			)
			(stroke
				(width 0)
				(type default)
			)
			(fill no)
			(layer "F.CrtYd")
		)
		(fp_poly
			(pts
				(xy -1.841491 -0.381057) (xy 1.841509 -0.381058) (xy 1.841508 0.380942) (xy -1.841491 0.380942)
			)
			(stroke
				(width 0)
				(type default)
			)
			(fill no)
			(layer "F.Fab")
		)
		(pad "1" thru_hole circle
			(at -1.460499 0 225)
			(size 0.508 0.508)
			(drill 0.254)
			(layers "*.Cu" "*.Mask")
			(remove_unused_layers no)
			(net "GND")
			(clearance 0.127)
			(thermal_gap 0.127)
		)
		(pad "2" thru_hole circle
			(at -0.4445 0 225)
			(size 0.508 0.508)
			(drill 0.254)
			(layers "*.Cu" "*.Mask")
			(remove_unused_layers no)
			(net "PCIE_COMP_TO_IOM_14_DP")
			(clearance 0.127)
			(thermal_gap 0.127)
		)
		(pad "3" thru_hole circle
			(at 0.4445 0 225)
			(size 0.508 0.508)
			(drill 0.254)
			(layers "*.Cu" "*.Mask")
			(remove_unused_layers no)
			(net "PCIE_COMP_TO_IOM_14_DN")
			(clearance 0.127)
			(thermal_gap 0.127)
		)
		(pad "4" thru_hole circle
			(at 1.460499 0 225)
			(size 0.508 0.508)
			(drill 0.254)
			(layers "*.Cu" "*.Mask")
			(remove_unused_layers no)
			(net "GND")
			(clearance 0.127)
			(thermal_gap 0.127)
		)
	)
	(footprint ""
		(layer "F.Cu")
		(at 18.650458 -175.96739 180)
		(property "Reference" "C229"
			(at 0 0 180)
			(layer "F.SilkS")
			(hide yes)
			(effects
				(font
					(size 1.27 1.27)
				)
			)
		)
		(property "Value" "SC1U16V3KX-5GP"
			(at 0 -2.8194 180)
			(unlocked yes)
			(layer "F.Fab")
			(hide yes)
			(effects
				(font
					(size 1.016 1.016)
					(thickness 0.1524)
				)
			)
		)
		(property "Device Type" "C603H36"
			(at 0 -4.3434 180)
			(unlocked yes)
			(layer "F.Fab")
			(hide yes)
			(effects
				(font
					(size 1.016 1.016)
					(thickness 0.1524)
				)
			)
		)
		(duplicate_pad_numbers_are_jumpers no)
		(fp_line
			(start 0.508 0)
			(end -0.508 0)
			(stroke
				(width 0.2032)
				(type default)
			)
			(layer "F.SilkS")
		)
		(fp_rect
			(start -0.5842 1.3335)
			(end 0.5842 -1.3335)
			(stroke
				(width 0)
				(type default)
			)
			(fill no)
			(layer "F.CrtYd")
		)
		(fp_rect
			(start -0.5842 1.3335)
			(end 0.5842 -1.3335)
			(stroke
				(width 0)
				(type default)
			)
			(fill no)
			(layer "F.Fab")
		)
		(pad "1" smd custom
			(at 0 -0.762 180)
			(size 0.2159 0.2159)
			(layers "F.Cu" "F.Mask" "F.Paste")
			(net "TPS74801_P1V2_STBY_BIAS")
			(options
				(clearance outline)
				(anchor circle)
			)
			(primitives
				(gr_poly
					(pts
						(arc
							(start -0.3302 -0.4318)
							(mid -0.402042 -0.402042)
							(end -0.4318 -0.3302)
						)
						(arc
							(start -0.4318 0.3302)
							(mid -0.402042 0.402042)
							(end -0.3302 0.4318)
						)
						(arc
							(start 0.3302 0.4318)
							(mid 0.402042 0.402042)
							(end 0.4318 0.3302)
						)
						(arc
							(start 0.4318 -0.3302)
							(mid 0.402042 -0.402042)
							(end 0.3302 -0.4318)
						)
					)
					(width 0)
					(fill yes)
				)
			)
		)
		(pad "2" smd custom
			(at 0 0.762 180)
			(size 0.2159 0.2159)
			(layers "F.Cu" "F.Mask" "F.Paste")
			(net "GND")
			(options
				(clearance outline)
				(anchor circle)
			)
			(primitives
				(gr_poly
					(pts
						(arc
							(start -0.3302 -0.4318)
							(mid -0.402042 -0.402042)
							(end -0.4318 -0.3302)
						)
						(arc
							(start -0.4318 0.3302)
							(mid -0.402042 0.402042)
							(end -0.3302 0.4318)
						)
						(arc
							(start 0.3302 0.4318)
							(mid 0.402042 0.402042)
							(end 0.4318 0.3302)
						)
						(arc
							(start 0.4318 -0.3302)
							(mid 0.402042 -0.402042)
							(end 0.3302 -0.4318)
						)
					)
					(width 0)
					(fill yes)
				)
			)
		)
	)
	(footprint ""
		(layer "F.Cu")
		(at 98.859594 -146.565874 90)
		(property "Reference" "C127"
			(at 0 0 90)
			(layer "F.SilkS")
			(hide yes)
			(effects
				(font
					(size 1.27 1.27)
				)
			)
		)
		(property "Value" "SCD1U16V2KX-3GP"
			(at 1.1811 -2.7051 90)
			(unlocked yes)
			(layer "F.Fab")
			(hide yes)
			(effects
				(font
					(size 1.016 1.016)
					(thickness 0.1524)
				)
			)
		)
		(property "Device Type" "C402H22"
			(at 1.1811 -4.2291 90)
			(unlocked yes)
			(layer "F.Fab")
			(hide yes)
			(effects
				(font
					(size 1.016 1.016)
					(thickness 0.1524)
				)
			)
		)
		(duplicate_pad_numbers_are_jumpers no)
		(fp_rect
			(start -0.4318 0.9525)
			(end 0.4318 -0.9525)
			(stroke
				(width 0)
				(type default)
			)
			(fill no)
			(layer "F.CrtYd")
		)
		(fp_rect
			(start -0.4318 0.9525)
			(end 0.4318 -0.9525)
			(stroke
				(width 0)
				(type default)
			)
			(fill no)
			(layer "F.Fab")
		)
		(pad "1" smd custom
			(at 0 -0.4445 90)
			(size 0.1524 0.1524)
			(layers "F.Cu" "F.Mask" "F.Paste")
			(net "P3V3_STBY")
			(options
				(clearance outline)
				(anchor circle)
			)
			(primitives
				(gr_poly
					(pts
						(arc
							(start 0.3048 -0.2032)
							(mid 0.275042 -0.275042)
							(end 0.2032 -0.3048)
						)
						(arc
							(start -0.2032 -0.3048)
							(mid -0.275042 -0.275042)
							(end -0.3048 -0.2032)
						)
						(arc
							(start -0.3048 0.2032)
							(mid -0.275042 0.275042)
							(end -0.2032 0.3048)
						)
						(arc
							(start 0.2032 0.3048)
							(mid 0.275042 0.275042)
							(end 0.3048 0.2032)
						)
					)
					(width 0)
					(fill yes)
				)
			)
		)
		(pad "2" smd custom
			(at 0 0.4445 90)
			(size 0.1524 0.1524)
			(layers "F.Cu" "F.Mask" "F.Paste")
			(net "GND")
			(options
				(clearance outline)
				(anchor circle)
			)
			(primitives
				(gr_poly
					(pts
						(arc
							(start 0.3048 -0.2032)
							(mid 0.275042 -0.275042)
							(end 0.2032 -0.3048)
						)
						(arc
							(start -0.2032 -0.3048)
							(mid -0.275042 -0.275042)
							(end -0.3048 -0.2032)
						)
						(arc
							(start -0.3048 0.2032)
							(mid -0.275042 0.275042)
							(end -0.2032 0.3048)
						)
						(arc
							(start 0.2032 0.3048)
							(mid 0.275042 0.275042)
							(end 0.3048 0.2032)
						)
					)
					(width 0)
					(fill yes)
				)
			)
		)
	)
	(footprint ""
		(layer "F.Cu")
		(at 65.532 -164.582856 180)
		(property "Reference" "R72"
			(at 0 0 180)
			(layer "F.SilkS")
			(hide yes)
			(effects
				(font
					(size 1.27 1.27)
				)
			)
		)
		(property "Value" "10KR2F-2-GP"
			(at 0.064008 -3.993896 180)
			(unlocked yes)
			(layer "F.Fab")
			(hide yes)
			(effects
				(font
					(size 1.016 1.016)
					(thickness 0.1524)
				)
			)
		)
		(property "Device Type" "R402H16"
			(at 0.064008 -5.517896 180)
			(unlocked yes)
			(layer "F.Fab")
			(hide yes)
			(effects
				(font
					(size 1.016 1.016)
					(thickness 0.1524)
				)
			)
		)
		(duplicate_pad_numbers_are_jumpers no)
		(fp_line
			(start 0.508 -0.9398)
			(end -0.508 -0.9398)
			(stroke
				(width 0.1524)
				(type default)
			)
			(layer "F.SilkS")
		)
		(fp_line
			(start -0.508 -0.9398)
			(end -0.508 0.9398)
			(stroke
				(width 0.1524)
				(type default)
			)
			(layer "F.SilkS")
		)
		(fp_rect
			(start -0.508 0.9398)
			(end 0.508 -0.9398)
			(stroke
				(width 0)
				(type default)
			)
			(fill no)
			(layer "F.CrtYd")
		)
		(fp_rect
			(start -0.508 0.9398)
			(end 0.508 -0.9398)
			(stroke
				(width 0)
				(type default)
			)
			(fill no)
			(layer "F.Fab")
		)
		(pad "1" smd custom
			(at 0 -0.4445 180)
			(size 0.1397 0.1397)
			(layers "F.Cu" "F.Mask" "F.Paste")
			(net "P3V3_STBY")
			(options
				(clearance outline)
				(anchor circle)
			)
			(primitives
				(gr_poly
					(pts
						(arc
							(start -0.1778 -0.2794)
							(mid -0.249642 -0.249642)
							(end -0.2794 -0.1778)
						)
						(arc
							(start -0.2794 0.1778)
							(mid -0.249642 0.249642)
							(end -0.1778 0.2794)
						)
						(arc
							(start 0.1778 0.2794)
							(mid 0.249642 0.249642)
							(end 0.2794 0.1778)
						)
						(arc
							(start 0.2794 -0.1778)
							(mid 0.249642 -0.249642)
							(end 0.1778 -0.2794)
						)
					)
					(width 0)
					(fill yes)
				)
			)
		)
		(pad "2" smd custom
			(at 0 0.4445 180)
			(size 0.1397 0.1397)
			(layers "F.Cu" "F.Mask" "F.Paste")
			(net "FM_TPM_PRSNT_RST")
			(options
				(clearance outline)
				(anchor circle)
			)
			(primitives
				(gr_poly
					(pts
						(arc
							(start -0.1778 -0.2794)
							(mid -0.249642 -0.249642)
							(end -0.2794 -0.1778)
						)
						(arc
							(start -0.2794 0.1778)
							(mid -0.249642 0.249642)
							(end -0.1778 0.2794)
						)
						(arc
							(start 0.1778 0.2794)
							(mid 0.249642 0.249642)
							(end 0.2794 0.1778)
						)
						(arc
							(start 0.2794 -0.1778)
							(mid 0.249642 -0.249642)
							(end 0.1778 -0.2794)
						)
					)
					(width 0)
					(fill yes)
				)
			)
		)
	)
	(footprint ""
		(layer "F.Cu")
		(at 10.796524 -136.715246 90)
		(property "Reference" "R208"
			(at 0 0 90)
			(layer "F.SilkS")
			(hide yes)
			(effects
				(font
					(size 1.27 1.27)
				)
			)
		)
		(property "Value" "120R2F-GP"
			(at 0.064008 -3.993896 90)
			(unlocked yes)
			(layer "F.Fab")
			(hide yes)
			(effects
				(font
					(size 1.016 1.016)
					(thickness 0.1524)
				)
			)
		)
		(property "Device Type" "R402H16"
			(at 0.064008 -5.517896 90)
			(unlocked yes)
			(layer "F.Fab")
			(hide yes)
			(effects
				(font
					(size 1.016 1.016)
					(thickness 0.1524)
				)
			)
		)
		(duplicate_pad_numbers_are_jumpers no)
		(fp_line
			(start 0.508 -0.9398)
			(end -0.508 -0.9398)
			(stroke
				(width 0.1524)
				(type default)
			)
			(layer "F.SilkS")
		)
		(fp_line
			(start -0.508 -0.9398)
			(end -0.508 0.9398)
			(stroke
				(width 0.1524)
				(type default)
			)
			(layer "F.SilkS")
		)
		(fp_rect
			(start -0.508 0.9398)
			(end 0.508 -0.9398)
			(stroke
				(width 0)
				(type default)
			)
			(fill no)
			(layer "F.CrtYd")
		)
		(fp_rect
			(start -0.508 0.9398)
			(end 0.508 -0.9398)
			(stroke
				(width 0)
				(type default)
			)
			(fill no)
			(layer "F.Fab")
		)
		(pad "1" smd custom
			(at 0 -0.4445 90)
			(size 0.1397 0.1397)
			(layers "F.Cu" "F.Mask" "F.Paste")
			(net "DDR4_RST_N")
			(options
				(clearance outline)
				(anchor circle)
			)
			(primitives
				(gr_poly
					(pts
						(arc
							(start -0.1778 -0.2794)
							(mid -0.249642 -0.249642)
							(end -0.2794 -0.1778)
						)
						(arc
							(start -0.2794 0.1778)
							(mid -0.249642 0.249642)
							(end -0.1778 0.2794)
						)
						(arc
							(start 0.1778 0.2794)
							(mid 0.249642 0.249642)
							(end 0.2794 0.1778)
						)
						(arc
							(start 0.2794 -0.1778)
							(mid 0.249642 -0.249642)
							(end 0.1778 -0.2794)
						)
					)
					(width 0)
					(fill yes)
				)
			)
		)
		(pad "2" smd custom
			(at 0 0.4445 90)
			(size 0.1397 0.1397)
			(layers "F.Cu" "F.Mask" "F.Paste")
			(net "P1V2_STBY")
			(options
				(clearance outline)
				(anchor circle)
			)
			(primitives
				(gr_poly
					(pts
						(arc
							(start -0.1778 -0.2794)
							(mid -0.249642 -0.249642)
							(end -0.2794 -0.1778)
						)
						(arc
							(start -0.2794 0.1778)
							(mid -0.249642 0.249642)
							(end -0.1778 0.2794)
						)
						(arc
							(start 0.1778 0.2794)
							(mid 0.249642 0.249642)
							(end 0.2794 0.1778)
						)
						(arc
							(start 0.2794 -0.1778)
							(mid 0.249642 -0.249642)
							(end 0.1778 -0.2794)
						)
					)
					(width 0)
					(fill yes)
				)
			)
		)
	)
	(footprint ""
		(layer "F.Cu")
		(at 212.829902 -91.518994 -90)
		(property "Reference" "R828"
			(at 0 0 270)
			(layer "F.SilkS")
			(hide yes)
			(effects
				(font
					(size 1.27 1.27)
				)
			)
		)
		(property "Value" "10KR2F-2-GP"
			(at 0.064008 -3.993896 270)
			(unlocked yes)
			(layer "F.Fab")
			(hide yes)
			(effects
				(font
					(size 1.016 1.016)
					(thickness 0.1524)
				)
			)
		)
		(property "Device Type" "R402H16"
			(at 0.064008 -5.517896 270)
			(unlocked yes)
			(layer "F.Fab")
			(hide yes)
			(effects
				(font
					(size 1.016 1.016)
					(thickness 0.1524)
				)
			)
		)
		(duplicate_pad_numbers_are_jumpers no)
		(fp_line
			(start -0.508 -0.9398)
			(end -0.508 0.9398)
			(stroke
				(width 0.1524)
				(type default)
			)
			(layer "F.SilkS")
		)
		(fp_line
			(start 0.508 -0.9398)
			(end -0.508 -0.9398)
			(stroke
				(width 0.1524)
				(type default)
			)
			(layer "F.SilkS")
		)
		(fp_rect
			(start -0.508 0.9398)
			(end 0.508 -0.9398)
			(stroke
				(width 0)
				(type default)
			)
			(fill no)
			(layer "F.CrtYd")
		)
		(fp_rect
			(start -0.508 0.9398)
			(end 0.508 -0.9398)
			(stroke
				(width 0)
				(type default)
			)
			(fill no)
			(layer "F.Fab")
		)
		(pad "1" smd custom
			(at 0 -0.4445 270)
			(size 0.1397 0.1397)
			(layers "F.Cu" "F.Mask" "F.Paste")
			(net "P3V3_M2_EN")
			(options
				(clearance outline)
				(anchor circle)
			)
			(primitives
				(gr_poly
					(pts
						(arc
							(start -0.1778 -0.2794)
							(mid -0.249642 -0.249642)
							(end -0.2794 -0.1778)
						)
						(arc
							(start -0.2794 0.1778)
							(mid -0.249642 0.249642)
							(end -0.1778 0.2794)
						)
						(arc
							(start 0.1778 0.2794)
							(mid 0.249642 0.249642)
							(end 0.2794 0.1778)
						)
						(arc
							(start 0.2794 -0.1778)
							(mid 0.249642 -0.249642)
							(end 0.1778 -0.2794)
						)
					)
					(width 0)
					(fill yes)
				)
			)
		)
		(pad "2" smd custom
			(at 0 0.4445 270)
			(size 0.1397 0.1397)
			(layers "F.Cu" "F.Mask" "F.Paste")
			(net "P3V3_STBY")
			(options
				(clearance outline)
				(anchor circle)
			)
			(primitives
				(gr_poly
					(pts
						(arc
							(start -0.1778 -0.2794)
							(mid -0.249642 -0.249642)
							(end -0.2794 -0.1778)
						)
						(arc
							(start -0.2794 0.1778)
							(mid -0.249642 0.249642)
							(end -0.1778 0.2794)
						)
						(arc
							(start 0.1778 0.2794)
							(mid 0.249642 0.249642)
							(end 0.2794 0.1778)
						)
						(arc
							(start 0.2794 -0.1778)
							(mid 0.249642 -0.249642)
							(end 0.1778 -0.2794)
						)
					)
					(width 0)
					(fill yes)
				)
			)
		)
	)
	(footprint ""
		(layer "F.Cu")
		(at 45.4152 -130.4036)
		(property "Reference" "TP204"
			(at 0 0 0)
			(layer "F.SilkS")
			(hide yes)
			(effects
				(font
					(size 1.27 1.27)
				)
			)
		)
		(property "Value" "TPAD28-2-GP"
			(at -0.0127 -1.6637 0)
			(unlocked yes)
			(layer "F.Fab")
			(hide yes)
			(effects
				(font
					(size 1.016 1.016)
					(thickness 0.1524)
				)
			)
		)
		(property "Device Type" "TPAD28"
			(at -0.0127 -3.1877 0)
			(unlocked yes)
			(layer "F.Fab")
			(hide yes)
			(effects
				(font
					(size 1.016 1.016)
					(thickness 0.1524)
				)
			)
		)
		(duplicate_pad_numbers_are_jumpers no)
		(fp_poly
			(pts
				(arc
					(start 0.3556 0)
					(mid -0.3556 0)
					(end 0.3556 0)
				)
			)
			(stroke
				(width 0)
				(type default)
			)
			(fill no)
			(layer "F.CrtYd")
		)
		(fp_poly
			(pts
				(arc
					(start 0.6096 0)
					(mid -0.6096 0)
					(end 0.6096 0)
				)
			)
			(stroke
				(width 0)
				(type default)
			)
			(fill no)
			(layer "F.Fab")
		)
		(pad "1" smd circle
			(at 0 0)
			(size 0.7112 0.7112)
			(layers "F.Cu" "F.Mask" "F.Paste")
			(net "BMC_SMB2_DAT_TP")
		)
	)
	(footprint ""
		(layer "F.Cu")
		(at 42.683938 -179.52085)
		(property "Reference" "R488"
			(at 0 0 0)
			(layer "F.SilkS")
			(hide yes)
			(effects
				(font
					(size 1.27 1.27)
				)
			)
		)
		(property "Value" "2K7R2F-GP"
			(at 0.064008 -3.993896 0)
			(unlocked yes)
			(layer "F.Fab")
			(hide yes)
			(effects
				(font
					(size 1.016 1.016)
					(thickness 0.1524)
				)
			)
		)
		(property "Device Type" "R402H16"
			(at 0.064008 -5.517896 0)
			(unlocked yes)
			(layer "F.Fab")
			(hide yes)
			(effects
				(font
					(size 1.016 1.016)
					(thickness 0.1524)
				)
			)
		)
		(duplicate_pad_numbers_are_jumpers no)
		(fp_line
			(start -0.508 -0.9398)
			(end -0.508 0.9398)
			(stroke
				(width 0.1524)
				(type default)
			)
			(layer "F.SilkS")
		)
		(fp_line
			(start 0.508 -0.9398)
			(end -0.508 -0.9398)
			(stroke
				(width 0.1524)
				(type default)
			)
			(layer "F.SilkS")
		)
		(fp_rect
			(start -0.508 0.9398)
			(end 0.508 -0.9398)
			(stroke
				(width 0)
				(type default)
			)
			(fill no)
			(layer "F.CrtYd")
		)
		(fp_rect
			(start -0.508 0.9398)
			(end 0.508 -0.9398)
			(stroke
				(width 0)
				(type default)
			)
			(fill no)
			(layer "F.Fab")
		)
		(pad "1" smd custom
			(at 0 -0.4445)
			(size 0.1397 0.1397)
			(layers "F.Cu" "F.Mask" "F.Paste")
			(net "P3V3_STBY_LL")
			(options
				(clearance outline)
				(anchor circle)
			)
			(primitives
				(gr_poly
					(pts
						(arc
							(start -0.1778 -0.2794)
							(mid -0.249642 -0.249642)
							(end -0.2794 -0.1778)
						)
						(arc
							(start -0.2794 0.1778)
							(mid -0.249642 0.249642)
							(end -0.1778 0.2794)
						)
						(arc
							(start 0.1778 0.2794)
							(mid 0.249642 0.249642)
							(end 0.2794 0.1778)
						)
						(arc
							(start 0.2794 -0.1778)
							(mid 0.249642 -0.249642)
							(end 0.1778 -0.2794)
						)
					)
					(width 0)
					(fill yes)
				)
			)
		)
		(pad "2" smd custom
			(at 0 0.4445)
			(size 0.1397 0.1397)
			(layers "F.Cu" "F.Mask" "F.Paste")
			(net "P3V3_STBY_LL_R")
			(options
				(clearance outline)
				(anchor circle)
			)
			(primitives
				(gr_poly
					(pts
						(arc
							(start -0.1778 -0.2794)
							(mid -0.249642 -0.249642)
							(end -0.2794 -0.1778)
						)
						(arc
							(start -0.2794 0.1778)
							(mid -0.249642 0.249642)
							(end -0.1778 0.2794)
						)
						(arc
							(start 0.1778 0.2794)
							(mid 0.249642 0.249642)
							(end 0.2794 0.1778)
						)
						(arc
							(start 0.2794 -0.1778)
							(mid 0.249642 -0.249642)
							(end 0.1778 -0.2794)
						)
					)
					(width 0)
					(fill yes)
				)
			)
		)
	)
	(footprint ""
		(layer "F.Cu")
		(at 23.058882 -171.227496 90)
		(property "Reference" "C232"
			(at 0 0 90)
			(layer "F.SilkS")
			(hide yes)
			(effects
				(font
					(size 1.27 1.27)
				)
			)
		)
		(property "Value" "SC10U6D3V5KX-4GP"
			(at -0.0762 -6.1214 90)
			(unlocked yes)
			(layer "F.Fab")
			(hide yes)
			(effects
				(font
					(size 1.016 1.016)
					(thickness 0.1524)
				)
			)
		)
		(property "Device Type" "C805H58"
			(at -0.0762 -8.1534 90)
			(unlocked yes)
			(layer "F.Fab")
			(hide yes)
			(effects
				(font
					(size 1.016 1.016)
					(thickness 0.1524)
				)
			)
		)
		(duplicate_pad_numbers_are_jumpers no)
		(fp_line
			(start 0.635 0)
			(end -0.635 0)
			(stroke
				(width 0.508)
				(type default)
			)
			(layer "F.SilkS")
		)
		(fp_rect
			(start -0.9652 1.778)
			(end 0.9652 -1.778)
			(stroke
				(width 0)
				(type default)
			)
			(fill no)
			(layer "F.CrtYd")
		)
		(fp_poly
			(pts
				(xy -0.9652 -1.778) (xy 0.9652 -1.778) (xy 0.9652 1.778) (xy -0.9652 1.778)
			)
			(stroke
				(width 0)
				(type default)
			)
			(fill no)
			(layer "F.Fab")
		)
		(pad "1" smd rect
			(at 0 -0.9652 90)
			(size 1.397 1.143)
			(layers "F.Cu" "F.Mask" "F.Paste")
			(net "P1V8_STBY")
		)
		(pad "2" smd rect
			(at 0 0.9652 90)
			(size 1.397 1.143)
			(layers "F.Cu" "F.Mask" "F.Paste")
			(net "GND")
		)
	)
	(footprint ""
		(layer "F.Cu")
		(at 170.754294 -138.635232 -135)
		(property "Reference" "VIA64"
			(at 0 0 225)
			(layer "F.SilkS")
			(hide yes)
			(effects
				(font
					(size 1.27 1.27)
				)
			)
		)
		(property "Value" "85OHM-8L-1D6MM-L16L18-GP"
			(at 4.064105 0.609655 225)
			(unlocked yes)
			(layer "F.Fab")
			(hide yes)
			(effects
				(font
					(size 1.016 1.016)
					(thickness 0.1524)
				)
			)
		)
		(property "Device Type" "VIA-PCIE-4P-368076"
			(at 4.064105 -0.914474 225)
			(unlocked yes)
			(layer "F.Fab")
			(hide yes)
			(effects
				(font
					(size 1.016 1.016)
					(thickness 0.1524)
				)
			)
		)
		(duplicate_pad_numbers_are_jumpers no)
		(fp_poly
			(pts
				(xy -1.841491 -0.381057) (xy 1.841509 -0.381058) (xy 1.841508 0.380942) (xy -1.841491 0.380942)
			)
			(stroke
				(width 0)
				(type default)
			)
			(fill no)
			(layer "F.CrtYd")
		)
		(fp_poly
			(pts
				(xy -1.841491 -0.381057) (xy 1.841509 -0.381058) (xy 1.841508 0.380942) (xy -1.841491 0.380942)
			)
			(stroke
				(width 0)
				(type default)
			)
			(fill no)
			(layer "F.Fab")
		)
		(pad "1" thru_hole circle
			(at -1.460499 0 225)
			(size 0.508 0.508)
			(drill 0.254)
			(layers "*.Cu" "*.Mask")
			(remove_unused_layers no)
			(net "GND")
			(clearance 0.127)
			(thermal_gap 0.127)
		)
		(pad "2" thru_hole circle
			(at -0.4445 0 225)
			(size 0.508 0.508)
			(drill 0.254)
			(layers "*.Cu" "*.Mask")
			(remove_unused_layers no)
			(net "PCIE_COMP_TO_IOM_15_DP")
			(clearance 0.127)
			(thermal_gap 0.127)
		)
		(pad "3" thru_hole circle
			(at 0.4445 0 225)
			(size 0.508 0.508)
			(drill 0.254)
			(layers "*.Cu" "*.Mask")
			(remove_unused_layers no)
			(net "PCIE_COMP_TO_IOM_15_DN")
			(clearance 0.127)
			(thermal_gap 0.127)
		)
		(pad "4" thru_hole circle
			(at 1.460499 0 225)
			(size 0.508 0.508)
			(drill 0.254)
			(layers "*.Cu" "*.Mask")
			(remove_unused_layers no)
			(net "GND")
			(clearance 0.127)
			(thermal_gap 0.127)
		)
	)
	(footprint ""
		(layer "F.Cu")
		(at 219.992956 -97.383346 180)
		(property "Reference" "U81"
			(at 0 0 180)
			(layer "F.SilkS")
			(hide yes)
			(effects
				(font
					(size 1.27 1.27)
				)
			)
		)
		(property "Value" "TPS53319DQPR-GP"
			(at 4.7498 -5.6896 180)
			(unlocked yes)
			(layer "F.Fab")
			(hide yes)
			(effects
				(font
					(size 1.016 1.016)
					(thickness 0.1524)
				)
			)
		)
		(property "Device Type" "QFN22G6050-G6133H60"
			(at 4.7498 -7.2136 180)
			(unlocked yes)
			(layer "F.Fab")
			(hide yes)
			(effects
				(font
					(size 1.016 1.016)
					(thickness 0.1524)
				)
			)
		)
		(duplicate_pad_numbers_are_jumpers no)
		(fp_line
			(start 3.556 3.5179)
			(end 3.556 2.2479)
			(stroke
				(width 0.1524)
				(type default)
			)
			(layer "F.SilkS")
		)
		(fp_line
			(start 2.286 3.5179)
			(end 3.556 3.5179)
			(stroke
				(width 0.1524)
				(type default)
			)
			(layer "F.SilkS")
		)
		(fp_line
			(start 1.500124 3.262122)
			(end 1.500124 4.024122)
			(stroke
				(width 0.1524)
				(type default)
			)
			(layer "F.SilkS")
		)
		(fp_line
			(start 0.500126 -3.262122)
			(end 0.500126 -3.770122)
			(stroke
				(width 0.1524)
				(type default)
			)
			(layer "F.SilkS")
		)
		(fp_line
			(start -0.999998 3.262122)
			(end -0.999998 3.770122)
			(stroke
				(width 0.1524)
				(type default)
			)
			(layer "F.SilkS")
		)
		(fp_line
			(start -1.999996 -3.262122)
			(end -1.999996 -4.024122)
			(stroke
				(width 0.1524)
				(type default)
			)
			(layer "F.SilkS")
		)
		(fp_line
			(start -2.286 -3.5179)
			(end -3.556 -3.5179)
			(stroke
				(width 0.1524)
				(type default)
			)
			(layer "F.SilkS")
		)
		(fp_line
			(start -3.556 3.5179)
			(end -2.286 3.5179)
			(stroke
				(width 0.1524)
				(type default)
			)
			(layer "F.SilkS")
		)
		(fp_line
			(start -3.556 2.2479)
			(end -3.556 3.5179)
			(stroke
				(width 0.1524)
				(type default)
			)
			(layer "F.SilkS")
		)
		(fp_line
			(start -3.556 -3.5179)
			(end -3.556 -2.2479)
			(stroke
				(width 0.1524)
				(type default)
			)
			(layer "F.SilkS")
		)
		(fp_poly
			(pts
				(xy 3.556 -3.5179) (xy 2.5273 -3.5179) (xy 3.556 -2.4892)
			)
			(stroke
				(width 0)
				(type default)
			)
			(fill yes)
			(layer "F.SilkS")
		)
		(fp_rect
			(start -2.9972 2.5019)
			(end 2.9972 -2.5019)
			(stroke
				(width 0)
				(type default)
			)
			(fill no)
			(layer "F.CrtYd")
		)
		(fp_poly
			(pts
				(xy 3.556 -2.5019) (xy -2.9972 -2.5019) (xy -2.9972 2.5019) (xy 2.9972 2.5019) (xy 2.9972 -2.4892)
				(xy 3.556 -2.4892) (xy 3.556 3.5179) (xy -3.556 3.5179) (xy -3.556 -3.5179) (xy 3.556 -3.5179)
			)
			(stroke
				(width 0)
				(type default)
			)
			(fill no)
			(layer "F.CrtYd")
		)
		(fp_rect
			(start -3.556 3.5179)
			(end 3.556 -3.5179)
			(stroke
				(width 0)
				(type default)
			)
			(fill no)
			(layer "F.Fab")
		)
		(pad "1" smd rect
			(at 2.500122 -2.449322 180)
			(size 0.3048 1.1176)
			(layers "F.Cu" "F.Mask" "F.Paste")
			(net "P3V3_M2_VFB")
		)
		(pad "2" smd rect
			(at 1.999996 -2.449322 180)
			(size 0.3048 1.1176)
			(layers "F.Cu" "F.Mask" "F.Paste")
			(net "P3V3_M2_EN")
		)
		(pad "3" smd rect
			(at 1.500124 -2.449322 180)
			(size 0.3048 1.1176)
			(layers "F.Cu" "F.Mask" "F.Paste")
			(net "IOM_FULL_PGOOD")
		)
		(pad "4" smd rect
			(at 0.999998 -2.449322 180)
			(size 0.3048 1.1176)
			(layers "F.Cu" "F.Mask" "F.Paste")
			(net "P3V3_M2_VBST")
		)
		(pad "5" smd rect
			(at 0.500126 -2.449322 180)
			(size 0.3048 1.1176)
			(layers "F.Cu" "F.Mask" "F.Paste")
			(net "AGND_P3V3_M2")
		)
		(pad "6" smd rect
			(at 0 -2.449322 180)
			(size 0.3048 1.1176)
			(layers "F.Cu" "F.Mask" "F.Paste")
			(net "P3V3_M2_LL")
		)
		(pad "7" smd rect
			(at -0.500126 -2.449322 180)
			(size 0.3048 1.1176)
			(layers "F.Cu" "F.Mask" "F.Paste")
			(net "P3V3_M2_LL")
		)
		(pad "8" smd rect
			(at -0.999998 -2.449322 180)
			(size 0.3048 1.1176)
			(layers "F.Cu" "F.Mask" "F.Paste")
			(net "P3V3_M2_LL")
		)
		(pad "9" smd rect
			(at -1.500124 -2.449322 180)
			(size 0.3048 1.1176)
			(layers "F.Cu" "F.Mask" "F.Paste")
			(net "P3V3_M2_LL")
		)
		(pad "10" smd rect
			(at -1.999996 -2.449322 180)
			(size 0.3048 1.1176)
			(layers "F.Cu" "F.Mask" "F.Paste")
			(net "P3V3_M2_LL")
		)
		(pad "11" smd rect
			(at -2.500122 -2.449322 180)
			(size 0.3048 1.1176)
			(layers "F.Cu" "F.Mask" "F.Paste")
			(net "P3V3_M2_LL")
		)
		(pad "12" smd rect
			(at -2.500122 2.449322 180)
			(size 0.3048 1.1176)
			(layers "F.Cu" "F.Mask" "F.Paste")
			(net "P12V_STBY_VIN_U81")
		)
		(pad "13" smd rect
			(at -1.999996 2.449322 180)
			(size 0.3048 1.1176)
			(layers "F.Cu" "F.Mask" "F.Paste")
			(net "P12V_STBY_VIN_U81")
		)
		(pad "14" smd rect
			(at -1.500124 2.449322 180)
			(size 0.3048 1.1176)
			(layers "F.Cu" "F.Mask" "F.Paste")
			(net "P12V_STBY_VIN_U81")
		)
		(pad "15" smd rect
			(at -0.999998 2.449322 180)
			(size 0.3048 1.1176)
			(layers "F.Cu" "F.Mask" "F.Paste")
			(net "P12V_STBY_VIN_U81")
		)
		(pad "16" smd rect
			(at -0.500126 2.449322 180)
			(size 0.3048 1.1176)
			(layers "F.Cu" "F.Mask" "F.Paste")
			(net "P12V_STBY_VIN_U81")
		)
		(pad "17" smd rect
			(at 0 2.449322 180)
			(size 0.3048 1.1176)
			(layers "F.Cu" "F.Mask" "F.Paste")
			(net "P12V_STBY_VIN_U81")
		)
		(pad "18" smd rect
			(at 0.500126 2.449322 180)
			(size 0.3048 1.1176)
			(layers "F.Cu" "F.Mask" "F.Paste")
			(net "P3V3_M2_VREG")
		)
		(pad "19" smd rect
			(at 0.999998 2.449322 180)
			(size 0.3048 1.1176)
			(layers "F.Cu" "F.Mask" "F.Paste")
			(net "P12V_STBY_VDD_U81")
		)
		(pad "20" smd rect
			(at 1.500124 2.449322 180)
			(size 0.3048 1.1176)
			(layers "F.Cu" "F.Mask" "F.Paste")
			(net "P3V3_M2_MODE")
		)
		(pad "21" smd rect
			(at 1.999996 2.449322 180)
			(size 0.3048 1.1176)
			(layers "F.Cu" "F.Mask" "F.Paste")
			(net "P3V3_M2_TRIP")
		)
		(pad "22" smd rect
			(at 2.500122 2.449322 180)
			(size 0.3048 1.1176)
			(layers "F.Cu" "F.Mask" "F.Paste")
			(net "P3V3_M2_RF")
		)
		(pad "23" smd custom
			(at 0 0 180)
			(size 0.83185 0.83185)
			(layers "F.Cu" "F.Mask" "F.Paste")
			(net "GND")
			(options
				(clearance outline)
				(anchor circle)
			)
			(primitives
				(gr_poly
					(pts
						(xy -2.7813 1.6637) (xy -2.7813 1.2954) (xy -3.048 1.2954) (xy -3.048 0.9525) (xy -2.7813 0.9525)
						(xy -2.7813 -0.9525) (xy -3.048 -0.9525) (xy -3.048 -1.2954) (xy -2.7813 -1.2954) (xy -2.7813 -1.6637)
						(xy 2.7813 -1.6637) (xy 2.7813 -1.2954) (xy 3.048 -1.2954) (xy 3.048 -0.9525) (xy 2.7813 -0.9525)
						(xy 2.7813 0.9525) (xy 3.048 0.9525) (xy 3.048 1.2954) (xy 2.7813 1.2954) (xy 2.7813 1.6637)
					)
					(width 0)
					(fill yes)
				)
			)
		)
	)
	(footprint ""
		(layer "F.Cu")
		(at 55.7784 -181.3306)
		(property "Reference" "C172"
			(at 0 0 0)
			(layer "F.SilkS")
			(hide yes)
			(effects
				(font
					(size 1.27 1.27)
				)
			)
		)
		(property "Value" "SC10U6D3V5KX-4GP"
			(at -0.0762 -6.1214 0)
			(unlocked yes)
			(layer "F.Fab")
			(hide yes)
			(effects
				(font
					(size 1.016 1.016)
					(thickness 0.1524)
				)
			)
		)
		(property "Device Type" "C805H58"
			(at -0.0762 -8.1534 0)
			(unlocked yes)
			(layer "F.Fab")
			(hide yes)
			(effects
				(font
					(size 1.016 1.016)
					(thickness 0.1524)
				)
			)
		)
		(duplicate_pad_numbers_are_jumpers no)
		(fp_line
			(start 0.635 0)
			(end -0.635 0)
			(stroke
				(width 0.508)
				(type default)
			)
			(layer "F.SilkS")
		)
		(fp_rect
			(start -0.9652 1.778)
			(end 0.9652 -1.778)
			(stroke
				(width 0)
				(type default)
			)
			(fill no)
			(layer "F.CrtYd")
		)
		(fp_poly
			(pts
				(xy -0.9652 -1.778) (xy 0.9652 -1.778) (xy 0.9652 1.778) (xy -0.9652 1.778)
			)
			(stroke
				(width 0)
				(type default)
			)
			(fill no)
			(layer "F.Fab")
		)
		(pad "1" smd rect
			(at 0 -0.9652)
			(size 1.397 1.143)
			(layers "F.Cu" "F.Mask" "F.Paste")
			(net "P3V3_STBY_OUT")
		)
		(pad "2" smd rect
			(at 0 0.9652)
			(size 1.397 1.143)
			(layers "F.Cu" "F.Mask" "F.Paste")
			(net "GND")
		)
	)
	(footprint ""
		(layer "F.Cu")
		(at 209.186272 -94.238826 -90)
		(property "Reference" "R829"
			(at 0 0 270)
			(layer "F.SilkS")
			(hide yes)
			(effects
				(font
					(size 1.27 1.27)
				)
			)
		)
		(property "Value" "10R3F-GP"
			(at -0.0254 -2.5146 270)
			(unlocked yes)
			(layer "F.Fab")
			(hide yes)
			(effects
				(font
					(size 1.016 1.016)
					(thickness 0.1524)
				)
			)
		)
		(property "Device Type" "R603H22"
			(at -0.0254 -4.0386 270)
			(unlocked yes)
			(layer "F.Fab")
			(hide yes)
			(effects
				(font
					(size 1.016 1.016)
					(thickness 0.1524)
				)
			)
		)
		(duplicate_pad_numbers_are_jumpers no)
		(fp_line
			(start -0.482854 0)
			(end -0.2032 0)
			(stroke
				(width 0.2032)
				(type default)
			)
			(layer "F.SilkS")
		)
		(fp_line
			(start 0.2032 0)
			(end 0.482854 0)
			(stroke
				(width 0.2032)
				(type default)
			)
			(layer "F.SilkS")
		)
		(fp_rect
			(start -0.5842 1.3335)
			(end 0.5842 -1.3335)
			(stroke
				(width 0)
				(type default)
			)
			(fill no)
			(layer "F.CrtYd")
		)
		(fp_rect
			(start -0.5842 1.3335)
			(end 0.5842 -1.3335)
			(stroke
				(width 0)
				(type default)
			)
			(fill no)
			(layer "F.Fab")
		)
		(pad "1" smd custom
			(at 0 -0.762 270)
			(size 0.2159 0.2159)
			(layers "F.Cu" "F.Mask" "F.Paste")
			(net "P3V3_M2_VFB_R")
			(options
				(clearance outline)
				(anchor circle)
			)
			(primitives
				(gr_poly
					(pts
						(arc
							(start -0.3302 -0.4318)
							(mid -0.402042 -0.402042)
							(end -0.4318 -0.3302)
						)
						(arc
							(start -0.4318 0.3302)
							(mid -0.402042 0.402042)
							(end -0.3302 0.4318)
						)
						(arc
							(start 0.3302 0.4318)
							(mid 0.402042 0.402042)
							(end 0.4318 0.3302)
						)
						(arc
							(start 0.4318 -0.3302)
							(mid 0.402042 -0.402042)
							(end 0.3302 -0.4318)
						)
					)
					(width 0)
					(fill yes)
				)
			)
		)
		(pad "2" smd custom
			(at 0 0.762 270)
			(size 0.2159 0.2159)
			(layers "F.Cu" "F.Mask" "F.Paste")
			(net "P3V3_M2")
			(options
				(clearance outline)
				(anchor circle)
			)
			(primitives
				(gr_poly
					(pts
						(arc
							(start -0.3302 -0.4318)
							(mid -0.402042 -0.402042)
							(end -0.4318 -0.3302)
						)
						(arc
							(start -0.4318 0.3302)
							(mid -0.402042 0.402042)
							(end -0.3302 0.4318)
						)
						(arc
							(start 0.3302 0.4318)
							(mid 0.402042 0.402042)
							(end 0.4318 0.3302)
						)
						(arc
							(start 0.4318 -0.3302)
							(mid 0.402042 -0.402042)
							(end 0.3302 -0.4318)
						)
					)
					(width 0)
					(fill yes)
				)
			)
		)
	)
	(footprint ""
		(layer "F.Cu")
		(at 16.023336 -163.5506 -90)
		(property "Reference" "C222"
			(at 0 0 270)
			(layer "F.SilkS")
			(hide yes)
			(effects
				(font
					(size 1.27 1.27)
				)
			)
		)
		(property "Value" "SC1KP50V2KX-1GP"
			(at 1.1811 -2.7051 270)
			(unlocked yes)
			(layer "F.Fab")
			(hide yes)
			(effects
				(font
					(size 1.016 1.016)
					(thickness 0.1524)
				)
			)
		)
		(property "Device Type" "C402H22"
			(at 1.1811 -4.2291 270)
			(unlocked yes)
			(layer "F.Fab")
			(hide yes)
			(effects
				(font
					(size 1.016 1.016)
					(thickness 0.1524)
				)
			)
		)
		(duplicate_pad_numbers_are_jumpers no)
		(fp_rect
			(start -0.4318 0.9525)
			(end 0.4318 -0.9525)
			(stroke
				(width 0)
				(type default)
			)
			(fill no)
			(layer "F.CrtYd")
		)
		(fp_rect
			(start -0.4318 0.9525)
			(end 0.4318 -0.9525)
			(stroke
				(width 0)
				(type default)
			)
			(fill no)
			(layer "F.Fab")
		)
		(pad "1" smd custom
			(at 0 -0.4445 270)
			(size 0.1524 0.1524)
			(layers "F.Cu" "F.Mask" "F.Paste")
			(net "TPS74801_P1V2_STBY_OUT")
			(options
				(clearance outline)
				(anchor circle)
			)
			(primitives
				(gr_poly
					(pts
						(arc
							(start 0.3048 -0.2032)
							(mid 0.275042 -0.275042)
							(end 0.2032 -0.3048)
						)
						(arc
							(start -0.2032 -0.3048)
							(mid -0.275042 -0.275042)
							(end -0.3048 -0.2032)
						)
						(arc
							(start -0.3048 0.2032)
							(mid -0.275042 0.275042)
							(end -0.2032 0.3048)
						)
						(arc
							(start 0.2032 0.3048)
							(mid 0.275042 0.275042)
							(end 0.3048 0.2032)
						)
					)
					(width 0)
					(fill yes)
				)
			)
		)
		(pad "2" smd custom
			(at 0 0.4445 270)
			(size 0.1524 0.1524)
			(layers "F.Cu" "F.Mask" "F.Paste")
			(net "TPS74801_P1V2_STBY_FB")
			(options
				(clearance outline)
				(anchor circle)
			)
			(primitives
				(gr_poly
					(pts
						(arc
							(start 0.3048 -0.2032)
							(mid 0.275042 -0.275042)
							(end 0.2032 -0.3048)
						)
						(arc
							(start -0.2032 -0.3048)
							(mid -0.275042 -0.275042)
							(end -0.3048 -0.2032)
						)
						(arc
							(start -0.3048 0.2032)
							(mid -0.275042 0.275042)
							(end -0.2032 0.3048)
						)
						(arc
							(start 0.2032 0.3048)
							(mid 0.275042 0.275042)
							(end 0.3048 0.2032)
						)
					)
					(width 0)
					(fill yes)
				)
			)
		)
	)
	(footprint ""
		(layer "F.Cu")
		(at 79.487776 -147.894802 90)
		(property "Reference" "R717"
			(at 0 0 90)
			(layer "F.SilkS")
			(hide yes)
			(effects
				(font
					(size 1.27 1.27)
				)
			)
		)
		(property "Value" "0R2J-2-GP"
			(at 0.064008 -3.993896 90)
			(unlocked yes)
			(layer "F.Fab")
			(hide yes)
			(effects
				(font
					(size 1.016 1.016)
					(thickness 0.1524)
				)
			)
		)
		(property "Device Type" "R402H16"
			(at 0.064008 -5.517896 90)
			(unlocked yes)
			(layer "F.Fab")
			(hide yes)
			(effects
				(font
					(size 1.016 1.016)
					(thickness 0.1524)
				)
			)
		)
		(duplicate_pad_numbers_are_jumpers no)
		(fp_line
			(start 0.508 -0.9398)
			(end -0.508 -0.9398)
			(stroke
				(width 0.1524)
				(type default)
			)
			(layer "F.SilkS")
		)
		(fp_line
			(start -0.508 -0.9398)
			(end -0.508 0.9398)
			(stroke
				(width 0.1524)
				(type default)
			)
			(layer "F.SilkS")
		)
		(fp_rect
			(start -0.508 0.9398)
			(end 0.508 -0.9398)
			(stroke
				(width 0)
				(type default)
			)
			(fill no)
			(layer "F.CrtYd")
		)
		(fp_rect
			(start -0.508 0.9398)
			(end 0.508 -0.9398)
			(stroke
				(width 0)
				(type default)
			)
			(fill no)
			(layer "F.Fab")
		)
		(pad "1" smd custom
			(at 0 -0.4445 90)
			(size 0.1397 0.1397)
			(layers "F.Cu" "F.Mask" "F.Paste")
			(net "COMP_TO_BMC_RESET_R")
			(options
				(clearance outline)
				(anchor circle)
			)
			(primitives
				(gr_poly
					(pts
						(arc
							(start -0.1778 -0.2794)
							(mid -0.249642 -0.249642)
							(end -0.2794 -0.1778)
						)
						(arc
							(start -0.2794 0.1778)
							(mid -0.249642 0.249642)
							(end -0.1778 0.2794)
						)
						(arc
							(start 0.1778 0.2794)
							(mid 0.249642 0.249642)
							(end 0.2794 0.1778)
						)
						(arc
							(start 0.2794 -0.1778)
							(mid 0.249642 -0.249642)
							(end 0.1778 -0.2794)
						)
					)
					(width 0)
					(fill yes)
				)
			)
		)
		(pad "2" smd custom
			(at 0 0.4445 90)
			(size 0.1397 0.1397)
			(layers "F.Cu" "F.Mask" "F.Paste")
			(net "COMP_TO_BMC_RESET")
			(options
				(clearance outline)
				(anchor circle)
			)
			(primitives
				(gr_poly
					(pts
						(arc
							(start -0.1778 -0.2794)
							(mid -0.249642 -0.249642)
							(end -0.2794 -0.1778)
						)
						(arc
							(start -0.2794 0.1778)
							(mid -0.249642 0.249642)
							(end -0.1778 0.2794)
						)
						(arc
							(start 0.1778 0.2794)
							(mid 0.249642 0.249642)
							(end 0.2794 0.1778)
						)
						(arc
							(start 0.2794 -0.1778)
							(mid 0.249642 -0.249642)
							(end 0.1778 -0.2794)
						)
					)
					(width 0)
					(fill yes)
				)
			)
		)
	)
	(footprint ""
		(layer "F.Cu")
		(at 222.499936 -120.000014)
		(property "Reference" ""
			(at 0 0 0)
			(layer "F.SilkS")
			(hide yes)
			(effects
				(font
					(size 1.27 1.27)
				)
			)
		)
		(property "Value" "*"
			(at -6.38175 0.19685 0)
			(unlocked yes)
			(layer "F.Fab")
			(hide yes)
			(effects
				(font
					(size 1.016 1.016)
					(thickness 0.1524)
				)
			)
		)
		(duplicate_pad_numbers_are_jumpers no)
		(fp_poly
			(pts
				(arc
					(start 5.0673 0)
					(mid -5.0673 0)
					(end 5.0673 0)
				)
			)
			(stroke
				(width 0)
				(type default)
			)
			(fill no)
			(layer "B.CrtYd")
		)
		(fp_poly
			(pts
				(arc
					(start 5.0673 0)
					(mid -5.0673 0)
					(end 5.0673 0)
				)
			)
			(stroke
				(width 0)
				(type default)
			)
			(fill no)
			(layer "F.CrtYd")
		)
		(fp_poly
			(pts
				(arc
					(start 5.0673 0)
					(mid -5.0673 0)
					(end 5.0673 0)
				)
			)
			(stroke
				(width 0)
				(type default)
			)
			(fill no)
			(layer "B.Fab")
		)
		(fp_poly
			(pts
				(arc
					(start 5.0673 0)
					(mid -5.0673 0)
					(end 5.0673 0)
				)
			)
			(stroke
				(width 0)
				(type default)
			)
			(fill no)
			(layer "F.Fab")
		)
		(pad "1" thru_hole circle
			(at 0 0)
			(size 9.525 9.525)
			(drill 3.5052)
			(layers "*.Cu" "*.Mask")
			(remove_unused_layers no)
			(net "Net_37")
			(clearance -2.5019)
			(thermal_gap 0.3048)
			(padstack
				(mode front_inner_back)
				(layer "Inner"
					(shape circle)
					(size 3.9116 3.9116)
					(clearance 0.3048)
				)
				(layer "B.Cu"
					(shape circle)
					(size 9.525 9.525)
					(clearance -2.5019)
				)
			)
		)
	)
	(footprint ""
		(layer "F.Cu")
		(at 75.632818 -148.365972 180)
		(property "Reference" "C75"
			(at 0 0 180)
			(layer "F.SilkS")
			(hide yes)
			(effects
				(font
					(size 1.27 1.27)
				)
			)
		)
		(property "Value" "SCD1U16V2KX-3GP"
			(at 1.1811 -2.7051 180)
			(unlocked yes)
			(layer "F.Fab")
			(hide yes)
			(effects
				(font
					(size 1.016 1.016)
					(thickness 0.1524)
				)
			)
		)
		(property "Device Type" "C402H22"
			(at 1.1811 -4.2291 180)
			(unlocked yes)
			(layer "F.Fab")
			(hide yes)
			(effects
				(font
					(size 1.016 1.016)
					(thickness 0.1524)
				)
			)
		)
		(duplicate_pad_numbers_are_jumpers no)
		(fp_rect
			(start -0.4318 0.9525)
			(end 0.4318 -0.9525)
			(stroke
				(width 0)
				(type default)
			)
			(fill no)
			(layer "F.CrtYd")
		)
		(fp_rect
			(start -0.4318 0.9525)
			(end 0.4318 -0.9525)
			(stroke
				(width 0)
				(type default)
			)
			(fill no)
			(layer "F.Fab")
		)
		(pad "1" smd custom
			(at 0 -0.4445 180)
			(size 0.1524 0.1524)
			(layers "F.Cu" "F.Mask" "F.Paste")
			(net "P3V3_STBY")
			(options
				(clearance outline)
				(anchor circle)
			)
			(primitives
				(gr_poly
					(pts
						(arc
							(start 0.3048 -0.2032)
							(mid 0.275042 -0.275042)
							(end 0.2032 -0.3048)
						)
						(arc
							(start -0.2032 -0.3048)
							(mid -0.275042 -0.275042)
							(end -0.3048 -0.2032)
						)
						(arc
							(start -0.3048 0.2032)
							(mid -0.275042 0.275042)
							(end -0.2032 0.3048)
						)
						(arc
							(start 0.2032 0.3048)
							(mid 0.275042 0.275042)
							(end 0.3048 0.2032)
						)
					)
					(width 0)
					(fill yes)
				)
			)
		)
		(pad "2" smd custom
			(at 0 0.4445 180)
			(size 0.1524 0.1524)
			(layers "F.Cu" "F.Mask" "F.Paste")
			(net "GND")
			(options
				(clearance outline)
				(anchor circle)
			)
			(primitives
				(gr_poly
					(pts
						(arc
							(start 0.3048 -0.2032)
							(mid 0.275042 -0.275042)
							(end 0.2032 -0.3048)
						)
						(arc
							(start -0.2032 -0.3048)
							(mid -0.275042 -0.275042)
							(end -0.3048 -0.2032)
						)
						(arc
							(start -0.3048 0.2032)
							(mid -0.275042 0.275042)
							(end -0.2032 0.3048)
						)
						(arc
							(start 0.2032 0.3048)
							(mid 0.275042 0.275042)
							(end 0.3048 0.2032)
						)
					)
					(width 0)
					(fill yes)
				)
			)
		)
	)
	(footprint ""
		(layer "F.Cu")
		(at 99.3902 -152.7302 -90)
		(property "Reference" "R31"
			(at 0 0 270)
			(layer "F.SilkS")
			(hide yes)
			(effects
				(font
					(size 1.27 1.27)
				)
			)
		)
		(property "Value" "4K7R2F-GP"
			(at 0.064008 -3.993896 270)
			(unlocked yes)
			(layer "F.Fab")
			(hide yes)
			(effects
				(font
					(size 1.016 1.016)
					(thickness 0.1524)
				)
			)
		)
		(property "Device Type" "R402H16"
			(at 0.064008 -5.517896 270)
			(unlocked yes)
			(layer "F.Fab")
			(hide yes)
			(effects
				(font
					(size 1.016 1.016)
					(thickness 0.1524)
				)
			)
		)
		(duplicate_pad_numbers_are_jumpers no)
		(fp_line
			(start -0.508 -0.9398)
			(end -0.508 0.9398)
			(stroke
				(width 0.1524)
				(type default)
			)
			(layer "F.SilkS")
		)
		(fp_line
			(start 0.508 -0.9398)
			(end -0.508 -0.9398)
			(stroke
				(width 0.1524)
				(type default)
			)
			(layer "F.SilkS")
		)
		(fp_rect
			(start -0.508 0.9398)
			(end 0.508 -0.9398)
			(stroke
				(width 0)
				(type default)
			)
			(fill no)
			(layer "F.CrtYd")
		)
		(fp_rect
			(start -0.508 0.9398)
			(end 0.508 -0.9398)
			(stroke
				(width 0)
				(type default)
			)
			(fill no)
			(layer "F.Fab")
		)
		(pad "1" smd custom
			(at 0 -0.4445 270)
			(size 0.1397 0.1397)
			(layers "F.Cu" "F.Mask" "F.Paste")
			(net "P3V3_STBY")
			(options
				(clearance outline)
				(anchor circle)
			)
			(primitives
				(gr_poly
					(pts
						(arc
							(start -0.1778 -0.2794)
							(mid -0.249642 -0.249642)
							(end -0.2794 -0.1778)
						)
						(arc
							(start -0.2794 0.1778)
							(mid -0.249642 0.249642)
							(end -0.1778 0.2794)
						)
						(arc
							(start 0.1778 0.2794)
							(mid 0.249642 0.249642)
							(end 0.2794 0.1778)
						)
						(arc
							(start 0.2794 -0.1778)
							(mid 0.249642 -0.249642)
							(end 0.1778 -0.2794)
						)
					)
					(width 0)
					(fill yes)
				)
			)
		)
		(pad "2" smd custom
			(at 0 0.4445 270)
			(size 0.1397 0.1397)
			(layers "F.Cu" "F.Mask" "F.Paste")
			(net "USB_OCS_N4")
			(options
				(clearance outline)
				(anchor circle)
			)
			(primitives
				(gr_poly
					(pts
						(arc
							(start -0.1778 -0.2794)
							(mid -0.249642 -0.249642)
							(end -0.2794 -0.1778)
						)
						(arc
							(start -0.2794 0.1778)
							(mid -0.249642 0.249642)
							(end -0.1778 0.2794)
						)
						(arc
							(start 0.1778 0.2794)
							(mid 0.249642 0.249642)
							(end 0.2794 0.1778)
						)
						(arc
							(start 0.2794 -0.1778)
							(mid 0.249642 -0.249642)
							(end 0.1778 -0.2794)
						)
					)
					(width 0)
					(fill yes)
				)
			)
		)
	)
	(footprint ""
		(layer "F.Cu")
		(at 36.28771 -121.3612 -90)
		(property "Reference" "SKT1"
			(at 0 0 270)
			(layer "F.SilkS")
			(hide yes)
			(effects
				(font
					(size 1.27 1.27)
				)
			)
		)
		(property "Value" "SKT-SPI16P-GP-U"
			(at -8.9916 4.641596 270)
			(unlocked yes)
			(layer "F.Fab")
			(hide yes)
			(effects
				(font
					(size 1.016 1.016)
					(thickness 0.1524)
				)
			)
		)
		(property "Device Type" "SKT-SOIC16-153139H258"
			(at -8.9916 3.117596 270)
			(unlocked yes)
			(layer "F.Fab")
			(hide yes)
			(effects
				(font
					(size 1.016 1.016)
					(thickness 0.1524)
				)
			)
		)
		(duplicate_pad_numbers_are_jumpers no)
		(fp_line
			(start -7.8994 6.4008)
			(end 7.8994 6.4008)
			(stroke
				(width 0.1524)
				(type default)
			)
			(layer "F.SilkS")
		)
		(fp_line
			(start 7.8994 6.4008)
			(end 7.8994 -6.4008)
			(stroke
				(width 0.1524)
				(type default)
			)
			(layer "F.SilkS")
		)
		(fp_line
			(start 6.7183 0.0762)
			(end 7.8994 1.2573)
			(stroke
				(width 0.1524)
				(type default)
			)
			(layer "F.SilkS")
		)
		(fp_line
			(start 7.8867 -1.0922)
			(end 6.7183 0.0762)
			(stroke
				(width 0.1524)
				(type default)
			)
			(layer "F.SilkS")
		)
		(fp_line
			(start 7.7216 -6.223)
			(end 7.7216 -3.6576)
			(stroke
				(width 0.508)
				(type default)
			)
			(layer "F.SilkS")
		)
		(fp_line
			(start -7.8994 -6.4008)
			(end -7.8994 6.4008)
			(stroke
				(width 0.1524)
				(type default)
			)
			(layer "F.SilkS")
		)
		(fp_line
			(start 7.8994 -6.4008)
			(end -7.8994 -6.4008)
			(stroke
				(width 0.1524)
				(type default)
			)
			(layer "F.SilkS")
		)
		(fp_poly
			(pts
				(xy -4.699 -3.855466) (xy -4.699 3.855466) (xy 4.699 3.855466) (xy 4.699 -3.855466)
			)
			(stroke
				(width 0)
				(type default)
			)
			(fill yes)
			(layer "F.SilkS")
		)
		(fp_rect
			(start -8.1534 11.6078)
			(end 8.1534 6.4008)
			(stroke
				(width 0)
				(type default)
			)
			(fill no)
			(layer "F.CrtYd")
		)
		(fp_rect
			(start -8.1534 -6.4008)
			(end 8.1534 -12.5222)
			(stroke
				(width 0)
				(type default)
			)
			(fill no)
			(layer "F.CrtYd")
		)
		(fp_poly
			(pts
				(xy -8.1534 6.4008) (xy -8.1534 -6.4008) (xy -6.2484 -6.4008) (xy -6.2484 -2.6416) (xy -7.6454 -2.6416)
				(xy -7.6454 2.6416) (xy -6.2484 2.6416) (xy -6.2484 6.4008)
			)
			(stroke
				(width 0)
				(type default)
			)
			(fill no)
			(layer "F.CrtYd")
		)
		(fp_poly
			(pts
				(xy 6.2484 -6.4008) (xy 8.1534 -6.4008) (xy 8.1534 6.4008) (xy 6.2484 6.4008) (xy 6.2484 2.6416)
				(xy 7.6454 2.6416) (xy 7.6454 -2.6416) (xy 6.2484 -2.6416)
			)
			(stroke
				(width 0)
				(type default)
			)
			(fill no)
			(layer "F.CrtYd")
		)
		(fp_poly
			(pts
				(xy 6.2484 -6.4008) (xy -6.2484 -6.4008) (xy -6.2484 -2.6416) (xy -7.6454 -2.6416) (xy -7.6454 2.6416)
				(xy -6.2484 2.6416) (xy -6.2484 6.4008) (xy 6.2484 6.4008) (xy 6.2484 2.6416) (xy 7.6454 2.6416)
				(xy 7.6454 -2.6416) (xy 6.2484 -2.6416)
			)
			(stroke
				(width 0)
				(type default)
			)
			(fill no)
			(layer "F.CrtYd")
		)
		(fp_rect
			(start -8.1534 11.6078)
			(end 8.1534 -12.5222)
			(stroke
				(width 0)
				(type default)
			)
			(fill no)
			(layer "F.Fab")
		)
		(pad "1" smd rect
			(at 4.445 -4.896866 270)
			(size 0.508 1.6764)
			(layers "F.Cu" "F.Mask" "F.Paste")
			(net "FLA0_SPI_HOLD_N")
		)
		(pad "2" smd rect
			(at 3.175 -4.896866 270)
			(size 0.508 1.6764)
			(layers "F.Cu" "F.Mask" "F.Paste")
			(net "P3V3_STBY")
		)
		(pad "3" smd rect
			(at 1.905 -4.896866 270)
			(size 0.508 1.6764)
			(layers "F.Cu" "F.Mask" "F.Paste")
			(net "FLA0_SPI_RST")
		)
		(pad "4" smd rect
			(at 0.635 -4.896866 270)
			(size 0.508 1.6764)
			(layers "F.Cu" "F.Mask" "F.Paste")
			(net "Net_927")
		)
		(pad "5" smd rect
			(at -0.635 -4.896866 270)
			(size 0.508 1.6764)
			(layers "F.Cu" "F.Mask" "F.Paste")
			(net "Net_926")
		)
		(pad "6" smd rect
			(at -1.905 -4.896866 270)
			(size 0.508 1.6764)
			(layers "F.Cu" "F.Mask" "F.Paste")
			(net "Net_925")
		)
		(pad "7" smd rect
			(at -3.175 -4.896866 270)
			(size 0.508 1.6764)
			(layers "F.Cu" "F.Mask" "F.Paste")
			(net "FLA_CS_0_R")
		)
		(pad "8" smd rect
			(at -4.445 -4.896866 270)
			(size 0.508 1.6764)
			(layers "F.Cu" "F.Mask" "F.Paste")
			(net "BMC_SPI_MISO_TPM")
		)
		(pad "9" smd rect
			(at -4.445 4.896866 270)
			(size 0.508 1.6764)
			(layers "F.Cu" "F.Mask" "F.Paste")
			(net "FLA0_WP_N")
		)
		(pad "10" smd rect
			(at -3.175 4.896866 270)
			(size 0.508 1.6764)
			(layers "F.Cu" "F.Mask" "F.Paste")
			(net "GND")
		)
		(pad "11" smd rect
			(at -1.905 4.896866 270)
			(size 0.508 1.6764)
			(layers "F.Cu" "F.Mask" "F.Paste")
			(net "Net_931")
		)
		(pad "12" smd rect
			(at -0.635 4.896866 270)
			(size 0.508 1.6764)
			(layers "F.Cu" "F.Mask" "F.Paste")
			(net "Net_930")
		)
		(pad "13" smd rect
			(at 0.635 4.896866 270)
			(size 0.508 1.6764)
			(layers "F.Cu" "F.Mask" "F.Paste")
			(net "Net_929")
		)
		(pad "14" smd rect
			(at 1.905 4.896866 270)
			(size 0.508 1.6764)
			(layers "F.Cu" "F.Mask" "F.Paste")
			(net "Net_928")
		)
		(pad "15" smd rect
			(at 3.175 4.896866 270)
			(size 0.508 1.6764)
			(layers "F.Cu" "F.Mask" "F.Paste")
			(net "BMC_SPI_MOSI_R")
		)
		(pad "16" smd rect
			(at 4.445 4.896866 270)
			(size 0.508 1.6764)
			(layers "F.Cu" "F.Mask" "F.Paste")
			(net "BMC_SPI_CLK_R")
		)
	)
	(footprint ""
		(layer "F.Cu")
		(at 61.04255 -144.404588 -90)
		(property "Reference" "R160"
			(at 0 0 270)
			(layer "F.SilkS")
			(hide yes)
			(effects
				(font
					(size 1.27 1.27)
				)
			)
		)
		(property "Value" "0R2J-2-GP"
			(at 0.064008 -3.993896 270)
			(unlocked yes)
			(layer "F.Fab")
			(hide yes)
			(effects
				(font
					(size 1.016 1.016)
					(thickness 0.1524)
				)
			)
		)
		(property "Device Type" "R402H16"
			(at 0.064008 -5.517896 270)
			(unlocked yes)
			(layer "F.Fab")
			(hide yes)
			(effects
				(font
					(size 1.016 1.016)
					(thickness 0.1524)
				)
			)
		)
		(duplicate_pad_numbers_are_jumpers no)
		(fp_line
			(start -0.508 -0.9398)
			(end -0.508 0.9398)
			(stroke
				(width 0.1524)
				(type default)
			)
			(layer "F.SilkS")
		)
		(fp_line
			(start 0.508 -0.9398)
			(end -0.508 -0.9398)
			(stroke
				(width 0.1524)
				(type default)
			)
			(layer "F.SilkS")
		)
		(fp_rect
			(start -0.508 0.9398)
			(end 0.508 -0.9398)
			(stroke
				(width 0)
				(type default)
			)
			(fill no)
			(layer "F.CrtYd")
		)
		(fp_rect
			(start -0.508 0.9398)
			(end 0.508 -0.9398)
			(stroke
				(width 0)
				(type default)
			)
			(fill no)
			(layer "F.Fab")
		)
		(pad "1" smd custom
			(at 0 -0.4445 270)
			(size 0.1397 0.1397)
			(layers "F.Cu" "F.Mask" "F.Paste")
			(net "I2C_SCC_SCL_OUT")
			(options
				(clearance outline)
				(anchor circle)
			)
			(primitives
				(gr_poly
					(pts
						(arc
							(start -0.1778 -0.2794)
							(mid -0.249642 -0.249642)
							(end -0.2794 -0.1778)
						)
						(arc
							(start -0.2794 0.1778)
							(mid -0.249642 0.249642)
							(end -0.1778 0.2794)
						)
						(arc
							(start 0.1778 0.2794)
							(mid 0.249642 0.249642)
							(end 0.2794 0.1778)
						)
						(arc
							(start 0.2794 -0.1778)
							(mid 0.249642 -0.249642)
							(end 0.1778 -0.2794)
						)
					)
					(width 0)
					(fill yes)
				)
			)
		)
		(pad "2" smd custom
			(at 0 0.4445 270)
			(size 0.1397 0.1397)
			(layers "F.Cu" "F.Mask" "F.Paste")
			(net "BMC_SMB3_CLK")
			(options
				(clearance outline)
				(anchor circle)
			)
			(primitives
				(gr_poly
					(pts
						(arc
							(start -0.1778 -0.2794)
							(mid -0.249642 -0.249642)
							(end -0.2794 -0.1778)
						)
						(arc
							(start -0.2794 0.1778)
							(mid -0.249642 0.249642)
							(end -0.1778 0.2794)
						)
						(arc
							(start 0.1778 0.2794)
							(mid 0.249642 0.249642)
							(end 0.2794 0.1778)
						)
						(arc
							(start 0.2794 -0.1778)
							(mid 0.249642 -0.249642)
							(end 0.1778 -0.2794)
						)
					)
					(width 0)
					(fill yes)
				)
			)
		)
	)
	(footprint ""
		(layer "F.Cu")
		(at 180.848 -111.0234)
		(property "Reference" "R545"
			(at 0 0 0)
			(layer "F.SilkS")
			(hide yes)
			(effects
				(font
					(size 1.27 1.27)
				)
			)
		)
		(property "Value" "4K7R2F-GP"
			(at 0.064008 -3.993896 0)
			(unlocked yes)
			(layer "F.Fab")
			(hide yes)
			(effects
				(font
					(size 1.016 1.016)
					(thickness 0.1524)
				)
			)
		)
		(property "Device Type" "R402H16"
			(at 0.064008 -5.517896 0)
			(unlocked yes)
			(layer "F.Fab")
			(hide yes)
			(effects
				(font
					(size 1.016 1.016)
					(thickness 0.1524)
				)
			)
		)
		(duplicate_pad_numbers_are_jumpers no)
		(fp_line
			(start -0.508 -0.9398)
			(end -0.508 0.9398)
			(stroke
				(width 0.1524)
				(type default)
			)
			(layer "F.SilkS")
		)
		(fp_line
			(start 0.508 -0.9398)
			(end -0.508 -0.9398)
			(stroke
				(width 0.1524)
				(type default)
			)
			(layer "F.SilkS")
		)
		(fp_rect
			(start -0.508 0.9398)
			(end 0.508 -0.9398)
			(stroke
				(width 0)
				(type default)
			)
			(fill no)
			(layer "F.CrtYd")
		)
		(fp_rect
			(start -0.508 0.9398)
			(end 0.508 -0.9398)
			(stroke
				(width 0)
				(type default)
			)
			(fill no)
			(layer "F.Fab")
		)
		(pad "1" smd custom
			(at 0 -0.4445)
			(size 0.1397 0.1397)
			(layers "F.Cu" "F.Mask" "F.Paste")
			(net "P3V3_STBY")
			(options
				(clearance outline)
				(anchor circle)
			)
			(primitives
				(gr_poly
					(pts
						(arc
							(start -0.1778 -0.2794)
							(mid -0.249642 -0.249642)
							(end -0.2794 -0.1778)
						)
						(arc
							(start -0.2794 0.1778)
							(mid -0.249642 0.249642)
							(end -0.1778 0.2794)
						)
						(arc
							(start 0.1778 0.2794)
							(mid 0.249642 0.249642)
							(end 0.2794 0.1778)
						)
						(arc
							(start 0.2794 -0.1778)
							(mid 0.249642 -0.249642)
							(end 0.1778 -0.2794)
						)
					)
					(width 0)
					(fill yes)
				)
			)
		)
		(pad "2" smd custom
			(at 0 0.4445)
			(size 0.1397 0.1397)
			(layers "F.Cu" "F.Mask" "F.Paste")
			(net "TEMP_1_A0")
			(options
				(clearance outline)
				(anchor circle)
			)
			(primitives
				(gr_poly
					(pts
						(arc
							(start -0.1778 -0.2794)
							(mid -0.249642 -0.249642)
							(end -0.2794 -0.1778)
						)
						(arc
							(start -0.2794 0.1778)
							(mid -0.249642 0.249642)
							(end -0.1778 0.2794)
						)
						(arc
							(start 0.1778 0.2794)
							(mid 0.249642 0.249642)
							(end 0.2794 0.1778)
						)
						(arc
							(start 0.2794 -0.1778)
							(mid 0.249642 -0.249642)
							(end 0.1778 -0.2794)
						)
					)
					(width 0)
					(fill yes)
				)
			)
		)
	)
	(footprint ""
		(layer "F.Cu")
		(at 149.28088 -12.81049 90)
		(property "Reference" "R513"
			(at 0 0 90)
			(layer "F.SilkS")
			(hide yes)
			(effects
				(font
					(size 1.27 1.27)
				)
			)
		)
		(property "Value" "10KR2F-2-GP"
			(at 0.064008 -3.993896 90)
			(unlocked yes)
			(layer "F.Fab")
			(hide yes)
			(effects
				(font
					(size 1.016 1.016)
					(thickness 0.1524)
				)
			)
		)
		(property "Device Type" "R402H16"
			(at 0.064008 -5.517896 90)
			(unlocked yes)
			(layer "F.Fab")
			(hide yes)
			(effects
				(font
					(size 1.016 1.016)
					(thickness 0.1524)
				)
			)
		)
		(duplicate_pad_numbers_are_jumpers no)
		(fp_line
			(start 0.508 -0.9398)
			(end -0.508 -0.9398)
			(stroke
				(width 0.1524)
				(type default)
			)
			(layer "F.SilkS")
		)
		(fp_line
			(start -0.508 -0.9398)
			(end -0.508 0.9398)
			(stroke
				(width 0.1524)
				(type default)
			)
			(layer "F.SilkS")
		)
		(fp_rect
			(start -0.508 0.9398)
			(end 0.508 -0.9398)
			(stroke
				(width 0)
				(type default)
			)
			(fill no)
			(layer "F.CrtYd")
		)
		(fp_rect
			(start -0.508 0.9398)
			(end 0.508 -0.9398)
			(stroke
				(width 0)
				(type default)
			)
			(fill no)
			(layer "F.Fab")
		)
		(pad "1" smd custom
			(at 0 -0.4445 90)
			(size 0.1397 0.1397)
			(layers "F.Cu" "F.Mask" "F.Paste")
			(net "AGND_P1V8_STBY")
			(options
				(clearance outline)
				(anchor circle)
			)
			(primitives
				(gr_poly
					(pts
						(arc
							(start -0.1778 -0.2794)
							(mid -0.249642 -0.249642)
							(end -0.2794 -0.1778)
						)
						(arc
							(start -0.2794 0.1778)
							(mid -0.249642 0.249642)
							(end -0.1778 0.2794)
						)
						(arc
							(start 0.1778 0.2794)
							(mid 0.249642 0.249642)
							(end 0.2794 0.1778)
						)
						(arc
							(start 0.2794 -0.1778)
							(mid 0.249642 -0.249642)
							(end 0.1778 -0.2794)
						)
					)
					(width 0)
					(fill yes)
				)
			)
		)
		(pad "2" smd custom
			(at 0 0.4445 90)
			(size 0.1397 0.1397)
			(layers "F.Cu" "F.Mask" "F.Paste")
			(net "P1V8_STBY_VFB")
			(options
				(clearance outline)
				(anchor circle)
			)
			(primitives
				(gr_poly
					(pts
						(arc
							(start -0.1778 -0.2794)
							(mid -0.249642 -0.249642)
							(end -0.2794 -0.1778)
						)
						(arc
							(start -0.2794 0.1778)
							(mid -0.249642 0.249642)
							(end -0.1778 0.2794)
						)
						(arc
							(start 0.1778 0.2794)
							(mid 0.249642 0.249642)
							(end 0.2794 0.1778)
						)
						(arc
							(start 0.2794 -0.1778)
							(mid 0.249642 -0.249642)
							(end 0.1778 -0.2794)
						)
					)
					(width 0)
					(fill yes)
				)
			)
		)
	)
	(footprint ""
		(layer "F.Cu")
		(at 98.3742 -137.4394 90)
		(property "Reference" "C51"
			(at 0 0 90)
			(layer "F.SilkS")
			(hide yes)
			(effects
				(font
					(size 1.27 1.27)
				)
			)
		)
		(property "Value" "SCD1U16V2KX-3GP"
			(at 1.1811 -2.7051 90)
			(unlocked yes)
			(layer "F.Fab")
			(hide yes)
			(effects
				(font
					(size 1.016 1.016)
					(thickness 0.1524)
				)
			)
		)
		(property "Device Type" "C402H22"
			(at 1.1811 -4.2291 90)
			(unlocked yes)
			(layer "F.Fab")
			(hide yes)
			(effects
				(font
					(size 1.016 1.016)
					(thickness 0.1524)
				)
			)
		)
		(duplicate_pad_numbers_are_jumpers no)
		(fp_rect
			(start -0.4318 0.9525)
			(end 0.4318 -0.9525)
			(stroke
				(width 0)
				(type default)
			)
			(fill no)
			(layer "F.CrtYd")
		)
		(fp_rect
			(start -0.4318 0.9525)
			(end 0.4318 -0.9525)
			(stroke
				(width 0)
				(type default)
			)
			(fill no)
			(layer "F.Fab")
		)
		(pad "1" smd custom
			(at 0 -0.4445 90)
			(size 0.1524 0.1524)
			(layers "F.Cu" "F.Mask" "F.Paste")
			(net "P3V3_STBY")
			(options
				(clearance outline)
				(anchor circle)
			)
			(primitives
				(gr_poly
					(pts
						(arc
							(start 0.3048 -0.2032)
							(mid 0.275042 -0.275042)
							(end 0.2032 -0.3048)
						)
						(arc
							(start -0.2032 -0.3048)
							(mid -0.275042 -0.275042)
							(end -0.3048 -0.2032)
						)
						(arc
							(start -0.3048 0.2032)
							(mid -0.275042 0.275042)
							(end -0.2032 0.3048)
						)
						(arc
							(start 0.2032 0.3048)
							(mid 0.275042 0.275042)
							(end 0.3048 0.2032)
						)
					)
					(width 0)
					(fill yes)
				)
			)
		)
		(pad "2" smd custom
			(at 0 0.4445 90)
			(size 0.1524 0.1524)
			(layers "F.Cu" "F.Mask" "F.Paste")
			(net "GND")
			(options
				(clearance outline)
				(anchor circle)
			)
			(primitives
				(gr_poly
					(pts
						(arc
							(start 0.3048 -0.2032)
							(mid 0.275042 -0.275042)
							(end 0.2032 -0.3048)
						)
						(arc
							(start -0.2032 -0.3048)
							(mid -0.275042 -0.275042)
							(end -0.3048 -0.2032)
						)
						(arc
							(start -0.3048 0.2032)
							(mid -0.275042 0.275042)
							(end -0.2032 0.3048)
						)
						(arc
							(start 0.2032 0.3048)
							(mid 0.275042 0.275042)
							(end 0.3048 0.2032)
						)
					)
					(width 0)
					(fill yes)
				)
			)
		)
	)
	(footprint ""
		(layer "F.Cu")
		(at 84.983828 -85.336634 90)
		(property "Reference" "VIA14"
			(at 0 0 90)
			(layer "F.SilkS")
			(hide yes)
			(effects
				(font
					(size 1.27 1.27)
				)
			)
		)
		(property "Value" "85OHM-8L-1D6MM-L16L18-GP"
			(at 4.064 0.6096 90)
			(unlocked yes)
			(layer "F.Fab")
			(hide yes)
			(effects
				(font
					(size 1.016 1.016)
					(thickness 0.1524)
				)
			)
		)
		(property "Device Type" "VIA-PCIE-4P-368076"
			(at 4.064 -0.9144 90)
			(unlocked yes)
			(layer "F.Fab")
			(hide yes)
			(effects
				(font
					(size 1.016 1.016)
					(thickness 0.1524)
				)
			)
		)
		(duplicate_pad_numbers_are_jumpers no)
		(fp_rect
			(start -1.8415 0.381)
			(end 1.8415 -0.381)
			(stroke
				(width 0)
				(type default)
			)
			(fill no)
			(layer "F.CrtYd")
		)
		(fp_rect
			(start -1.8415 0.381)
			(end 1.8415 -0.381)
			(stroke
				(width 0)
				(type default)
			)
			(fill no)
			(layer "F.Fab")
		)
		(pad "1" thru_hole circle
			(at -1.4605 0 90)
			(size 0.508 0.508)
			(drill 0.254)
			(layers "*.Cu" "*.Mask")
			(remove_unused_layers no)
			(net "GND")
			(clearance 0.127)
			(thermal_gap 0.127)
		)
		(pad "2" thru_hole circle
			(at -0.4445 0 90)
			(size 0.508 0.508)
			(drill 0.254)
			(layers "*.Cu" "*.Mask")
			(remove_unused_layers no)
			(net "PCIE_IOM_TO_COMP_20_DP")
			(clearance 0.127)
			(thermal_gap 0.127)
		)
		(pad "3" thru_hole circle
			(at 0.4445 0 90)
			(size 0.508 0.508)
			(drill 0.254)
			(layers "*.Cu" "*.Mask")
			(remove_unused_layers no)
			(net "PCIE_IOM_TO_COMP_20_DN")
			(clearance 0.127)
			(thermal_gap 0.127)
		)
		(pad "4" thru_hole circle
			(at 1.4605 0 90)
			(size 0.508 0.508)
			(drill 0.254)
			(layers "*.Cu" "*.Mask")
			(remove_unused_layers no)
			(net "GND")
			(clearance 0.127)
			(thermal_gap 0.127)
		)
	)
	(footprint ""
		(layer "F.Cu")
		(at 222.873824 -86.284054)
		(property "Reference" "L31"
			(at 0 0 0)
			(layer "F.SilkS")
			(hide yes)
			(effects
				(font
					(size 1.27 1.27)
				)
			)
		)
		(property "Value" "IND-1UH-191-GP"
			(at -6.7818 -2.1082 0)
			(unlocked yes)
			(layer "F.Fab")
			(hide yes)
			(effects
				(font
					(size 1.016 1.016)
					(thickness 0.1524)
				)
			)
		)
		(property "Device Type" "L109100-2430-UH119"
			(at -6.7818 -3.6322 0)
			(unlocked yes)
			(layer "F.Fab")
			(hide yes)
			(effects
				(font
					(size 1.016 1.016)
					(thickness 0.1524)
				)
			)
		)
		(duplicate_pad_numbers_are_jumpers no)
		(fp_line
			(start -5.2578 -6.4262)
			(end 5.2578 -6.4262)
			(stroke
				(width 0.1524)
				(type default)
			)
			(layer "F.SilkS")
		)
		(fp_line
			(start -5.2578 6.4262)
			(end -5.2578 -6.4262)
			(stroke
				(width 0.1524)
				(type default)
			)
			(layer "F.SilkS")
		)
		(fp_line
			(start 5.2578 -6.4262)
			(end 5.2578 6.4262)
			(stroke
				(width 0.1524)
				(type default)
			)
			(layer "F.SilkS")
		)
		(fp_line
			(start 5.2578 6.4262)
			(end -5.2578 6.4262)
			(stroke
				(width 0.1524)
				(type default)
			)
			(layer "F.SilkS")
		)
		(fp_rect
			(start -5.0038 5.4229)
			(end 5.0038 -5.4229)
			(stroke
				(width 0)
				(type default)
			)
			(fill no)
			(layer "F.CrtYd")
		)
		(fp_poly
			(pts
				(xy -5.5118 6.5024) (xy -5.5118 -6.5024) (xy 5.5118 -6.5024) (xy 5.5118 -0.8509) (xy 5.0038 -0.8509)
				(xy 5.0038 -5.4229) (xy -5.0038 -5.4229) (xy -5.0038 5.4229) (xy 5.0038 5.4229) (xy 5.0038 -0.8382)
				(xy 5.5118 -0.8382) (xy 5.5118 6.5024)
			)
			(stroke
				(width 0)
				(type default)
			)
			(fill no)
			(layer "F.CrtYd")
		)
		(fp_rect
			(start -5.5118 6.5024)
			(end 5.5118 -6.5024)
			(stroke
				(width 0)
				(type default)
			)
			(fill no)
			(layer "F.Fab")
		)
		(pad "1" smd rect
			(at 0 -4.396994)
			(size 3.5052 3.556)
			(layers "F.Cu" "F.Mask" "F.Paste")
			(net "P3V3_M2_LL")
		)
		(pad "2" smd rect
			(at 0 4.396994)
			(size 3.5052 3.556)
			(layers "F.Cu" "F.Mask" "F.Paste")
			(net "P3V3_M2")
		)
	)
	(footprint ""
		(layer "F.Cu")
		(at 88.9 -12.649962)
		(property "Reference" "USB1"
			(at 0 0 0)
			(layer "F.SilkS")
			(hide yes)
			(effects
				(font
					(size 1.27 1.27)
				)
			)
		)
		(property "Value" "SKT-USB13-246-GP"
			(at 4.9149 11.7348 0)
			(unlocked yes)
			(layer "F.Fab")
			(hide yes)
			(effects
				(font
					(size 1.016 1.016)
					(thickness 0.1524)
				)
			)
		)
		(property "Device Type" "SKT-USB13-064258"
			(at 4.9149 10.2108 0)
			(unlocked yes)
			(layer "F.Fab")
			(hide yes)
			(effects
				(font
					(size 1.016 1.016)
					(thickness 0.1524)
				)
			)
		)
		(duplicate_pad_numbers_are_jumpers no)
		(fp_line
			(start -3.827526 -10.395204)
			(end -3.827526 -11.004804)
			(stroke
				(width 0.3048)
				(type default)
			)
			(layer "F.SilkS")
		)
		(fp_line
			(start -3.827526 0.6477)
			(end -3.827526 -0.6477)
			(stroke
				(width 0.3048)
				(type default)
			)
			(layer "F.SilkS")
		)
		(fp_line
			(start -3.7211 -12.8016)
			(end 3.7211 -12.8016)
			(stroke
				(width 0.1524)
				(type default)
			)
			(layer "F.SilkS")
		)
		(fp_line
			(start -3.7211 -9.5758)
			(end -3.7211 -12.8016)
			(stroke
				(width 0.1524)
				(type default)
			)
			(layer "F.SilkS")
		)
		(fp_line
			(start -3.7211 -1.4732)
			(end -3.4671 -1.4732)
			(stroke
				(width 0.1524)
				(type default)
			)
			(layer "F.SilkS")
		)
		(fp_line
			(start -3.7211 1.4732)
			(end -3.7211 -1.4732)
			(stroke
				(width 0.1524)
				(type default)
			)
			(layer "F.SilkS")
		)
		(fp_line
			(start -3.4671 -9.5758)
			(end -3.7211 -9.5758)
			(stroke
				(width 0.1524)
				(type default)
			)
			(layer "F.SilkS")
		)
		(fp_line
			(start -3.4671 -1.4732)
			(end -3.4671 -9.5758)
			(stroke
				(width 0.1524)
				(type default)
			)
			(layer "F.SilkS")
		)
		(fp_line
			(start -3.4671 1.4732)
			(end -3.7211 1.4732)
			(stroke
				(width 0.1524)
				(type default)
			)
			(layer "F.SilkS")
		)
		(fp_line
			(start -3.4671 12.649962)
			(end -3.4671 1.4732)
			(stroke
				(width 0.1524)
				(type default)
			)
			(layer "F.SilkS")
		)
		(fp_line
			(start -3.4671 13.462)
			(end -3.4671 12.649962)
			(stroke
				(width 0.1524)
				(type default)
			)
			(layer "F.SilkS")
		)
		(fp_line
			(start -1.592326 -11.004804)
			(end -1.592326 -10.395204)
			(stroke
				(width 0.3048)
				(type default)
			)
			(layer "F.SilkS")
		)
		(fp_line
			(start -1.592326 -0.6477)
			(end -1.592326 0.6477)
			(stroke
				(width 0.3048)
				(type default)
			)
			(layer "F.SilkS")
		)
		(fp_line
			(start 1.592326 -10.052304)
			(end 1.592326 -11.347704)
			(stroke
				(width 0.3048)
				(type default)
			)
			(layer "F.SilkS")
		)
		(fp_line
			(start 1.592326 0.3048)
			(end 1.592326 -0.3048)
			(stroke
				(width 0.3048)
				(type default)
			)
			(layer "F.SilkS")
		)
		(fp_line
			(start 3.4671 -9.2202)
			(end 3.4671 -1.1303)
			(stroke
				(width 0.1524)
				(type default)
			)
			(layer "F.SilkS")
		)
		(fp_line
			(start 3.4671 -1.1303)
			(end 3.7211 -1.1303)
			(stroke
				(width 0.1524)
				(type default)
			)
			(layer "F.SilkS")
		)
		(fp_line
			(start 3.4671 1.1303)
			(end 3.4671 12.649962)
			(stroke
				(width 0.1524)
				(type default)
			)
			(layer "F.SilkS")
		)
		(fp_line
			(start 3.4671 12.649962)
			(end -3.4671 12.649962)
			(stroke
				(width 0.1524)
				(type default)
			)
			(layer "F.SilkS")
		)
		(fp_line
			(start 3.4671 12.649962)
			(end 3.4671 13.462)
			(stroke
				(width 0.1524)
				(type default)
			)
			(layer "F.SilkS")
		)
		(fp_line
			(start 3.4671 13.462)
			(end -3.4671 13.462)
			(stroke
				(width 0.1524)
				(type default)
			)
			(layer "F.SilkS")
		)
		(fp_line
			(start 3.7211 -12.8016)
			(end 3.7211 -9.2202)
			(stroke
				(width 0.1524)
				(type default)
			)
			(layer "F.SilkS")
		)
		(fp_line
			(start 3.7211 -9.2202)
			(end 3.4671 -9.2202)
			(stroke
				(width 0.1524)
				(type default)
			)
			(layer "F.SilkS")
		)
		(fp_line
			(start 3.7211 -1.1303)
			(end 3.7211 1.1303)
			(stroke
				(width 0.1524)
				(type default)
			)
			(layer "F.SilkS")
		)
		(fp_line
			(start 3.7211 1.1303)
			(end 3.4671 1.1303)
			(stroke
				(width 0.1524)
				(type default)
			)
			(layer "F.SilkS")
		)
		(fp_line
			(start 3.827526 -11.347704)
			(end 3.827526 -10.052304)
			(stroke
				(width 0.3048)
				(type default)
			)
			(layer "F.SilkS")
		)
		(fp_line
			(start 3.827526 -0.3048)
			(end 3.827526 0.3048)
			(stroke
				(width 0.3048)
				(type default)
			)
			(layer "F.SilkS")
		)
		(fp_arc
			(start -3.827526 -11.004804)
			(mid -2.709926 -12.122404)
			(end -1.592326 -11.004804)
			(stroke
				(width 0.3048)
				(type default)
			)
			(layer "F.SilkS")
		)
		(fp_arc
			(start -3.827526 -0.6477)
			(mid -2.709926 -1.7653)
			(end -1.592326 -0.6477)
			(stroke
				(width 0.3048)
				(type default)
			)
			(layer "F.SilkS")
		)
		(fp_arc
			(start -1.592326 -10.395204)
			(mid -2.709926 -9.277604)
			(end -3.827526 -10.395204)
			(stroke
				(width 0.3048)
				(type default)
			)
			(layer "F.SilkS")
		)
		(fp_arc
			(start -1.592326 0.6477)
			(mid -2.709926 1.7653)
			(end -3.827526 0.6477)
			(stroke
				(width 0.3048)
				(type default)
			)
			(layer "F.SilkS")
		)
		(fp_arc
			(start 1.592326 -11.347704)
			(mid 2.709926 -12.465304)
			(end 3.827526 -11.347704)
			(stroke
				(width 0.3048)
				(type default)
			)
			(layer "F.SilkS")
		)
		(fp_arc
			(start 1.592326 -0.3048)
			(mid 2.709926 -1.4224)
			(end 3.827526 -0.3048)
			(stroke
				(width 0.3048)
				(type default)
			)
			(layer "F.SilkS")
		)
		(fp_arc
			(start 1.607566 -9.8679)
			(mid 1.596126 -9.959786)
			(end 1.592326 -10.052304)
			(stroke
				(width 0.3048)
				(type default)
			)
			(layer "F.SilkS")
		)
		(fp_arc
			(start 1.783588 -9.426956)
			(mid 0.074258 -9.000444)
			(end 1.607566 -9.8679)
			(stroke
				(width 0.3048)
				(type default)
			)
			(layer "F.SilkS")
		)
		(fp_arc
			(start 3.827526 -10.052304)
			(mid 3.036889 -8.983601)
			(end 1.783588 -9.426956)
			(stroke
				(width 0.3048)
				(type default)
			)
			(layer "F.SilkS")
		)
		(fp_arc
			(start 3.827526 0.3048)
			(mid 2.709926 1.4224)
			(end 1.592326 0.3048)
			(stroke
				(width 0.3048)
				(type default)
			)
			(layer "F.SilkS")
		)
		(fp_circle
			(center -0.899922 -8.830056)
			(end -0.010922 -8.830056)
			(stroke
				(width 0.3048)
				(type default)
			)
			(fill no)
			(layer "F.SilkS")
		)
		(fp_circle
			(center -0.899922 -6.329934)
			(end -0.010922 -6.329934)
			(stroke
				(width 0.3048)
				(type default)
			)
			(fill no)
			(layer "F.SilkS")
		)
		(fp_circle
			(center -0.899922 -4.329938)
			(end -0.010922 -4.329938)
			(stroke
				(width 0.3048)
				(type default)
			)
			(fill no)
			(layer "F.SilkS")
		)
		(fp_circle
			(center -0.899922 -1.829816)
			(end -0.010922 -1.829816)
			(stroke
				(width 0.3048)
				(type default)
			)
			(fill no)
			(layer "F.SilkS")
		)
		(fp_circle
			(center -0.899922 -1.829816)
			(end -0.010922 -1.829816)
			(stroke
				(width 0.3048)
				(type default)
			)
			(fill no)
			(layer "F.SilkS")
		)
		(fp_circle
			(center 0.899922 -7.329932)
			(end 1.788922 -7.329932)
			(stroke
				(width 0.3048)
				(type default)
			)
			(fill no)
			(layer "F.SilkS")
		)
		(fp_circle
			(center 0.899922 -5.329936)
			(end 1.788922 -5.329936)
			(stroke
				(width 0.3048)
				(type default)
			)
			(fill no)
			(layer "F.SilkS")
		)
		(fp_circle
			(center 0.899922 -3.32994)
			(end 1.788922 -3.32994)
			(stroke
				(width 0.3048)
				(type default)
			)
			(fill no)
			(layer "F.SilkS")
		)
		(fp_circle
			(center 0.899922 -1.329944)
			(end 1.788922 -1.329944)
			(stroke
				(width 0.3048)
				(type default)
			)
			(fill no)
			(layer "F.SilkS")
		)
		(fp_circle
			(center 0.899922 -1.329944)
			(end 1.788922 -1.329944)
			(stroke
				(width 0.3048)
				(type default)
			)
			(fill no)
			(layer "F.SilkS")
		)
		(fp_rect
			(start -3.2131 13.208)
			(end 3.2131 -12.5476)
			(stroke
				(width 0)
				(type default)
			)
			(fill no)
			(layer "F.CrtYd")
		)
		(fp_poly
			(pts
				(xy -3.7211 13.716) (xy -3.7211 1.7272) (xy -3.9751 1.7272) (xy -3.9751 -1.7272) (xy -3.7211 -1.7272)
				(xy -3.7211 -9.3218) (xy -3.9751 -9.3218) (xy -3.9751 -13.0556) (xy 3.9751 -13.0556) (xy 3.9751 -8.9662)
				(xy 3.7211 -8.9662) (xy 3.7211 -1.3843) (xy 3.9751 -1.3843) (xy 3.9751 -0.00635) (xy 3.2131 -0.00635)
				(xy 3.2131 -12.5476) (xy -3.2131 -12.5476) (xy -3.2131 13.208) (xy 3.2131 13.208) (xy 3.2131 0.00635)
				(xy 3.9751 0.00635) (xy 3.9751 1.3843) (xy 3.7211 1.3843) (xy 3.7211 13.716)
			)
			(stroke
				(width 0)
				(type default)
			)
			(fill no)
			(layer "F.CrtYd")
		)
		(fp_poly
			(pts
				(xy -3.7211 13.716) (xy -3.7211 1.7272) (xy -3.9751 1.7272) (xy -3.9751 -1.7272) (xy -3.7211 -1.7272)
				(xy -3.7211 -9.3218) (xy -3.9751 -9.3218) (xy -3.9751 -13.0556) (xy 3.9751 -13.0556) (xy 3.9751 -8.9662)
				(xy 3.7211 -8.9662) (xy 3.7211 -1.3843) (xy 3.9751 -1.3843) (xy 3.9751 1.3843) (xy 3.7211 1.3843)
				(xy 3.7211 13.716)
			)
			(stroke
				(width 0)
				(type default)
			)
			(fill no)
			(layer "F.Fab")
		)
		(pad "1" thru_hole circle
			(at -0.899922 -8.830056)
			(size 1.0668 1.0668)
			(drill 0.7112)
			(layers "*.Cu" "*.Mask")
			(remove_unused_layers no)
			(net "P5V_VBUS_CONN")
			(clearance 0.1778)
			(thermal_gap 0.1778)
		)
		(pad "2" thru_hole circle
			(at -0.899922 -6.329934)
			(size 1.0668 1.0668)
			(drill 0.7112)
			(layers "*.Cu" "*.Mask")
			(remove_unused_layers no)
			(net "USB_P1_F_DN1")
			(clearance 0.1778)
			(thermal_gap 0.1778)
		)
		(pad "3" thru_hole circle
			(at -0.899922 -4.329938)
			(size 1.0668 1.0668)
			(drill 0.7112)
			(layers "*.Cu" "*.Mask")
			(remove_unused_layers no)
			(net "USB_P1_F_DP1")
			(clearance 0.1778)
			(thermal_gap 0.1778)
		)
		(pad "4" thru_hole circle
			(at -0.899922 -1.829816)
			(size 1.0668 1.0668)
			(drill 0.7112)
			(layers "*.Cu" "*.Mask")
			(remove_unused_layers no)
			(net "GND")
			(clearance 0.1778)
			(thermal_gap 0.1778)
		)
		(pad "5" thru_hole circle
			(at 0.899922 -1.329944)
			(size 1.0668 1.0668)
			(drill 0.7112)
			(layers "*.Cu" "*.Mask")
			(remove_unused_layers no)
			(net "I2C_DEBUG_SCL")
			(clearance 0.1778)
			(thermal_gap 0.1778)
		)
		(pad "6" thru_hole circle
			(at 0.899922 -3.32994)
			(size 1.0668 1.0668)
			(drill 0.7112)
			(layers "*.Cu" "*.Mask")
			(remove_unused_layers no)
			(net "I2C_DEBUG_SDA")
			(clearance 0.1778)
			(thermal_gap 0.1778)
		)
		(pad "7" thru_hole circle
			(at 0.899922 -5.329936)
			(size 1.0668 1.0668)
			(drill 0.7112)
			(layers "*.Cu" "*.Mask")
			(remove_unused_layers no)
			(net "DEBUG_CARD_PRSNT")
			(clearance 0.1778)
			(thermal_gap 0.1778)
		)
		(pad "8" thru_hole circle
			(at 0.899922 -7.329932)
			(size 1.0668 1.0668)
			(drill 0.7112)
			(layers "*.Cu" "*.Mask")
			(remove_unused_layers no)
			(net "UART_IOM_TX")
			(clearance 0.1778)
			(thermal_gap 0.1778)
		)
		(pad "9" thru_hole circle
			(at 0.899922 -9.329928)
			(size 1.0668 1.0668)
			(drill 0.7112)
			(layers "*.Cu" "*.Mask")
			(remove_unused_layers no)
			(net "UART_IOM_RX")
			(clearance 0.1778)
			(thermal_gap 0.1778)
		)
		(pad "10" thru_hole oval
			(at -2.709926 -10.700004)
			(size 1.524 2.1336)
			(drill oval 0.8128 1.4224)
			(layers "*.Cu" "*.Mask")
			(remove_unused_layers no)
			(net "USB_CONN_GND")
			(clearance 0.1524)
			(thermal_gap 0.1524)
		)
		(pad "11" thru_hole oval
			(at -2.709926 0)
			(size 1.524 2.8194)
			(drill oval 0.8128 2.1082)
			(layers "*.Cu" "*.Mask")
			(remove_unused_layers no)
			(net "USB_CONN_GND")
			(clearance 0.1524)
			(thermal_gap 0.1524)
		)
		(pad "12" thru_hole oval
			(at 2.709926 0)
			(size 1.524 2.1336)
			(drill oval 0.8128 1.4224)
			(layers "*.Cu" "*.Mask")
			(remove_unused_layers no)
			(net "USB_CONN_GND")
			(clearance 0.1524)
			(thermal_gap 0.1524)
		)
		(pad "13" thru_hole oval
			(at 2.709926 -10.700004)
			(size 1.524 2.8194)
			(drill oval 0.8128 2.1082)
			(layers "*.Cu" "*.Mask")
			(remove_unused_layers no)
			(net "USB_CONN_GND")
			(clearance 0.1524)
			(thermal_gap 0.1524)
		)
	)
	(footprint ""
		(layer "F.Cu")
		(at 27.559 -124.206)
		(property "Reference" "R787"
			(at 0 0 0)
			(layer "F.SilkS")
			(hide yes)
			(effects
				(font
					(size 1.27 1.27)
				)
			)
		)
		(property "Value" "0R2J-2-GP"
			(at 0.064008 -3.993896 0)
			(unlocked yes)
			(layer "F.Fab")
			(hide yes)
			(effects
				(font
					(size 1.016 1.016)
					(thickness 0.1524)
				)
			)
		)
		(property "Device Type" "R402H16"
			(at 0.064008 -5.517896 0)
			(unlocked yes)
			(layer "F.Fab")
			(hide yes)
			(effects
				(font
					(size 1.016 1.016)
					(thickness 0.1524)
				)
			)
		)
		(duplicate_pad_numbers_are_jumpers no)
		(fp_line
			(start -0.508 -0.9398)
			(end -0.508 0.9398)
			(stroke
				(width 0.1524)
				(type default)
			)
			(layer "F.SilkS")
		)
		(fp_line
			(start 0.508 -0.9398)
			(end -0.508 -0.9398)
			(stroke
				(width 0.1524)
				(type default)
			)
			(layer "F.SilkS")
		)
		(fp_rect
			(start -0.508 0.9398)
			(end 0.508 -0.9398)
			(stroke
				(width 0)
				(type default)
			)
			(fill no)
			(layer "F.CrtYd")
		)
		(fp_rect
			(start -0.508 0.9398)
			(end 0.508 -0.9398)
			(stroke
				(width 0)
				(type default)
			)
			(fill no)
			(layer "F.Fab")
		)
		(pad "1" smd custom
			(at 0 -0.4445)
			(size 0.1397 0.1397)
			(layers "F.Cu" "F.Mask" "F.Paste")
			(net "FLA0_WP_N")
			(options
				(clearance outline)
				(anchor circle)
			)
			(primitives
				(gr_poly
					(pts
						(arc
							(start -0.1778 -0.2794)
							(mid -0.249642 -0.249642)
							(end -0.2794 -0.1778)
						)
						(arc
							(start -0.2794 0.1778)
							(mid -0.249642 0.249642)
							(end -0.1778 0.2794)
						)
						(arc
							(start 0.1778 0.2794)
							(mid 0.249642 0.249642)
							(end 0.2794 0.1778)
						)
						(arc
							(start 0.2794 -0.1778)
							(mid 0.249642 -0.249642)
							(end 0.1778 -0.2794)
						)
					)
					(width 0)
					(fill yes)
				)
			)
		)
		(pad "2" smd custom
			(at 0 0.4445)
			(size 0.1397 0.1397)
			(layers "F.Cu" "F.Mask" "F.Paste")
			(net "WP_DISABLE")
			(options
				(clearance outline)
				(anchor circle)
			)
			(primitives
				(gr_poly
					(pts
						(arc
							(start -0.1778 -0.2794)
							(mid -0.249642 -0.249642)
							(end -0.2794 -0.1778)
						)
						(arc
							(start -0.2794 0.1778)
							(mid -0.249642 0.249642)
							(end -0.1778 0.2794)
						)
						(arc
							(start 0.1778 0.2794)
							(mid 0.249642 0.249642)
							(end 0.2794 0.1778)
						)
						(arc
							(start 0.2794 -0.1778)
							(mid 0.249642 -0.249642)
							(end 0.1778 -0.2794)
						)
					)
					(width 0)
					(fill yes)
				)
			)
		)
	)
	(footprint ""
		(layer "F.Cu")
		(at 131.768088 -6.77672 -90)
		(property "Reference" "R450"
			(at 0 0 270)
			(layer "F.SilkS")
			(hide yes)
			(effects
				(font
					(size 1.27 1.27)
				)
			)
		)
		(property "Value" "10R5F-1-GP"
			(at 0 -8.9535 270)
			(unlocked yes)
			(layer "F.Fab")
			(hide yes)
			(effects
				(font
					(size 1.27 1.016)
					(thickness 0.1524)
				)
			)
		)
		(property "Device Type" "R805H24"
			(at 0 -10.6299 270)
			(unlocked yes)
			(layer "F.Fab")
			(hide yes)
			(effects
				(font
					(size 1.27 1.016)
					(thickness 0.1524)
				)
			)
		)
		(duplicate_pad_numbers_are_jumpers no)
		(fp_line
			(start -0.889 1.7018)
			(end 0.889 1.7018)
			(stroke
				(width 0.1524)
				(type default)
			)
			(layer "F.SilkS")
		)
		(fp_line
			(start 0.889 1.7018)
			(end 0.889 -0.508)
			(stroke
				(width 0.1524)
				(type default)
			)
			(layer "F.SilkS")
		)
		(fp_line
			(start -0.889 0.0762)
			(end -0.889 1.7018)
			(stroke
				(width 0.1524)
				(type default)
			)
			(layer "F.SilkS")
		)
		(fp_line
			(start -0.889 -1.7018)
			(end -0.889 0.2794)
			(stroke
				(width 0.1524)
				(type default)
			)
			(layer "F.SilkS")
		)
		(fp_line
			(start 0.889 -1.7018)
			(end 0.889 -0.381)
			(stroke
				(width 0.1524)
				(type default)
			)
			(layer "F.SilkS")
		)
		(fp_line
			(start 0.889 -1.7018)
			(end -0.889 -1.7018)
			(stroke
				(width 0.1524)
				(type default)
			)
			(layer "F.SilkS")
		)
		(fp_poly
			(pts
				(xy 0.9652 -1.778) (xy 0.9652 1.778) (xy -0.9652 1.778) (xy -0.9652 -1.778)
			)
			(stroke
				(width 0)
				(type default)
			)
			(fill no)
			(layer "F.CrtYd")
		)
		(fp_rect
			(start -0.9652 1.778)
			(end 0.9652 -1.778)
			(stroke
				(width 0)
				(type default)
			)
			(fill no)
			(layer "F.Fab")
		)
		(pad "1" smd rect
			(at 0 -0.9652 270)
			(size 1.397 1.143)
			(layers "F.Cu" "F.Mask" "F.Paste")
			(net "MB0_12V_CTRL_GATE1")
		)
		(pad "2" smd rect
			(at 0 0.9652 270)
			(size 1.397 1.143)
			(layers "F.Cu" "F.Mask" "F.Paste")
			(net "MB0_CM_GATE_R")
		)
	)
	(footprint ""
		(layer "F.Cu")
		(at 27.419046 -154.422856 -90)
		(property "Reference" "R770"
			(at 0 0 270)
			(layer "F.SilkS")
			(hide yes)
			(effects
				(font
					(size 1.27 1.27)
				)
			)
		)
		(property "Value" "0R2J-2-GP"
			(at 0.064008 -3.993896 270)
			(unlocked yes)
			(layer "F.Fab")
			(hide yes)
			(effects
				(font
					(size 1.016 1.016)
					(thickness 0.1524)
				)
			)
		)
		(property "Device Type" "R402H16"
			(at 0.064008 -5.517896 270)
			(unlocked yes)
			(layer "F.Fab")
			(hide yes)
			(effects
				(font
					(size 1.016 1.016)
					(thickness 0.1524)
				)
			)
		)
		(duplicate_pad_numbers_are_jumpers no)
		(fp_line
			(start -0.508 -0.9398)
			(end -0.508 0.9398)
			(stroke
				(width 0.1524)
				(type default)
			)
			(layer "F.SilkS")
		)
		(fp_line
			(start 0.508 -0.9398)
			(end -0.508 -0.9398)
			(stroke
				(width 0.1524)
				(type default)
			)
			(layer "F.SilkS")
		)
		(fp_rect
			(start -0.508 0.9398)
			(end 0.508 -0.9398)
			(stroke
				(width 0)
				(type default)
			)
			(fill no)
			(layer "F.CrtYd")
		)
		(fp_rect
			(start -0.508 0.9398)
			(end 0.508 -0.9398)
			(stroke
				(width 0)
				(type default)
			)
			(fill no)
			(layer "F.Fab")
		)
		(pad "1" smd custom
			(at 0 -0.4445 270)
			(size 0.1397 0.1397)
			(layers "F.Cu" "F.Mask" "F.Paste")
			(net "DEBUG_GPIO_BMC_R_3")
			(options
				(clearance outline)
				(anchor circle)
			)
			(primitives
				(gr_poly
					(pts
						(arc
							(start -0.1778 -0.2794)
							(mid -0.249642 -0.249642)
							(end -0.2794 -0.1778)
						)
						(arc
							(start -0.2794 0.1778)
							(mid -0.249642 0.249642)
							(end -0.1778 0.2794)
						)
						(arc
							(start 0.1778 0.2794)
							(mid 0.249642 0.249642)
							(end 0.2794 0.1778)
						)
						(arc
							(start 0.2794 -0.1778)
							(mid 0.249642 -0.249642)
							(end 0.1778 -0.2794)
						)
					)
					(width 0)
					(fill yes)
				)
			)
		)
		(pad "2" smd custom
			(at 0 0.4445 270)
			(size 0.1397 0.1397)
			(layers "F.Cu" "F.Mask" "F.Paste")
			(net "DEBUG_GPIO_BMC_3")
			(options
				(clearance outline)
				(anchor circle)
			)
			(primitives
				(gr_poly
					(pts
						(arc
							(start -0.1778 -0.2794)
							(mid -0.249642 -0.249642)
							(end -0.2794 -0.1778)
						)
						(arc
							(start -0.2794 0.1778)
							(mid -0.249642 0.249642)
							(end -0.1778 0.2794)
						)
						(arc
							(start 0.1778 0.2794)
							(mid 0.249642 0.249642)
							(end 0.2794 0.1778)
						)
						(arc
							(start 0.2794 -0.1778)
							(mid 0.249642 -0.249642)
							(end 0.1778 -0.2794)
						)
					)
					(width 0)
					(fill yes)
				)
			)
		)
	)
	(footprint ""
		(layer "F.Cu")
		(at 69.883782 -156.277818 180)
		(property "Reference" "X2"
			(at 0 0 180)
			(layer "F.SilkS")
			(hide yes)
			(effects
				(font
					(size 1.27 1.27)
				)
			)
		)
		(property "Value" "OSC-50MHZ-16-GP"
			(at 0.0127 -2.7686 180)
			(unlocked yes)
			(layer "F.Fab")
			(hide yes)
			(effects
				(font
					(size 1.016 1.016)
					(thickness 0.1524)
				)
			)
		)
		(property "Device Type" "OSC-3225-4P-3H48"
			(at 0.0127 -4.2926 180)
			(unlocked yes)
			(layer "F.Fab")
			(hide yes)
			(effects
				(font
					(size 1.016 1.016)
					(thickness 0.1524)
				)
			)
		)
		(duplicate_pad_numbers_are_jumpers no)
		(fp_line
			(start 2.1209 1.5367)
			(end -2.1209 1.5367)
			(stroke
				(width 0.1524)
				(type default)
			)
			(layer "F.SilkS")
		)
		(fp_line
			(start 2.1209 -1.5367)
			(end 2.1209 1.5367)
			(stroke
				(width 0.1524)
				(type default)
			)
			(layer "F.SilkS")
		)
		(fp_line
			(start -1.3208 1.6256)
			(end -2.2352 1.6256)
			(stroke
				(width 0.3302)
				(type default)
			)
			(layer "F.SilkS")
		)
		(fp_line
			(start -2.1209 1.5367)
			(end -2.1209 -1.5367)
			(stroke
				(width 0.1524)
				(type default)
			)
			(layer "F.SilkS")
		)
		(fp_line
			(start -2.1209 -1.5367)
			(end 2.1209 -1.5367)
			(stroke
				(width 0.1524)
				(type default)
			)
			(layer "F.SilkS")
		)
		(fp_line
			(start -2.2352 1.6256)
			(end -2.2352 0.635)
			(stroke
				(width 0.3302)
				(type default)
			)
			(layer "F.SilkS")
		)
		(fp_poly
			(pts
				(xy -0.982218 2.599182) (xy -2.252218 2.599182) (xy -1.617218 1.964182)
			)
			(stroke
				(width 0)
				(type default)
			)
			(fill yes)
			(layer "F.SilkS")
		)
		(fp_rect
			(start -1.6002 1.2446)
			(end 1.6002 -1.2446)
			(stroke
				(width 0)
				(type default)
			)
			(fill no)
			(layer "F.CrtYd")
		)
		(fp_poly
			(pts
				(xy -2.3749 1.7907) (xy -2.3749 -1.7907) (xy 2.3749 -1.7907) (xy 2.3749 1.7907) (xy 1.6002 1.7907)
				(xy 1.6002 -1.2446) (xy -1.6002 -1.2446) (xy -1.6002 1.2446) (xy 1.59512 1.2446) (xy 1.59512 1.7907)
			)
			(stroke
				(width 0)
				(type default)
			)
			(fill no)
			(layer "F.CrtYd")
		)
		(fp_rect
			(start -2.3749 1.7907)
			(end 2.3749 -1.7907)
			(stroke
				(width 0)
				(type default)
			)
			(fill no)
			(layer "F.Fab")
		)
		(pad "1" smd rect
			(at -1.171448 0.824992 180)
			(size 1.397 0.9144)
			(layers "F.Cu" "F.Mask" "F.Paste")
			(net "FM_OSC_50M_EN")
		)
		(pad "2" smd rect
			(at 1.171448 0.824992 180)
			(size 1.397 0.9144)
			(layers "F.Cu" "F.Mask" "F.Paste")
			(net "GND")
		)
		(pad "3" smd rect
			(at 1.171448 -0.824992 180)
			(size 1.397 0.9144)
			(layers "F.Cu" "F.Mask" "F.Paste")
			(net "50M_CLK_OUT")
		)
		(pad "4" smd rect
			(at -1.171448 -0.824992 180)
			(size 1.397 0.9144)
			(layers "F.Cu" "F.Mask" "F.Paste")
			(net "P3V3_STBY")
		)
		(zone
			(layer "F.Cu")
			(hatch none 0.5)
			(connect_pads
				(clearance 0)
			)
			(min_thickness 0.25)
			(keepout
				(tracks not_allowed)
				(vias allowed)
				(pads allowed)
				(copperpour not_allowed)
				(footprints allowed)
			)
			(placement
				(enabled no)
				(sheetname "")
			)
			(fill
				(thermal_gap 0.5)
				(thermal_bridge_width 0.5)
				(island_removal_mode 0)
			)
			(polygon
				(pts
					(xy 70.03161 -156.32049) (xy 69.735954 -156.32049) (xy 69.735954 -156.235146) (xy 70.03161 -156.235146)
				)
			)
		)
		(zone
			(layer "F.Cu")
			(hatch none 0.5)
			(connect_pads
				(clearance 0)
			)
			(min_thickness 0.25)
			(keepout
				(tracks allowed)
				(vias not_allowed)
				(pads allowed)
				(copperpour not_allowed)
				(footprints allowed)
			)
			(placement
				(enabled no)
				(sheetname "")
			)
			(fill
				(thermal_gap 0.5)
				(thermal_bridge_width 0.5)
				(island_removal_mode 0)
			)
			(polygon
				(pts
					(xy 70.35673 -157.56001) (xy 70.35673 -156.64561) (xy 71.75373 -156.64561) (xy 71.75373 -155.910026)
					(xy 70.35673 -155.910026) (xy 70.35673 -154.995626) (xy 69.410834 -154.995626) (xy 69.410834 -155.910026)
					(xy 68.013834 -155.910026) (xy 68.013834 -156.64561) (xy 69.410834 -156.64561) (xy 69.410834 -157.56001)
				)
			)
		)
	)
	(footprint ""
		(layer "F.Cu")
		(at 68.4276 -153.8732 -90)
		(property "Reference" "R306"
			(at 0 0 270)
			(layer "F.SilkS")
			(hide yes)
			(effects
				(font
					(size 1.27 1.27)
				)
			)
		)
		(property "Value" "33R2J-2-GP"
			(at 0.064008 -3.993896 270)
			(unlocked yes)
			(layer "F.Fab")
			(hide yes)
			(effects
				(font
					(size 1.016 1.016)
					(thickness 0.1524)
				)
			)
		)
		(property "Device Type" "R402H16"
			(at 0.064008 -5.517896 270)
			(unlocked yes)
			(layer "F.Fab")
			(hide yes)
			(effects
				(font
					(size 1.016 1.016)
					(thickness 0.1524)
				)
			)
		)
		(duplicate_pad_numbers_are_jumpers no)
		(fp_line
			(start -0.508 -0.9398)
			(end -0.508 0.9398)
			(stroke
				(width 0.1524)
				(type default)
			)
			(layer "F.SilkS")
		)
		(fp_line
			(start 0.508 -0.9398)
			(end -0.508 -0.9398)
			(stroke
				(width 0.1524)
				(type default)
			)
			(layer "F.SilkS")
		)
		(fp_rect
			(start -0.508 0.9398)
			(end 0.508 -0.9398)
			(stroke
				(width 0)
				(type default)
			)
			(fill no)
			(layer "F.CrtYd")
		)
		(fp_rect
			(start -0.508 0.9398)
			(end 0.508 -0.9398)
			(stroke
				(width 0)
				(type default)
			)
			(fill no)
			(layer "F.Fab")
		)
		(pad "1" smd custom
			(at 0 -0.4445 270)
			(size 0.1397 0.1397)
			(layers "F.Cu" "F.Mask" "F.Paste")
			(net "50M_CLK_OUT")
			(options
				(clearance outline)
				(anchor circle)
			)
			(primitives
				(gr_poly
					(pts
						(arc
							(start -0.1778 -0.2794)
							(mid -0.249642 -0.249642)
							(end -0.2794 -0.1778)
						)
						(arc
							(start -0.2794 0.1778)
							(mid -0.249642 0.249642)
							(end -0.1778 0.2794)
						)
						(arc
							(start 0.1778 0.2794)
							(mid 0.249642 0.249642)
							(end 0.2794 0.1778)
						)
						(arc
							(start 0.2794 -0.1778)
							(mid 0.249642 -0.249642)
							(end 0.1778 -0.2794)
						)
					)
					(width 0)
					(fill yes)
				)
			)
		)
		(pad "2" smd custom
			(at 0 0.4445 270)
			(size 0.1397 0.1397)
			(layers "F.Cu" "F.Mask" "F.Paste")
			(net "50M_CLK_OUT_R")
			(options
				(clearance outline)
				(anchor circle)
			)
			(primitives
				(gr_poly
					(pts
						(arc
							(start -0.1778 -0.2794)
							(mid -0.249642 -0.249642)
							(end -0.2794 -0.1778)
						)
						(arc
							(start -0.2794 0.1778)
							(mid -0.249642 0.249642)
							(end -0.1778 0.2794)
						)
						(arc
							(start 0.1778 0.2794)
							(mid 0.249642 0.249642)
							(end 0.2794 0.1778)
						)
						(arc
							(start 0.2794 -0.1778)
							(mid 0.249642 -0.249642)
							(end 0.1778 -0.2794)
						)
					)
					(width 0)
					(fill yes)
				)
			)
		)
	)
	(footprint ""
		(layer "F.Cu")
		(at 23.058882 -173.234096 90)
		(property "Reference" "C231"
			(at 0 0 90)
			(layer "F.SilkS")
			(hide yes)
			(effects
				(font
					(size 1.27 1.27)
				)
			)
		)
		(property "Value" "SC10U6D3V5KX-4GP"
			(at -0.0762 -6.1214 90)
			(unlocked yes)
			(layer "F.Fab")
			(hide yes)
			(effects
				(font
					(size 1.016 1.016)
					(thickness 0.1524)
				)
			)
		)
		(property "Device Type" "C805H58"
			(at -0.0762 -8.1534 90)
			(unlocked yes)
			(layer "F.Fab")
			(hide yes)
			(effects
				(font
					(size 1.016 1.016)
					(thickness 0.1524)
				)
			)
		)
		(duplicate_pad_numbers_are_jumpers no)
		(fp_line
			(start 0.635 0)
			(end -0.635 0)
			(stroke
				(width 0.508)
				(type default)
			)
			(layer "F.SilkS")
		)
		(fp_rect
			(start -0.9652 1.778)
			(end 0.9652 -1.778)
			(stroke
				(width 0)
				(type default)
			)
			(fill no)
			(layer "F.CrtYd")
		)
		(fp_poly
			(pts
				(xy -0.9652 -1.778) (xy 0.9652 -1.778) (xy 0.9652 1.778) (xy -0.9652 1.778)
			)
			(stroke
				(width 0)
				(type default)
			)
			(fill no)
			(layer "F.Fab")
		)
		(pad "1" smd rect
			(at 0 -0.9652 90)
			(size 1.397 1.143)
			(layers "F.Cu" "F.Mask" "F.Paste")
			(net "P1V8_STBY")
		)
		(pad "2" smd rect
			(at 0 0.9652 90)
			(size 1.397 1.143)
			(layers "F.Cu" "F.Mask" "F.Paste")
			(net "GND")
		)
	)
	(footprint ""
		(layer "F.Cu")
		(at 73.9902 -140.0302 -90)
		(property "Reference" "R58"
			(at 0 0 270)
			(layer "F.SilkS")
			(hide yes)
			(effects
				(font
					(size 1.27 1.27)
				)
			)
		)
		(property "Value" "33R2F-3-GP"
			(at 0.064008 -3.993896 270)
			(unlocked yes)
			(layer "F.Fab")
			(hide yes)
			(effects
				(font
					(size 1.016 1.016)
					(thickness 0.1524)
				)
			)
		)
		(property "Device Type" "R402H16"
			(at 0.064008 -5.517896 270)
			(unlocked yes)
			(layer "F.Fab")
			(hide yes)
			(effects
				(font
					(size 1.016 1.016)
					(thickness 0.1524)
				)
			)
		)
		(duplicate_pad_numbers_are_jumpers no)
		(fp_line
			(start -0.508 -0.9398)
			(end -0.508 0.9398)
			(stroke
				(width 0.1524)
				(type default)
			)
			(layer "F.SilkS")
		)
		(fp_line
			(start 0.508 -0.9398)
			(end -0.508 -0.9398)
			(stroke
				(width 0.1524)
				(type default)
			)
			(layer "F.SilkS")
		)
		(fp_rect
			(start -0.508 0.9398)
			(end 0.508 -0.9398)
			(stroke
				(width 0)
				(type default)
			)
			(fill no)
			(layer "F.CrtYd")
		)
		(fp_rect
			(start -0.508 0.9398)
			(end 0.508 -0.9398)
			(stroke
				(width 0)
				(type default)
			)
			(fill no)
			(layer "F.Fab")
		)
		(pad "1" smd custom
			(at 0 -0.4445 270)
			(size 0.1397 0.1397)
			(layers "F.Cu" "F.Mask" "F.Paste")
			(net "SYS_RST_BTN_IN_N")
			(options
				(clearance outline)
				(anchor circle)
			)
			(primitives
				(gr_poly
					(pts
						(arc
							(start -0.1778 -0.2794)
							(mid -0.249642 -0.249642)
							(end -0.2794 -0.1778)
						)
						(arc
							(start -0.2794 0.1778)
							(mid -0.249642 0.249642)
							(end -0.1778 0.2794)
						)
						(arc
							(start 0.1778 0.2794)
							(mid 0.249642 0.249642)
							(end 0.2794 0.1778)
						)
						(arc
							(start 0.2794 -0.1778)
							(mid 0.249642 -0.249642)
							(end 0.1778 -0.2794)
						)
					)
					(width 0)
					(fill yes)
				)
			)
		)
		(pad "2" smd custom
			(at 0 0.4445 270)
			(size 0.1397 0.1397)
			(layers "F.Cu" "F.Mask" "F.Paste")
			(net "FP_RESET_RC_N")
			(options
				(clearance outline)
				(anchor circle)
			)
			(primitives
				(gr_poly
					(pts
						(arc
							(start -0.1778 -0.2794)
							(mid -0.249642 -0.249642)
							(end -0.2794 -0.1778)
						)
						(arc
							(start -0.2794 0.1778)
							(mid -0.249642 0.249642)
							(end -0.1778 0.2794)
						)
						(arc
							(start 0.1778 0.2794)
							(mid 0.249642 0.249642)
							(end 0.2794 0.1778)
						)
						(arc
							(start 0.2794 -0.1778)
							(mid 0.249642 -0.249642)
							(end 0.1778 -0.2794)
						)
					)
					(width 0)
					(fill yes)
				)
			)
		)
	)
	(footprint ""
		(layer "F.Cu")
		(at 215.17864 -100.583492 90)
		(property "Reference" "R842"
			(at 0 0 90)
			(layer "F.SilkS")
			(hide yes)
			(effects
				(font
					(size 1.27 1.27)
				)
			)
		)
		(property "Value" "309KR2F-GP"
			(at 0.064008 -3.993896 90)
			(unlocked yes)
			(layer "F.Fab")
			(hide yes)
			(effects
				(font
					(size 1.016 1.016)
					(thickness 0.1524)
				)
			)
		)
		(property "Device Type" "R402H16"
			(at 0.064008 -5.517896 90)
			(unlocked yes)
			(layer "F.Fab")
			(hide yes)
			(effects
				(font
					(size 1.016 1.016)
					(thickness 0.1524)
				)
			)
		)
		(duplicate_pad_numbers_are_jumpers no)
		(fp_line
			(start 0.508 -0.9398)
			(end -0.508 -0.9398)
			(stroke
				(width 0.1524)
				(type default)
			)
			(layer "F.SilkS")
		)
		(fp_line
			(start -0.508 -0.9398)
			(end -0.508 0.9398)
			(stroke
				(width 0.1524)
				(type default)
			)
			(layer "F.SilkS")
		)
		(fp_rect
			(start -0.508 0.9398)
			(end 0.508 -0.9398)
			(stroke
				(width 0)
				(type default)
			)
			(fill no)
			(layer "F.CrtYd")
		)
		(fp_rect
			(start -0.508 0.9398)
			(end 0.508 -0.9398)
			(stroke
				(width 0)
				(type default)
			)
			(fill no)
			(layer "F.Fab")
		)
		(pad "1" smd custom
			(at 0 -0.4445 90)
			(size 0.1397 0.1397)
			(layers "F.Cu" "F.Mask" "F.Paste")
			(net "AGND_P3V3_M2")
			(options
				(clearance outline)
				(anchor circle)
			)
			(primitives
				(gr_poly
					(pts
						(arc
							(start -0.1778 -0.2794)
							(mid -0.249642 -0.249642)
							(end -0.2794 -0.1778)
						)
						(arc
							(start -0.2794 0.1778)
							(mid -0.249642 0.249642)
							(end -0.1778 0.2794)
						)
						(arc
							(start 0.1778 0.2794)
							(mid 0.249642 0.249642)
							(end 0.2794 0.1778)
						)
						(arc
							(start 0.2794 -0.1778)
							(mid 0.249642 -0.249642)
							(end 0.1778 -0.2794)
						)
					)
					(width 0)
					(fill yes)
				)
			)
		)
		(pad "2" smd custom
			(at 0 0.4445 90)
			(size 0.1397 0.1397)
			(layers "F.Cu" "F.Mask" "F.Paste")
			(net "P3V3_M2_RF")
			(options
				(clearance outline)
				(anchor circle)
			)
			(primitives
				(gr_poly
					(pts
						(arc
							(start -0.1778 -0.2794)
							(mid -0.249642 -0.249642)
							(end -0.2794 -0.1778)
						)
						(arc
							(start -0.2794 0.1778)
							(mid -0.249642 0.249642)
							(end -0.1778 0.2794)
						)
						(arc
							(start 0.1778 0.2794)
							(mid 0.249642 0.249642)
							(end 0.2794 0.1778)
						)
						(arc
							(start 0.2794 -0.1778)
							(mid 0.249642 -0.249642)
							(end 0.1778 -0.2794)
						)
					)
					(width 0)
					(fill yes)
				)
			)
		)
	)
	(footprint ""
		(layer "F.Cu")
		(at 69.51726 -183.78678 -90)
		(property "Reference" "R510"
			(at 0 0 270)
			(layer "F.SilkS")
			(hide yes)
			(effects
				(font
					(size 1.27 1.27)
				)
			)
		)
		(property "Value" "0R2J-2-GP"
			(at 0.064008 -3.993896 270)
			(unlocked yes)
			(layer "F.Fab")
			(hide yes)
			(effects
				(font
					(size 1.016 1.016)
					(thickness 0.1524)
				)
			)
		)
		(property "Device Type" "R402H16"
			(at 0.064008 -5.517896 270)
			(unlocked yes)
			(layer "F.Fab")
			(hide yes)
			(effects
				(font
					(size 1.016 1.016)
					(thickness 0.1524)
				)
			)
		)
		(duplicate_pad_numbers_are_jumpers no)
		(fp_line
			(start -0.508 -0.9398)
			(end -0.508 0.9398)
			(stroke
				(width 0.1524)
				(type default)
			)
			(layer "F.SilkS")
		)
		(fp_line
			(start 0.508 -0.9398)
			(end -0.508 -0.9398)
			(stroke
				(width 0.1524)
				(type default)
			)
			(layer "F.SilkS")
		)
		(fp_rect
			(start -0.508 0.9398)
			(end 0.508 -0.9398)
			(stroke
				(width 0)
				(type default)
			)
			(fill no)
			(layer "F.CrtYd")
		)
		(fp_rect
			(start -0.508 0.9398)
			(end 0.508 -0.9398)
			(stroke
				(width 0)
				(type default)
			)
			(fill no)
			(layer "F.Fab")
		)
		(pad "1" smd custom
			(at 0 -0.4445 270)
			(size 0.1397 0.1397)
			(layers "F.Cu" "F.Mask" "F.Paste")
			(net "TPS74801_P2V5_STBY_EN")
			(options
				(clearance outline)
				(anchor circle)
			)
			(primitives
				(gr_poly
					(pts
						(arc
							(start -0.1778 -0.2794)
							(mid -0.249642 -0.249642)
							(end -0.2794 -0.1778)
						)
						(arc
							(start -0.2794 0.1778)
							(mid -0.249642 0.249642)
							(end -0.1778 0.2794)
						)
						(arc
							(start 0.1778 0.2794)
							(mid 0.249642 0.249642)
							(end 0.2794 0.1778)
						)
						(arc
							(start 0.2794 -0.1778)
							(mid 0.249642 -0.249642)
							(end 0.1778 -0.2794)
						)
					)
					(width 0)
					(fill yes)
				)
			)
		)
		(pad "2" smd custom
			(at 0 0.4445 270)
			(size 0.1397 0.1397)
			(layers "F.Cu" "F.Mask" "F.Paste")
			(net "PWRGD_P3V3_STBY")
			(options
				(clearance outline)
				(anchor circle)
			)
			(primitives
				(gr_poly
					(pts
						(arc
							(start -0.1778 -0.2794)
							(mid -0.249642 -0.249642)
							(end -0.2794 -0.1778)
						)
						(arc
							(start -0.2794 0.1778)
							(mid -0.249642 0.249642)
							(end -0.1778 0.2794)
						)
						(arc
							(start 0.1778 0.2794)
							(mid 0.249642 0.249642)
							(end 0.2794 0.1778)
						)
						(arc
							(start 0.2794 -0.1778)
							(mid 0.249642 -0.249642)
							(end 0.1778 -0.2794)
						)
					)
					(width 0)
					(fill yes)
				)
			)
		)
	)
	(footprint ""
		(layer "F.Cu")
		(at 46.970696 -124.827792 180)
		(property "Reference" "R296"
			(at 0 0 180)
			(layer "F.SilkS")
			(hide yes)
			(effects
				(font
					(size 1.27 1.27)
				)
			)
		)
		(property "Value" "2K2R2F-GP"
			(at 0.064008 -3.993896 180)
			(unlocked yes)
			(layer "F.Fab")
			(hide yes)
			(effects
				(font
					(size 1.016 1.016)
					(thickness 0.1524)
				)
			)
		)
		(property "Device Type" "R402H16"
			(at 0.064008 -5.517896 180)
			(unlocked yes)
			(layer "F.Fab")
			(hide yes)
			(effects
				(font
					(size 1.016 1.016)
					(thickness 0.1524)
				)
			)
		)
		(duplicate_pad_numbers_are_jumpers no)
		(fp_line
			(start 0.508 -0.9398)
			(end -0.508 -0.9398)
			(stroke
				(width 0.1524)
				(type default)
			)
			(layer "F.SilkS")
		)
		(fp_line
			(start -0.508 -0.9398)
			(end -0.508 0.9398)
			(stroke
				(width 0.1524)
				(type default)
			)
			(layer "F.SilkS")
		)
		(fp_rect
			(start -0.508 0.9398)
			(end 0.508 -0.9398)
			(stroke
				(width 0)
				(type default)
			)
			(fill no)
			(layer "F.CrtYd")
		)
		(fp_rect
			(start -0.508 0.9398)
			(end 0.508 -0.9398)
			(stroke
				(width 0)
				(type default)
			)
			(fill no)
			(layer "F.Fab")
		)
		(pad "1" smd custom
			(at 0 -0.4445 180)
			(size 0.1397 0.1397)
			(layers "F.Cu" "F.Mask" "F.Paste")
			(net "BMC_SMB2_CLK")
			(options
				(clearance outline)
				(anchor circle)
			)
			(primitives
				(gr_poly
					(pts
						(arc
							(start -0.1778 -0.2794)
							(mid -0.249642 -0.249642)
							(end -0.2794 -0.1778)
						)
						(arc
							(start -0.2794 0.1778)
							(mid -0.249642 0.249642)
							(end -0.1778 0.2794)
						)
						(arc
							(start 0.1778 0.2794)
							(mid 0.249642 0.249642)
							(end 0.2794 0.1778)
						)
						(arc
							(start 0.2794 -0.1778)
							(mid 0.249642 -0.249642)
							(end 0.1778 -0.2794)
						)
					)
					(width 0)
					(fill yes)
				)
			)
		)
		(pad "2" smd custom
			(at 0 0.4445 180)
			(size 0.1397 0.1397)
			(layers "F.Cu" "F.Mask" "F.Paste")
			(net "P3V3_STBY")
			(options
				(clearance outline)
				(anchor circle)
			)
			(primitives
				(gr_poly
					(pts
						(arc
							(start -0.1778 -0.2794)
							(mid -0.249642 -0.249642)
							(end -0.2794 -0.1778)
						)
						(arc
							(start -0.2794 0.1778)
							(mid -0.249642 0.249642)
							(end -0.1778 0.2794)
						)
						(arc
							(start 0.1778 0.2794)
							(mid 0.249642 0.249642)
							(end 0.2794 0.1778)
						)
						(arc
							(start 0.2794 -0.1778)
							(mid 0.249642 -0.249642)
							(end 0.1778 -0.2794)
						)
					)
					(width 0)
					(fill yes)
				)
			)
		)
	)
	(footprint ""
		(layer "F.Cu")
		(at 90.98407 -59.32551 90)
		(property "Reference" "D4"
			(at 0 0 90)
			(layer "F.SilkS")
			(hide yes)
			(effects
				(font
					(size 1.27 1.27)
				)
			)
		)
		(property "Value" "SMF15A-GP"
			(at -2.0955 1.2192 90)
			(unlocked yes)
			(layer "F.Fab")
			(hide yes)
			(effects
				(font
					(size 1.016 1.016)
					(thickness 0.1524)
				)
			)
		)
		(property "Device Type" "SOD123AK-2H43"
			(at -2.0955 -0.3048 90)
			(unlocked yes)
			(layer "F.Fab")
			(hide yes)
			(effects
				(font
					(size 1.016 1.016)
					(thickness 0.1524)
				)
			)
		)
		(duplicate_pad_numbers_are_jumpers no)
		(fp_line
			(start 1.1557 -2.7686)
			(end -1.1557 -2.7686)
			(stroke
				(width 0.1524)
				(type default)
			)
			(layer "F.SilkS")
		)
		(fp_line
			(start -1.1557 -2.7686)
			(end -1.1557 2.7686)
			(stroke
				(width 0.1524)
				(type default)
			)
			(layer "F.SilkS")
		)
		(fp_line
			(start 1.1557 2.7686)
			(end 1.1557 -2.7686)
			(stroke
				(width 0.1524)
				(type default)
			)
			(layer "F.SilkS")
		)
		(fp_line
			(start -1.1557 2.7686)
			(end 1.1557 2.7686)
			(stroke
				(width 0.1524)
				(type default)
			)
			(layer "F.SilkS")
		)
		(fp_line
			(start 1.1557 2.921)
			(end -1.1557 2.921)
			(stroke
				(width 0.508)
				(type default)
			)
			(layer "F.SilkS")
		)
		(fp_poly
			(pts
				(xy -0.4572 1.8669) (xy -0.4572 1.397) (xy -0.9017 1.397) (xy -0.9017 -1.397) (xy -0.4572 -1.397)
				(xy -0.4572 -1.8669) (xy 0.4572 -1.8669) (xy 0.4572 -1.397) (xy 0.9017 -1.397) (xy 0.9017 1.397)
				(xy 0.4572 1.397) (xy 0.4572 1.8669)
			)
			(stroke
				(width 0)
				(type default)
			)
			(fill no)
			(layer "F.CrtYd")
		)
		(fp_poly
			(pts
				(xy -1.4097 2.8448) (xy -1.4097 -2.8448) (xy 1.4097 -2.8448) (xy 1.4097 1.3716) (xy 0.9017 1.3716)
				(xy 0.9017 -1.397) (xy 0.4572 -1.397) (xy 0.4572 -1.8669) (xy -0.4572 -1.8669) (xy -0.4572 -1.397)
				(xy -0.9017 -1.397) (xy -0.9017 1.397) (xy -0.4572 1.397) (xy -0.4572 1.8669) (xy 0.4572 1.8669)
				(xy 0.4572 1.397) (xy 0.9017 1.397) (xy 0.9017 1.3843) (xy 1.4097 1.3843) (xy 1.4097 2.8448)
			)
			(stroke
				(width 0)
				(type default)
			)
			(fill no)
			(layer "F.CrtYd")
		)
		(fp_rect
			(start -1.4097 2.8448)
			(end 1.4097 -2.8448)
			(stroke
				(width 0)
				(type default)
			)
			(fill no)
			(layer "F.Fab")
		)
		(pad "A" smd rect
			(at 0 -1.75768 90)
			(size 1.143 1.4986)
			(layers "F.Cu" "F.Mask" "F.Paste")
			(net "P3V3_EN_R")
		)
		(pad "K" smd rect
			(at 0 1.75768 90)
			(size 1.143 1.4986)
			(layers "F.Cu" "F.Mask" "F.Paste")
			(net "P3V3_EN")
		)
	)
	(footprint ""
		(layer "F.Cu")
		(at 71.92518 -161.8615 90)
		(property "Reference" "C240"
			(at 0 0 90)
			(layer "F.SilkS")
			(hide yes)
			(effects
				(font
					(size 1.27 1.27)
				)
			)
		)
		(property "Value" "SC470P50V2KX-3GP"
			(at 1.1811 -2.7051 90)
			(unlocked yes)
			(layer "F.Fab")
			(hide yes)
			(effects
				(font
					(size 1.016 1.016)
					(thickness 0.1524)
				)
			)
		)
		(property "Device Type" "C402H22"
			(at 1.1811 -4.2291 90)
			(unlocked yes)
			(layer "F.Fab")
			(hide yes)
			(effects
				(font
					(size 1.016 1.016)
					(thickness 0.1524)
				)
			)
		)
		(duplicate_pad_numbers_are_jumpers no)
		(fp_rect
			(start -0.4318 0.9525)
			(end 0.4318 -0.9525)
			(stroke
				(width 0)
				(type default)
			)
			(fill no)
			(layer "F.CrtYd")
		)
		(fp_rect
			(start -0.4318 0.9525)
			(end 0.4318 -0.9525)
			(stroke
				(width 0)
				(type default)
			)
			(fill no)
			(layer "F.Fab")
		)
		(pad "1" smd custom
			(at 0 -0.4445 90)
			(size 0.1524 0.1524)
			(layers "F.Cu" "F.Mask" "F.Paste")
			(net "GND")
			(options
				(clearance outline)
				(anchor circle)
			)
			(primitives
				(gr_poly
					(pts
						(arc
							(start 0.3048 -0.2032)
							(mid 0.275042 -0.275042)
							(end 0.2032 -0.3048)
						)
						(arc
							(start -0.2032 -0.3048)
							(mid -0.275042 -0.275042)
							(end -0.3048 -0.2032)
						)
						(arc
							(start -0.3048 0.2032)
							(mid -0.275042 0.275042)
							(end -0.2032 0.3048)
						)
						(arc
							(start 0.2032 0.3048)
							(mid 0.275042 0.275042)
							(end 0.3048 0.2032)
						)
					)
					(width 0)
					(fill yes)
				)
			)
		)
		(pad "2" smd custom
			(at 0 0.4445 90)
			(size 0.1524 0.1524)
			(layers "F.Cu" "F.Mask" "F.Paste")
			(net "TPS74801_P1V15_STBY_SS")
			(options
				(clearance outline)
				(anchor circle)
			)
			(primitives
				(gr_poly
					(pts
						(arc
							(start 0.3048 -0.2032)
							(mid 0.275042 -0.275042)
							(end 0.2032 -0.3048)
						)
						(arc
							(start -0.2032 -0.3048)
							(mid -0.275042 -0.275042)
							(end -0.3048 -0.2032)
						)
						(arc
							(start -0.3048 0.2032)
							(mid -0.275042 0.275042)
							(end -0.2032 0.3048)
						)
						(arc
							(start 0.2032 0.3048)
							(mid 0.275042 0.275042)
							(end 0.3048 0.2032)
						)
					)
					(width 0)
					(fill yes)
				)
			)
		)
	)
	(footprint ""
		(layer "F.Cu")
		(at 206.756 -139.573 -135)
		(property "Reference" "VIA51"
			(at 0 0 225)
			(layer "F.SilkS")
			(hide yes)
			(effects
				(font
					(size 1.27 1.27)
				)
			)
		)
		(property "Value" "85OHM-8L-1D6MM-L16L18-GP"
			(at 4.064105 0.609655 225)
			(unlocked yes)
			(layer "F.Fab")
			(hide yes)
			(effects
				(font
					(size 1.016 1.016)
					(thickness 0.1524)
				)
			)
		)
		(property "Device Type" "VIA-PCIE-4P-368076"
			(at 4.064105 -0.914474 225)
			(unlocked yes)
			(layer "F.Fab")
			(hide yes)
			(effects
				(font
					(size 1.016 1.016)
					(thickness 0.1524)
				)
			)
		)
		(duplicate_pad_numbers_are_jumpers no)
		(fp_poly
			(pts
				(xy -1.841491 -0.381057) (xy 1.841509 -0.381058) (xy 1.841508 0.380942) (xy -1.841491 0.380942)
			)
			(stroke
				(width 0)
				(type default)
			)
			(fill no)
			(layer "F.CrtYd")
		)
		(fp_poly
			(pts
				(xy -1.841491 -0.381057) (xy 1.841509 -0.381058) (xy 1.841508 0.380942) (xy -1.841491 0.380942)
			)
			(stroke
				(width 0)
				(type default)
			)
			(fill no)
			(layer "F.Fab")
		)
		(pad "1" thru_hole circle
			(at -1.460499 0 225)
			(size 0.508 0.508)
			(drill 0.254)
			(layers "*.Cu" "*.Mask")
			(remove_unused_layers no)
			(net "GND")
			(clearance 0.127)
			(thermal_gap 0.127)
		)
		(pad "2" thru_hole circle
			(at -0.4445 0 225)
			(size 0.508 0.508)
			(drill 0.254)
			(layers "*.Cu" "*.Mask")
			(remove_unused_layers no)
			(net "PCIE_IOM_TO_COMP_8_DP")
			(clearance 0.127)
			(thermal_gap 0.127)
		)
		(pad "3" thru_hole circle
			(at 0.4445 0 225)
			(size 0.508 0.508)
			(drill 0.254)
			(layers "*.Cu" "*.Mask")
			(remove_unused_layers no)
			(net "PCIE_IOM_TO_COMP_8_DN")
			(clearance 0.127)
			(thermal_gap 0.127)
		)
		(pad "4" thru_hole circle
			(at 1.460499 0 225)
			(size 0.508 0.508)
			(drill 0.254)
			(layers "*.Cu" "*.Mask")
			(remove_unused_layers no)
			(net "GND")
			(clearance 0.127)
			(thermal_gap 0.127)
		)
	)
	(footprint ""
		(layer "F.Cu")
		(at 183.8452 -7.9756 180)
		(property "Reference" "R411"
			(at 0 0 180)
			(layer "F.SilkS")
			(hide yes)
			(effects
				(font
					(size 1.27 1.27)
				)
			)
		)
		(property "Value" "0R2J-2-GP"
			(at 0.064008 -3.993896 180)
			(unlocked yes)
			(layer "F.Fab")
			(hide yes)
			(effects
				(font
					(size 1.016 1.016)
					(thickness 0.1524)
				)
			)
		)
		(property "Device Type" "R402H16"
			(at 0.064008 -5.517896 180)
			(unlocked yes)
			(layer "F.Fab")
			(hide yes)
			(effects
				(font
					(size 1.016 1.016)
					(thickness 0.1524)
				)
			)
		)
		(duplicate_pad_numbers_are_jumpers no)
		(fp_line
			(start 0.508 -0.9398)
			(end -0.508 -0.9398)
			(stroke
				(width 0.1524)
				(type default)
			)
			(layer "F.SilkS")
		)
		(fp_line
			(start -0.508 -0.9398)
			(end -0.508 0.9398)
			(stroke
				(width 0.1524)
				(type default)
			)
			(layer "F.SilkS")
		)
		(fp_rect
			(start -0.508 0.9398)
			(end 0.508 -0.9398)
			(stroke
				(width 0)
				(type default)
			)
			(fill no)
			(layer "F.CrtYd")
		)
		(fp_rect
			(start -0.508 0.9398)
			(end 0.508 -0.9398)
			(stroke
				(width 0)
				(type default)
			)
			(fill no)
			(layer "F.Fab")
		)
		(pad "1" smd custom
			(at 0 -0.4445 180)
			(size 0.1397 0.1397)
			(layers "F.Cu" "F.Mask" "F.Paste")
			(net "BMC_ML_PWR_YELLOW_LED_R")
			(options
				(clearance outline)
				(anchor circle)
			)
			(primitives
				(gr_poly
					(pts
						(arc
							(start -0.1778 -0.2794)
							(mid -0.249642 -0.249642)
							(end -0.2794 -0.1778)
						)
						(arc
							(start -0.2794 0.1778)
							(mid -0.249642 0.249642)
							(end -0.1778 0.2794)
						)
						(arc
							(start 0.1778 0.2794)
							(mid 0.249642 0.249642)
							(end 0.2794 0.1778)
						)
						(arc
							(start 0.2794 -0.1778)
							(mid 0.249642 -0.249642)
							(end 0.1778 -0.2794)
						)
					)
					(width 0)
					(fill yes)
				)
			)
		)
		(pad "2" smd custom
			(at 0 0.4445 180)
			(size 0.1397 0.1397)
			(layers "F.Cu" "F.Mask" "F.Paste")
			(net "BMC_ML_PWR_YELLOW_LED")
			(options
				(clearance outline)
				(anchor circle)
			)
			(primitives
				(gr_poly
					(pts
						(arc
							(start -0.1778 -0.2794)
							(mid -0.249642 -0.249642)
							(end -0.2794 -0.1778)
						)
						(arc
							(start -0.2794 0.1778)
							(mid -0.249642 0.249642)
							(end -0.1778 0.2794)
						)
						(arc
							(start 0.1778 0.2794)
							(mid 0.249642 0.249642)
							(end 0.2794 0.1778)
						)
						(arc
							(start 0.2794 -0.1778)
							(mid 0.249642 -0.249642)
							(end 0.1778 -0.2794)
						)
					)
					(width 0)
					(fill yes)
				)
			)
		)
	)
	(footprint ""
		(layer "F.Cu")
		(at 112.638078 -13.13561 180)
		(property "Reference" "R457"
			(at 0 0 180)
			(layer "F.SilkS")
			(hide yes)
			(effects
				(font
					(size 1.27 1.27)
				)
			)
		)
		(property "Value" "100KR2J-4-GP"
			(at 0.064008 -3.993896 180)
			(unlocked yes)
			(layer "F.Fab")
			(hide yes)
			(effects
				(font
					(size 1.016 1.016)
					(thickness 0.1524)
				)
			)
		)
		(property "Device Type" "R402H15"
			(at 0.064008 -5.517896 180)
			(unlocked yes)
			(layer "F.Fab")
			(hide yes)
			(effects
				(font
					(size 1.016 1.016)
					(thickness 0.1524)
				)
			)
		)
		(duplicate_pad_numbers_are_jumpers no)
		(fp_line
			(start 0.508 -0.9398)
			(end -0.508 -0.9398)
			(stroke
				(width 0.1524)
				(type default)
			)
			(layer "F.SilkS")
		)
		(fp_line
			(start -0.508 -0.9398)
			(end -0.508 0.9398)
			(stroke
				(width 0.1524)
				(type default)
			)
			(layer "F.SilkS")
		)
		(fp_rect
			(start -0.508 0.9398)
			(end 0.508 -0.9398)
			(stroke
				(width 0)
				(type default)
			)
			(fill no)
			(layer "F.CrtYd")
		)
		(fp_rect
			(start -0.508 0.9398)
			(end 0.508 -0.9398)
			(stroke
				(width 0)
				(type default)
			)
			(fill no)
			(layer "F.Fab")
		)
		(pad "1" smd custom
			(at 0 -0.4445 180)
			(size 0.1397 0.1397)
			(layers "F.Cu" "F.Mask" "F.Paste")
			(net "MB0_VCAP_R")
			(options
				(clearance outline)
				(anchor circle)
			)
			(primitives
				(gr_poly
					(pts
						(arc
							(start -0.1778 -0.2794)
							(mid -0.249642 -0.249642)
							(end -0.2794 -0.1778)
						)
						(arc
							(start -0.2794 0.1778)
							(mid -0.249642 0.249642)
							(end -0.1778 0.2794)
						)
						(arc
							(start 0.1778 0.2794)
							(mid 0.249642 0.249642)
							(end 0.2794 0.1778)
						)
						(arc
							(start 0.2794 -0.1778)
							(mid 0.249642 -0.249642)
							(end 0.1778 -0.2794)
						)
					)
					(width 0)
					(fill yes)
				)
			)
		)
		(pad "2" smd custom
			(at 0 0.4445 180)
			(size 0.1397 0.1397)
			(layers "F.Cu" "F.Mask" "F.Paste")
			(net "MB0_PSET_R")
			(options
				(clearance outline)
				(anchor circle)
			)
			(primitives
				(gr_poly
					(pts
						(arc
							(start -0.1778 -0.2794)
							(mid -0.249642 -0.249642)
							(end -0.2794 -0.1778)
						)
						(arc
							(start -0.2794 0.1778)
							(mid -0.249642 0.249642)
							(end -0.1778 0.2794)
						)
						(arc
							(start 0.1778 0.2794)
							(mid 0.249642 0.249642)
							(end 0.2794 0.1778)
						)
						(arc
							(start 0.2794 -0.1778)
							(mid 0.249642 -0.249642)
							(end 0.1778 -0.2794)
						)
					)
					(width 0)
					(fill yes)
				)
			)
		)
	)
	(footprint ""
		(layer "F.Cu")
		(at 58.252868 -131.23037)
		(property "Reference" "R278"
			(at 0 0 0)
			(layer "F.SilkS")
			(hide yes)
			(effects
				(font
					(size 1.27 1.27)
				)
			)
		)
		(property "Value" "0R2J-2-GP"
			(at 0.064008 -3.993896 0)
			(unlocked yes)
			(layer "F.Fab")
			(hide yes)
			(effects
				(font
					(size 1.016 1.016)
					(thickness 0.1524)
				)
			)
		)
		(property "Device Type" "R402H16"
			(at 0.064008 -5.517896 0)
			(unlocked yes)
			(layer "F.Fab")
			(hide yes)
			(effects
				(font
					(size 1.016 1.016)
					(thickness 0.1524)
				)
			)
		)
		(duplicate_pad_numbers_are_jumpers no)
		(fp_line
			(start -0.508 -0.9398)
			(end -0.508 0.9398)
			(stroke
				(width 0.1524)
				(type default)
			)
			(layer "F.SilkS")
		)
		(fp_line
			(start 0.508 -0.9398)
			(end -0.508 -0.9398)
			(stroke
				(width 0.1524)
				(type default)
			)
			(layer "F.SilkS")
		)
		(fp_rect
			(start -0.508 0.9398)
			(end 0.508 -0.9398)
			(stroke
				(width 0)
				(type default)
			)
			(fill no)
			(layer "F.CrtYd")
		)
		(fp_rect
			(start -0.508 0.9398)
			(end 0.508 -0.9398)
			(stroke
				(width 0)
				(type default)
			)
			(fill no)
			(layer "F.Fab")
		)
		(pad "1" smd custom
			(at 0 -0.4445)
			(size 0.1397 0.1397)
			(layers "F.Cu" "F.Mask" "F.Paste")
			(net "RSTBTN_OUT_N_R")
			(options
				(clearance outline)
				(anchor circle)
			)
			(primitives
				(gr_poly
					(pts
						(arc
							(start -0.1778 -0.2794)
							(mid -0.249642 -0.249642)
							(end -0.2794 -0.1778)
						)
						(arc
							(start -0.2794 0.1778)
							(mid -0.249642 0.249642)
							(end -0.1778 0.2794)
						)
						(arc
							(start 0.1778 0.2794)
							(mid 0.249642 0.249642)
							(end 0.2794 0.1778)
						)
						(arc
							(start 0.2794 -0.1778)
							(mid 0.249642 -0.249642)
							(end 0.1778 -0.2794)
						)
					)
					(width 0)
					(fill yes)
				)
			)
		)
		(pad "2" smd custom
			(at 0 0.4445)
			(size 0.1397 0.1397)
			(layers "F.Cu" "F.Mask" "F.Paste")
			(net "RSTBTN_OUT_N")
			(options
				(clearance outline)
				(anchor circle)
			)
			(primitives
				(gr_poly
					(pts
						(arc
							(start -0.1778 -0.2794)
							(mid -0.249642 -0.249642)
							(end -0.2794 -0.1778)
						)
						(arc
							(start -0.2794 0.1778)
							(mid -0.249642 0.249642)
							(end -0.1778 0.2794)
						)
						(arc
							(start 0.1778 0.2794)
							(mid 0.249642 0.249642)
							(end 0.2794 0.1778)
						)
						(arc
							(start 0.2794 -0.1778)
							(mid 0.249642 -0.249642)
							(end 0.1778 -0.2794)
						)
					)
					(width 0)
					(fill yes)
				)
			)
		)
	)
	(footprint ""
		(layer "F.Cu")
		(at 32.3342 -162.687 180)
		(property "Reference" "C102"
			(at 0 0 180)
			(layer "F.SilkS")
			(hide yes)
			(effects
				(font
					(size 1.27 1.27)
				)
			)
		)
		(property "Value" "SC1U16V3KX-5GP"
			(at 0 -2.8194 180)
			(unlocked yes)
			(layer "F.Fab")
			(hide yes)
			(effects
				(font
					(size 1.016 1.016)
					(thickness 0.1524)
				)
			)
		)
		(property "Device Type" "C603H36"
			(at 0 -4.3434 180)
			(unlocked yes)
			(layer "F.Fab")
			(hide yes)
			(effects
				(font
					(size 1.016 1.016)
					(thickness 0.1524)
				)
			)
		)
		(duplicate_pad_numbers_are_jumpers no)
		(fp_line
			(start 0.508 0)
			(end -0.508 0)
			(stroke
				(width 0.2032)
				(type default)
			)
			(layer "F.SilkS")
		)
		(fp_rect
			(start -0.5842 1.3335)
			(end 0.5842 -1.3335)
			(stroke
				(width 0)
				(type default)
			)
			(fill no)
			(layer "F.CrtYd")
		)
		(fp_rect
			(start -0.5842 1.3335)
			(end 0.5842 -1.3335)
			(stroke
				(width 0)
				(type default)
			)
			(fill no)
			(layer "F.Fab")
		)
		(pad "1" smd custom
			(at 0 -0.762 180)
			(size 0.2159 0.2159)
			(layers "F.Cu" "F.Mask" "F.Paste")
			(net "V1PLLAV11")
			(options
				(clearance outline)
				(anchor circle)
			)
			(primitives
				(gr_poly
					(pts
						(arc
							(start -0.3302 -0.4318)
							(mid -0.402042 -0.402042)
							(end -0.4318 -0.3302)
						)
						(arc
							(start -0.4318 0.3302)
							(mid -0.402042 0.402042)
							(end -0.3302 0.4318)
						)
						(arc
							(start 0.3302 0.4318)
							(mid 0.402042 0.402042)
							(end 0.4318 0.3302)
						)
						(arc
							(start 0.4318 -0.3302)
							(mid 0.402042 -0.402042)
							(end 0.3302 -0.4318)
						)
					)
					(width 0)
					(fill yes)
				)
			)
		)
		(pad "2" smd custom
			(at 0 0.762 180)
			(size 0.2159 0.2159)
			(layers "F.Cu" "F.Mask" "F.Paste")
			(net "GND")
			(options
				(clearance outline)
				(anchor circle)
			)
			(primitives
				(gr_poly
					(pts
						(arc
							(start -0.3302 -0.4318)
							(mid -0.402042 -0.402042)
							(end -0.4318 -0.3302)
						)
						(arc
							(start -0.4318 0.3302)
							(mid -0.402042 0.402042)
							(end -0.3302 0.4318)
						)
						(arc
							(start 0.3302 0.4318)
							(mid 0.402042 0.402042)
							(end 0.4318 0.3302)
						)
						(arc
							(start 0.4318 -0.3302)
							(mid 0.402042 -0.402042)
							(end 0.3302 -0.4318)
						)
					)
					(width 0)
					(fill yes)
				)
			)
		)
	)
	(footprint ""
		(layer "F.Cu")
		(at 203.5048 -99.441)
		(property "Reference" "R559"
			(at 0 0 0)
			(layer "F.SilkS")
			(hide yes)
			(effects
				(font
					(size 1.27 1.27)
				)
			)
		)
		(property "Value" "0R2J-2-GP"
			(at 0.064008 -3.993896 0)
			(unlocked yes)
			(layer "F.Fab")
			(hide yes)
			(effects
				(font
					(size 1.016 1.016)
					(thickness 0.1524)
				)
			)
		)
		(property "Device Type" "R402H16"
			(at 0.064008 -5.517896 0)
			(unlocked yes)
			(layer "F.Fab")
			(hide yes)
			(effects
				(font
					(size 1.016 1.016)
					(thickness 0.1524)
				)
			)
		)
		(duplicate_pad_numbers_are_jumpers no)
		(fp_line
			(start -0.508 -0.9398)
			(end -0.508 0.9398)
			(stroke
				(width 0.1524)
				(type default)
			)
			(layer "F.SilkS")
		)
		(fp_line
			(start 0.508 -0.9398)
			(end -0.508 -0.9398)
			(stroke
				(width 0.1524)
				(type default)
			)
			(layer "F.SilkS")
		)
		(fp_rect
			(start -0.508 0.9398)
			(end 0.508 -0.9398)
			(stroke
				(width 0)
				(type default)
			)
			(fill no)
			(layer "F.CrtYd")
		)
		(fp_rect
			(start -0.508 0.9398)
			(end 0.508 -0.9398)
			(stroke
				(width 0)
				(type default)
			)
			(fill no)
			(layer "F.Fab")
		)
		(pad "1" smd custom
			(at 0 -0.4445)
			(size 0.1397 0.1397)
			(layers "F.Cu" "F.Mask" "F.Paste")
			(net "TEMP_2_SCL")
			(options
				(clearance outline)
				(anchor circle)
			)
			(primitives
				(gr_poly
					(pts
						(arc
							(start -0.1778 -0.2794)
							(mid -0.249642 -0.249642)
							(end -0.2794 -0.1778)
						)
						(arc
							(start -0.2794 0.1778)
							(mid -0.249642 0.249642)
							(end -0.1778 0.2794)
						)
						(arc
							(start 0.1778 0.2794)
							(mid 0.249642 0.249642)
							(end 0.2794 0.1778)
						)
						(arc
							(start 0.2794 -0.1778)
							(mid 0.249642 -0.249642)
							(end 0.1778 -0.2794)
						)
					)
					(width 0)
					(fill yes)
				)
			)
		)
		(pad "2" smd custom
			(at 0 0.4445)
			(size 0.1397 0.1397)
			(layers "F.Cu" "F.Mask" "F.Paste")
			(net "I2C_IOM_SCL")
			(options
				(clearance outline)
				(anchor circle)
			)
			(primitives
				(gr_poly
					(pts
						(arc
							(start -0.1778 -0.2794)
							(mid -0.249642 -0.249642)
							(end -0.2794 -0.1778)
						)
						(arc
							(start -0.2794 0.1778)
							(mid -0.249642 0.249642)
							(end -0.1778 0.2794)
						)
						(arc
							(start 0.1778 0.2794)
							(mid 0.249642 0.249642)
							(end 0.2794 0.1778)
						)
						(arc
							(start 0.2794 -0.1778)
							(mid 0.249642 -0.249642)
							(end 0.1778 -0.2794)
						)
					)
					(width 0)
					(fill yes)
				)
			)
		)
	)
	(footprint ""
		(layer "F.Cu")
		(at 85.487256 -141.090142 -90)
		(property "Reference" "R617"
			(at 0 0 270)
			(layer "F.SilkS")
			(hide yes)
			(effects
				(font
					(size 1.27 1.27)
				)
			)
		)
		(property "Value" "0R2J-2-GP"
			(at 0.064008 -3.993896 270)
			(unlocked yes)
			(layer "F.Fab")
			(hide yes)
			(effects
				(font
					(size 1.016 1.016)
					(thickness 0.1524)
				)
			)
		)
		(property "Device Type" "R402H16"
			(at 0.064008 -5.517896 270)
			(unlocked yes)
			(layer "F.Fab")
			(hide yes)
			(effects
				(font
					(size 1.016 1.016)
					(thickness 0.1524)
				)
			)
		)
		(duplicate_pad_numbers_are_jumpers no)
		(fp_line
			(start -0.508 -0.9398)
			(end -0.508 0.9398)
			(stroke
				(width 0.1524)
				(type default)
			)
			(layer "F.SilkS")
		)
		(fp_line
			(start 0.508 -0.9398)
			(end -0.508 -0.9398)
			(stroke
				(width 0.1524)
				(type default)
			)
			(layer "F.SilkS")
		)
		(fp_rect
			(start -0.508 0.9398)
			(end 0.508 -0.9398)
			(stroke
				(width 0)
				(type default)
			)
			(fill no)
			(layer "F.CrtYd")
		)
		(fp_rect
			(start -0.508 0.9398)
			(end 0.508 -0.9398)
			(stroke
				(width 0)
				(type default)
			)
			(fill no)
			(layer "F.Fab")
		)
		(pad "1" smd custom
			(at 0 -0.4445 270)
			(size 0.1397 0.1397)
			(layers "F.Cu" "F.Mask" "F.Paste")
			(net "I2C_DPB_SDA")
			(options
				(clearance outline)
				(anchor circle)
			)
			(primitives
				(gr_poly
					(pts
						(arc
							(start -0.1778 -0.2794)
							(mid -0.249642 -0.249642)
							(end -0.2794 -0.1778)
						)
						(arc
							(start -0.2794 0.1778)
							(mid -0.249642 0.249642)
							(end -0.1778 0.2794)
						)
						(arc
							(start 0.1778 0.2794)
							(mid 0.249642 0.249642)
							(end 0.2794 0.1778)
						)
						(arc
							(start 0.2794 -0.1778)
							(mid 0.249642 -0.249642)
							(end 0.1778 -0.2794)
						)
					)
					(width 0)
					(fill yes)
				)
			)
		)
		(pad "2" smd custom
			(at 0 0.4445 270)
			(size 0.1397 0.1397)
			(layers "F.Cu" "F.Mask" "F.Paste")
			(net "I2C_DPB_SDA_R")
			(options
				(clearance outline)
				(anchor circle)
			)
			(primitives
				(gr_poly
					(pts
						(arc
							(start -0.1778 -0.2794)
							(mid -0.249642 -0.249642)
							(end -0.2794 -0.1778)
						)
						(arc
							(start -0.2794 0.1778)
							(mid -0.249642 0.249642)
							(end -0.1778 0.2794)
						)
						(arc
							(start 0.1778 0.2794)
							(mid 0.249642 0.249642)
							(end 0.2794 0.1778)
						)
						(arc
							(start 0.2794 -0.1778)
							(mid 0.249642 -0.249642)
							(end 0.1778 -0.2794)
						)
					)
					(width 0)
					(fill yes)
				)
			)
		)
	)
	(footprint ""
		(layer "F.Cu")
		(at 99.3902 -151.6888 90)
		(property "Reference" "R43"
			(at 0 0 90)
			(layer "F.SilkS")
			(hide yes)
			(effects
				(font
					(size 1.27 1.27)
				)
			)
		)
		(property "Value" "4K7R2F-GP"
			(at 0.064008 -3.993896 90)
			(unlocked yes)
			(layer "F.Fab")
			(hide yes)
			(effects
				(font
					(size 1.016 1.016)
					(thickness 0.1524)
				)
			)
		)
		(property "Device Type" "R402H16"
			(at 0.064008 -5.517896 90)
			(unlocked yes)
			(layer "F.Fab")
			(hide yes)
			(effects
				(font
					(size 1.016 1.016)
					(thickness 0.1524)
				)
			)
		)
		(duplicate_pad_numbers_are_jumpers no)
		(fp_line
			(start 0.508 -0.9398)
			(end -0.508 -0.9398)
			(stroke
				(width 0.1524)
				(type default)
			)
			(layer "F.SilkS")
		)
		(fp_line
			(start -0.508 -0.9398)
			(end -0.508 0.9398)
			(stroke
				(width 0.1524)
				(type default)
			)
			(layer "F.SilkS")
		)
		(fp_rect
			(start -0.508 0.9398)
			(end 0.508 -0.9398)
			(stroke
				(width 0)
				(type default)
			)
			(fill no)
			(layer "F.CrtYd")
		)
		(fp_rect
			(start -0.508 0.9398)
			(end 0.508 -0.9398)
			(stroke
				(width 0)
				(type default)
			)
			(fill no)
			(layer "F.Fab")
		)
		(pad "1" smd custom
			(at 0 -0.4445 90)
			(size 0.1397 0.1397)
			(layers "F.Cu" "F.Mask" "F.Paste")
			(net "USB_EN_4")
			(options
				(clearance outline)
				(anchor circle)
			)
			(primitives
				(gr_poly
					(pts
						(arc
							(start -0.1778 -0.2794)
							(mid -0.249642 -0.249642)
							(end -0.2794 -0.1778)
						)
						(arc
							(start -0.2794 0.1778)
							(mid -0.249642 0.249642)
							(end -0.1778 0.2794)
						)
						(arc
							(start 0.1778 0.2794)
							(mid 0.249642 0.249642)
							(end 0.2794 0.1778)
						)
						(arc
							(start 0.2794 -0.1778)
							(mid 0.249642 -0.249642)
							(end 0.1778 -0.2794)
						)
					)
					(width 0)
					(fill yes)
				)
			)
		)
		(pad "2" smd custom
			(at 0 0.4445 90)
			(size 0.1397 0.1397)
			(layers "F.Cu" "F.Mask" "F.Paste")
			(net "GND")
			(options
				(clearance outline)
				(anchor circle)
			)
			(primitives
				(gr_poly
					(pts
						(arc
							(start -0.1778 -0.2794)
							(mid -0.249642 -0.249642)
							(end -0.2794 -0.1778)
						)
						(arc
							(start -0.2794 0.1778)
							(mid -0.249642 0.249642)
							(end -0.1778 0.2794)
						)
						(arc
							(start 0.1778 0.2794)
							(mid 0.249642 0.249642)
							(end 0.2794 0.1778)
						)
						(arc
							(start 0.2794 -0.1778)
							(mid 0.249642 -0.249642)
							(end 0.1778 -0.2794)
						)
					)
					(width 0)
					(fill yes)
				)
			)
		)
	)
	(footprint ""
		(layer "F.Cu")
		(at 224.185988 -18.469356)
		(property "Reference" "C164"
			(at 0 0 0)
			(layer "F.SilkS")
			(hide yes)
			(effects
				(font
					(size 1.27 1.27)
				)
			)
		)
		(property "Value" "SC10U16V5KX-7-GP-U"
			(at -0.0762 -6.1214 0)
			(unlocked yes)
			(layer "F.Fab")
			(hide yes)
			(effects
				(font
					(size 1.016 1.016)
					(thickness 0.1524)
				)
			)
		)
		(property "Device Type" "C805H58"
			(at -0.0762 -8.1534 0)
			(unlocked yes)
			(layer "F.Fab")
			(hide yes)
			(effects
				(font
					(size 1.016 1.016)
					(thickness 0.1524)
				)
			)
		)
		(duplicate_pad_numbers_are_jumpers no)
		(fp_line
			(start 0.635 0)
			(end -0.635 0)
			(stroke
				(width 0.508)
				(type default)
			)
			(layer "F.SilkS")
		)
		(fp_rect
			(start -0.9652 1.778)
			(end 0.9652 -1.778)
			(stroke
				(width 0)
				(type default)
			)
			(fill no)
			(layer "F.CrtYd")
		)
		(fp_poly
			(pts
				(xy -0.9652 -1.778) (xy 0.9652 -1.778) (xy 0.9652 1.778) (xy -0.9652 1.778)
			)
			(stroke
				(width 0)
				(type default)
			)
			(fill no)
			(layer "F.Fab")
		)
		(pad "1" smd rect
			(at 0 -0.9652)
			(size 1.397 1.143)
			(layers "F.Cu" "F.Mask" "F.Paste")
			(net "P5V_STBY")
		)
		(pad "2" smd rect
			(at 0 0.9652)
			(size 1.397 1.143)
			(layers "F.Cu" "F.Mask" "F.Paste")
			(net "GND")
		)
	)
	(footprint ""
		(layer "F.Cu")
		(at 147.854416 -11.675618 -90)
		(property "Reference" "C209"
			(at 0 0 270)
			(layer "F.SilkS")
			(hide yes)
			(effects
				(font
					(size 1.27 1.27)
				)
			)
		)
		(property "Value" "SC1U16V3KX-5GP"
			(at 0 -2.8194 270)
			(unlocked yes)
			(layer "F.Fab")
			(hide yes)
			(effects
				(font
					(size 1.016 1.016)
					(thickness 0.1524)
				)
			)
		)
		(property "Device Type" "C603H36"
			(at 0 -4.3434 270)
			(unlocked yes)
			(layer "F.Fab")
			(hide yes)
			(effects
				(font
					(size 1.016 1.016)
					(thickness 0.1524)
				)
			)
		)
		(duplicate_pad_numbers_are_jumpers no)
		(fp_line
			(start 0.508 0)
			(end -0.508 0)
			(stroke
				(width 0.2032)
				(type default)
			)
			(layer "F.SilkS")
		)
		(fp_rect
			(start -0.5842 1.3335)
			(end 0.5842 -1.3335)
			(stroke
				(width 0)
				(type default)
			)
			(fill no)
			(layer "F.CrtYd")
		)
		(fp_rect
			(start -0.5842 1.3335)
			(end 0.5842 -1.3335)
			(stroke
				(width 0)
				(type default)
			)
			(fill no)
			(layer "F.Fab")
		)
		(pad "1" smd custom
			(at 0 -0.762 270)
			(size 0.2159 0.2159)
			(layers "F.Cu" "F.Mask" "F.Paste")
			(net "P1V8_STBY_VRG5")
			(options
				(clearance outline)
				(anchor circle)
			)
			(primitives
				(gr_poly
					(pts
						(arc
							(start -0.3302 -0.4318)
							(mid -0.402042 -0.402042)
							(end -0.4318 -0.3302)
						)
						(arc
							(start -0.4318 0.3302)
							(mid -0.402042 0.402042)
							(end -0.3302 0.4318)
						)
						(arc
							(start 0.3302 0.4318)
							(mid 0.402042 0.402042)
							(end 0.4318 0.3302)
						)
						(arc
							(start 0.4318 -0.3302)
							(mid 0.402042 -0.402042)
							(end 0.3302 -0.4318)
						)
					)
					(width 0)
					(fill yes)
				)
			)
		)
		(pad "2" smd custom
			(at 0 0.762 270)
			(size 0.2159 0.2159)
			(layers "F.Cu" "F.Mask" "F.Paste")
			(net "GND")
			(options
				(clearance outline)
				(anchor circle)
			)
			(primitives
				(gr_poly
					(pts
						(arc
							(start -0.3302 -0.4318)
							(mid -0.402042 -0.402042)
							(end -0.4318 -0.3302)
						)
						(arc
							(start -0.4318 0.3302)
							(mid -0.402042 0.402042)
							(end -0.3302 0.4318)
						)
						(arc
							(start 0.3302 0.4318)
							(mid 0.402042 0.402042)
							(end 0.4318 0.3302)
						)
						(arc
							(start 0.4318 -0.3302)
							(mid 0.402042 -0.402042)
							(end 0.3302 -0.4318)
						)
					)
					(width 0)
					(fill yes)
				)
			)
		)
	)
	(footprint ""
		(layer "F.Cu")
		(at 120.0658 -15.9766)
		(property "Reference" "R441"
			(at 0 0 0)
			(layer "F.SilkS")
			(hide yes)
			(effects
				(font
					(size 1.27 1.27)
				)
			)
		)
		(property "Value" "10R2F-L-GP"
			(at 0.064008 -3.993896 0)
			(unlocked yes)
			(layer "F.Fab")
			(hide yes)
			(effects
				(font
					(size 1.016 1.016)
					(thickness 0.1524)
				)
			)
		)
		(property "Device Type" "R402H14"
			(at 0.064008 -5.517896 0)
			(unlocked yes)
			(layer "F.Fab")
			(hide yes)
			(effects
				(font
					(size 1.016 1.016)
					(thickness 0.1524)
				)
			)
		)
		(duplicate_pad_numbers_are_jumpers no)
		(fp_line
			(start -0.508 -0.9398)
			(end -0.508 0.9398)
			(stroke
				(width 0.1524)
				(type default)
			)
			(layer "F.SilkS")
		)
		(fp_line
			(start 0.508 -0.9398)
			(end -0.508 -0.9398)
			(stroke
				(width 0.1524)
				(type default)
			)
			(layer "F.SilkS")
		)
		(fp_rect
			(start -0.508 0.9398)
			(end 0.508 -0.9398)
			(stroke
				(width 0)
				(type default)
			)
			(fill no)
			(layer "F.CrtYd")
		)
		(fp_rect
			(start -0.508 0.9398)
			(end 0.508 -0.9398)
			(stroke
				(width 0)
				(type default)
			)
			(fill no)
			(layer "F.Fab")
		)
		(pad "1" smd custom
			(at 0 -0.4445)
			(size 0.1397 0.1397)
			(layers "F.Cu" "F.Mask" "F.Paste")
			(net "MB0_CM_SENSE_R1_N")
			(options
				(clearance outline)
				(anchor circle)
			)
			(primitives
				(gr_poly
					(pts
						(arc
							(start -0.1778 -0.2794)
							(mid -0.249642 -0.249642)
							(end -0.2794 -0.1778)
						)
						(arc
							(start -0.2794 0.1778)
							(mid -0.249642 0.249642)
							(end -0.1778 0.2794)
						)
						(arc
							(start 0.1778 0.2794)
							(mid 0.249642 0.249642)
							(end 0.2794 0.1778)
						)
						(arc
							(start 0.2794 -0.1778)
							(mid 0.249642 -0.249642)
							(end 0.1778 -0.2794)
						)
					)
					(width 0)
					(fill yes)
				)
			)
		)
		(pad "2" smd custom
			(at 0 0.4445)
			(size 0.1397 0.1397)
			(layers "F.Cu" "F.Mask" "F.Paste")
			(net "MB0_CM_SENSE_N")
			(options
				(clearance outline)
				(anchor circle)
			)
			(primitives
				(gr_poly
					(pts
						(arc
							(start -0.1778 -0.2794)
							(mid -0.249642 -0.249642)
							(end -0.2794 -0.1778)
						)
						(arc
							(start -0.2794 0.1778)
							(mid -0.249642 0.249642)
							(end -0.1778 0.2794)
						)
						(arc
							(start 0.1778 0.2794)
							(mid 0.249642 0.249642)
							(end 0.2794 0.1778)
						)
						(arc
							(start 0.2794 -0.1778)
							(mid 0.249642 -0.249642)
							(end 0.1778 -0.2794)
						)
					)
					(width 0)
					(fill yes)
				)
			)
		)
	)
	(footprint ""
		(layer "F.Cu")
		(at 65.741042 -159.091884)
		(property "Reference" "C518"
			(at 0 0 0)
			(layer "F.SilkS")
			(hide yes)
			(effects
				(font
					(size 1.27 1.27)
				)
			)
		)
		(property "Value" "SCD1U25V2KX-2-GP"
			(at 1.1811 -2.7051 0)
			(unlocked yes)
			(layer "F.Fab")
			(hide yes)
			(effects
				(font
					(size 1.016 1.016)
					(thickness 0.1524)
				)
			)
		)
		(property "Device Type" "C402H22"
			(at 1.1811 -4.2291 0)
			(unlocked yes)
			(layer "F.Fab")
			(hide yes)
			(effects
				(font
					(size 1.016 1.016)
					(thickness 0.1524)
				)
			)
		)
		(duplicate_pad_numbers_are_jumpers no)
		(fp_rect
			(start -0.4318 0.9525)
			(end 0.4318 -0.9525)
			(stroke
				(width 0)
				(type default)
			)
			(fill no)
			(layer "F.CrtYd")
		)
		(fp_rect
			(start -0.4318 0.9525)
			(end 0.4318 -0.9525)
			(stroke
				(width 0)
				(type default)
			)
			(fill no)
			(layer "F.Fab")
		)
		(pad "1" smd custom
			(at 0 -0.4445)
			(size 0.1524 0.1524)
			(layers "F.Cu" "F.Mask" "F.Paste")
			(net "ADC_P1V15_STBY")
			(options
				(clearance outline)
				(anchor circle)
			)
			(primitives
				(gr_poly
					(pts
						(arc
							(start 0.3048 -0.2032)
							(mid 0.275042 -0.275042)
							(end 0.2032 -0.3048)
						)
						(arc
							(start -0.2032 -0.3048)
							(mid -0.275042 -0.275042)
							(end -0.3048 -0.2032)
						)
						(arc
							(start -0.3048 0.2032)
							(mid -0.275042 0.275042)
							(end -0.2032 0.3048)
						)
						(arc
							(start 0.2032 0.3048)
							(mid 0.275042 0.275042)
							(end 0.3048 0.2032)
						)
					)
					(width 0)
					(fill yes)
				)
			)
		)
		(pad "2" smd custom
			(at 0 0.4445)
			(size 0.1524 0.1524)
			(layers "F.Cu" "F.Mask" "F.Paste")
			(net "GND")
			(options
				(clearance outline)
				(anchor circle)
			)
			(primitives
				(gr_poly
					(pts
						(arc
							(start 0.3048 -0.2032)
							(mid 0.275042 -0.275042)
							(end 0.2032 -0.3048)
						)
						(arc
							(start -0.2032 -0.3048)
							(mid -0.275042 -0.275042)
							(end -0.3048 -0.2032)
						)
						(arc
							(start -0.3048 0.2032)
							(mid -0.275042 0.275042)
							(end -0.2032 0.3048)
						)
						(arc
							(start 0.2032 0.3048)
							(mid 0.275042 0.275042)
							(end 0.3048 0.2032)
						)
					)
					(width 0)
					(fill yes)
				)
			)
		)
	)
	(footprint ""
		(layer "F.Cu")
		(at 136.933432 -18.298414 180)
		(property "Reference" "C139"
			(at 0 0 180)
			(layer "F.SilkS")
			(hide yes)
			(effects
				(font
					(size 1.27 1.27)
				)
			)
		)
		(property "Value" "SCD1U50V3KX-GP"
			(at 0 -2.8194 180)
			(unlocked yes)
			(layer "F.Fab")
			(hide yes)
			(effects
				(font
					(size 1.016 1.016)
					(thickness 0.1524)
				)
			)
		)
		(property "Device Type" "C603H36"
			(at 0 -4.3434 180)
			(unlocked yes)
			(layer "F.Fab")
			(hide yes)
			(effects
				(font
					(size 1.016 1.016)
					(thickness 0.1524)
				)
			)
		)
		(duplicate_pad_numbers_are_jumpers no)
		(fp_line
			(start 0.508 0)
			(end -0.508 0)
			(stroke
				(width 0.2032)
				(type default)
			)
			(layer "F.SilkS")
		)
		(fp_rect
			(start -0.5842 1.3335)
			(end 0.5842 -1.3335)
			(stroke
				(width 0)
				(type default)
			)
			(fill no)
			(layer "F.CrtYd")
		)
		(fp_rect
			(start -0.5842 1.3335)
			(end 0.5842 -1.3335)
			(stroke
				(width 0)
				(type default)
			)
			(fill no)
			(layer "F.Fab")
		)
		(pad "1" smd custom
			(at 0 -0.762 180)
			(size 0.2159 0.2159)
			(layers "F.Cu" "F.Mask" "F.Paste")
			(net "P12V_IOM")
			(options
				(clearance outline)
				(anchor circle)
			)
			(primitives
				(gr_poly
					(pts
						(arc
							(start -0.3302 -0.4318)
							(mid -0.402042 -0.402042)
							(end -0.4318 -0.3302)
						)
						(arc
							(start -0.4318 0.3302)
							(mid -0.402042 0.402042)
							(end -0.3302 0.4318)
						)
						(arc
							(start 0.3302 0.4318)
							(mid 0.402042 0.402042)
							(end 0.4318 0.3302)
						)
						(arc
							(start 0.4318 -0.3302)
							(mid 0.402042 -0.402042)
							(end 0.3302 -0.4318)
						)
					)
					(width 0)
					(fill yes)
				)
			)
		)
		(pad "2" smd custom
			(at 0 0.762 180)
			(size 0.2159 0.2159)
			(layers "F.Cu" "F.Mask" "F.Paste")
			(net "GND")
			(options
				(clearance outline)
				(anchor circle)
			)
			(primitives
				(gr_poly
					(pts
						(arc
							(start -0.3302 -0.4318)
							(mid -0.402042 -0.402042)
							(end -0.4318 -0.3302)
						)
						(arc
							(start -0.4318 0.3302)
							(mid -0.402042 0.402042)
							(end -0.3302 0.4318)
						)
						(arc
							(start 0.3302 0.4318)
							(mid 0.402042 0.402042)
							(end 0.4318 0.3302)
						)
						(arc
							(start 0.4318 -0.3302)
							(mid 0.402042 -0.402042)
							(end 0.3302 -0.4318)
						)
					)
					(width 0)
					(fill yes)
				)
			)
		)
	)
	(footprint ""
		(layer "F.Cu")
		(at 188.1886 -140.6144)
		(property "Reference" "TP214"
			(at 0 0 0)
			(layer "F.SilkS")
			(hide yes)
			(effects
				(font
					(size 1.27 1.27)
				)
			)
		)
		(property "Value" "TPAD28-2-GP"
			(at -0.0127 -1.6637 0)
			(unlocked yes)
			(layer "F.Fab")
			(hide yes)
			(effects
				(font
					(size 1.016 1.016)
					(thickness 0.1524)
				)
			)
		)
		(property "Device Type" "TPAD28"
			(at -0.0127 -3.1877 0)
			(unlocked yes)
			(layer "F.Fab")
			(hide yes)
			(effects
				(font
					(size 1.016 1.016)
					(thickness 0.1524)
				)
			)
		)
		(duplicate_pad_numbers_are_jumpers no)
		(fp_poly
			(pts
				(arc
					(start 0.3556 0)
					(mid -0.3556 0)
					(end 0.3556 0)
				)
			)
			(stroke
				(width 0)
				(type default)
			)
			(fill no)
			(layer "F.CrtYd")
		)
		(fp_poly
			(pts
				(arc
					(start 0.6096 0)
					(mid -0.6096 0)
					(end 0.6096 0)
				)
			)
			(stroke
				(width 0)
				(type default)
			)
			(fill no)
			(layer "F.Fab")
		)
		(pad "1" smd circle
			(at 0 0)
			(size 0.7112 0.7112)
			(layers "F.Cu" "F.Mask" "F.Paste")
			(net "TP_M2_2_MFG_DAT")
		)
	)
	(footprint ""
		(layer "F.Cu")
		(at 92.501974 -57.368694 90)
		(property "Reference" "R727"
			(at 0 0 90)
			(layer "F.SilkS")
			(hide yes)
			(effects
				(font
					(size 1.27 1.27)
				)
			)
		)
		(property "Value" "0R2J-2-GP"
			(at 0.064008 -3.993896 90)
			(unlocked yes)
			(layer "F.Fab")
			(hide yes)
			(effects
				(font
					(size 1.016 1.016)
					(thickness 0.1524)
				)
			)
		)
		(property "Device Type" "R402H16"
			(at 0.064008 -5.517896 90)
			(unlocked yes)
			(layer "F.Fab")
			(hide yes)
			(effects
				(font
					(size 1.016 1.016)
					(thickness 0.1524)
				)
			)
		)
		(duplicate_pad_numbers_are_jumpers no)
		(fp_line
			(start 0.508 -0.9398)
			(end -0.508 -0.9398)
			(stroke
				(width 0.1524)
				(type default)
			)
			(layer "F.SilkS")
		)
		(fp_line
			(start -0.508 -0.9398)
			(end -0.508 0.9398)
			(stroke
				(width 0.1524)
				(type default)
			)
			(layer "F.SilkS")
		)
		(fp_rect
			(start -0.508 0.9398)
			(end 0.508 -0.9398)
			(stroke
				(width 0)
				(type default)
			)
			(fill no)
			(layer "F.CrtYd")
		)
		(fp_rect
			(start -0.508 0.9398)
			(end 0.508 -0.9398)
			(stroke
				(width 0)
				(type default)
			)
			(fill no)
			(layer "F.Fab")
		)
		(pad "1" smd custom
			(at 0 -0.4445 90)
			(size 0.1397 0.1397)
			(layers "F.Cu" "F.Mask" "F.Paste")
			(net "P3V3_EN_R")
			(options
				(clearance outline)
				(anchor circle)
			)
			(primitives
				(gr_poly
					(pts
						(arc
							(start -0.1778 -0.2794)
							(mid -0.249642 -0.249642)
							(end -0.2794 -0.1778)
						)
						(arc
							(start -0.2794 0.1778)
							(mid -0.249642 0.249642)
							(end -0.1778 0.2794)
						)
						(arc
							(start 0.1778 0.2794)
							(mid 0.249642 0.249642)
							(end 0.2794 0.1778)
						)
						(arc
							(start 0.2794 -0.1778)
							(mid 0.249642 -0.249642)
							(end 0.1778 -0.2794)
						)
					)
					(width 0)
					(fill yes)
				)
			)
		)
		(pad "2" smd custom
			(at 0 0.4445 90)
			(size 0.1397 0.1397)
			(layers "F.Cu" "F.Mask" "F.Paste")
			(net "P3V3_EN")
			(options
				(clearance outline)
				(anchor circle)
			)
			(primitives
				(gr_poly
					(pts
						(arc
							(start -0.1778 -0.2794)
							(mid -0.249642 -0.249642)
							(end -0.2794 -0.1778)
						)
						(arc
							(start -0.2794 0.1778)
							(mid -0.249642 0.249642)
							(end -0.1778 0.2794)
						)
						(arc
							(start 0.1778 0.2794)
							(mid 0.249642 0.249642)
							(end 0.2794 0.1778)
						)
						(arc
							(start 0.2794 -0.1778)
							(mid 0.249642 -0.249642)
							(end 0.1778 -0.2794)
						)
					)
					(width 0)
					(fill yes)
				)
			)
		)
	)
	(footprint ""
		(layer "F.Cu")
		(at 226.309936 -48.9712 -90)
		(property "Reference" "R469"
			(at 0 0 270)
			(layer "F.SilkS")
			(hide yes)
			(effects
				(font
					(size 1.27 1.27)
				)
			)
		)
		(property "Value" "3D01R5F-GP"
			(at 0 -8.9535 270)
			(unlocked yes)
			(layer "F.Fab")
			(hide yes)
			(effects
				(font
					(size 1.27 1.016)
					(thickness 0.1524)
				)
			)
		)
		(property "Device Type" "R805H24"
			(at 0 -10.6299 270)
			(unlocked yes)
			(layer "F.Fab")
			(hide yes)
			(effects
				(font
					(size 1.27 1.016)
					(thickness 0.1524)
				)
			)
		)
		(duplicate_pad_numbers_are_jumpers no)
		(fp_line
			(start -0.889 1.7018)
			(end 0.889 1.7018)
			(stroke
				(width 0.1524)
				(type default)
			)
			(layer "F.SilkS")
		)
		(fp_line
			(start 0.889 1.7018)
			(end 0.889 -0.508)
			(stroke
				(width 0.1524)
				(type default)
			)
			(layer "F.SilkS")
		)
		(fp_line
			(start -0.889 0.0762)
			(end -0.889 1.7018)
			(stroke
				(width 0.1524)
				(type default)
			)
			(layer "F.SilkS")
		)
		(fp_line
			(start -0.889 -1.7018)
			(end -0.889 0.2794)
			(stroke
				(width 0.1524)
				(type default)
			)
			(layer "F.SilkS")
		)
		(fp_line
			(start 0.889 -1.7018)
			(end 0.889 -0.381)
			(stroke
				(width 0.1524)
				(type default)
			)
			(layer "F.SilkS")
		)
		(fp_line
			(start 0.889 -1.7018)
			(end -0.889 -1.7018)
			(stroke
				(width 0.1524)
				(type default)
			)
			(layer "F.SilkS")
		)
		(fp_poly
			(pts
				(xy 0.9652 -1.778) (xy 0.9652 1.778) (xy -0.9652 1.778) (xy -0.9652 -1.778)
			)
			(stroke
				(width 0)
				(type default)
			)
			(fill no)
			(layer "F.CrtYd")
		)
		(fp_rect
			(start -0.9652 1.778)
			(end 0.9652 -1.778)
			(stroke
				(width 0)
				(type default)
			)
			(fill no)
			(layer "F.Fab")
		)
		(pad "1" smd rect
			(at 0 -0.9652 270)
			(size 1.397 1.143)
			(layers "F.Cu" "F.Mask" "F.Paste")
			(net "P5V_SNB")
		)
		(pad "2" smd rect
			(at 0 0.9652 270)
			(size 1.397 1.143)
			(layers "F.Cu" "F.Mask" "F.Paste")
			(net "GND")
		)
	)
	(footprint ""
		(layer "F.Cu")
		(at 49.657 -128.143 180)
		(property "Reference" "R287"
			(at 0 0 180)
			(layer "F.SilkS")
			(hide yes)
			(effects
				(font
					(size 1.27 1.27)
				)
			)
		)
		(property "Value" "0R2J-2-GP"
			(at 0.064008 -3.993896 180)
			(unlocked yes)
			(layer "F.Fab")
			(hide yes)
			(effects
				(font
					(size 1.016 1.016)
					(thickness 0.1524)
				)
			)
		)
		(property "Device Type" "R402H16"
			(at 0.064008 -5.517896 180)
			(unlocked yes)
			(layer "F.Fab")
			(hide yes)
			(effects
				(font
					(size 1.016 1.016)
					(thickness 0.1524)
				)
			)
		)
		(duplicate_pad_numbers_are_jumpers no)
		(fp_line
			(start 0.508 -0.9398)
			(end -0.508 -0.9398)
			(stroke
				(width 0.1524)
				(type default)
			)
			(layer "F.SilkS")
		)
		(fp_line
			(start -0.508 -0.9398)
			(end -0.508 0.9398)
			(stroke
				(width 0.1524)
				(type default)
			)
			(layer "F.SilkS")
		)
		(fp_rect
			(start -0.508 0.9398)
			(end 0.508 -0.9398)
			(stroke
				(width 0)
				(type default)
			)
			(fill no)
			(layer "F.CrtYd")
		)
		(fp_rect
			(start -0.508 0.9398)
			(end 0.508 -0.9398)
			(stroke
				(width 0)
				(type default)
			)
			(fill no)
			(layer "F.Fab")
		)
		(pad "1" smd custom
			(at 0 -0.4445 180)
			(size 0.1397 0.1397)
			(layers "F.Cu" "F.Mask" "F.Paste")
			(net "SCC_RMT_FULL_PWR_EN")
			(options
				(clearance outline)
				(anchor circle)
			)
			(primitives
				(gr_poly
					(pts
						(arc
							(start -0.1778 -0.2794)
							(mid -0.249642 -0.249642)
							(end -0.2794 -0.1778)
						)
						(arc
							(start -0.2794 0.1778)
							(mid -0.249642 0.249642)
							(end -0.1778 0.2794)
						)
						(arc
							(start 0.1778 0.2794)
							(mid 0.249642 0.249642)
							(end 0.2794 0.1778)
						)
						(arc
							(start 0.2794 -0.1778)
							(mid 0.249642 -0.249642)
							(end 0.1778 -0.2794)
						)
					)
					(width 0)
					(fill yes)
				)
			)
		)
		(pad "2" smd custom
			(at 0 0.4445 180)
			(size 0.1397 0.1397)
			(layers "F.Cu" "F.Mask" "F.Paste")
			(net "SCC_RMT_FULLPWR_EN")
			(options
				(clearance outline)
				(anchor circle)
			)
			(primitives
				(gr_poly
					(pts
						(arc
							(start -0.1778 -0.2794)
							(mid -0.249642 -0.249642)
							(end -0.2794 -0.1778)
						)
						(arc
							(start -0.2794 0.1778)
							(mid -0.249642 0.249642)
							(end -0.1778 0.2794)
						)
						(arc
							(start 0.1778 0.2794)
							(mid 0.249642 0.249642)
							(end 0.2794 0.1778)
						)
						(arc
							(start 0.2794 -0.1778)
							(mid 0.249642 -0.249642)
							(end 0.1778 -0.2794)
						)
					)
					(width 0)
					(fill yes)
				)
			)
		)
	)
	(footprint ""
		(layer "F.Cu")
		(at 149.999954 -120.000014)
		(property "Reference" ""
			(at 0 0 0)
			(layer "F.SilkS")
			(hide yes)
			(effects
				(font
					(size 1.27 1.27)
				)
			)
		)
		(property "Value" "*"
			(at -6.38175 0.19685 0)
			(unlocked yes)
			(layer "F.Fab")
			(hide yes)
			(effects
				(font
					(size 1.016 1.016)
					(thickness 0.1524)
				)
			)
		)
		(duplicate_pad_numbers_are_jumpers no)
		(fp_poly
			(pts
				(arc
					(start 5.0673 0)
					(mid -5.0673 0)
					(end 5.0673 0)
				)
			)
			(stroke
				(width 0)
				(type default)
			)
			(fill no)
			(layer "B.CrtYd")
		)
		(fp_poly
			(pts
				(arc
					(start 5.0673 0)
					(mid -5.0673 0)
					(end 5.0673 0)
				)
			)
			(stroke
				(width 0)
				(type default)
			)
			(fill no)
			(layer "F.CrtYd")
		)
		(fp_poly
			(pts
				(arc
					(start 5.0673 0)
					(mid -5.0673 0)
					(end 5.0673 0)
				)
			)
			(stroke
				(width 0)
				(type default)
			)
			(fill no)
			(layer "B.Fab")
		)
		(fp_poly
			(pts
				(arc
					(start 5.0673 0)
					(mid -5.0673 0)
					(end 5.0673 0)
				)
			)
			(stroke
				(width 0)
				(type default)
			)
			(fill no)
			(layer "F.Fab")
		)
		(pad "1" thru_hole circle
			(at 0 0)
			(size 9.525 9.525)
			(drill 3.5052)
			(layers "*.Cu" "*.Mask")
			(remove_unused_layers no)
			(net "Net_43")
			(clearance -2.5019)
			(thermal_gap 0.3048)
			(padstack
				(mode front_inner_back)
				(layer "Inner"
					(shape circle)
					(size 3.9116 3.9116)
					(clearance 0.3048)
				)
				(layer "B.Cu"
					(shape circle)
					(size 9.525 9.525)
					(clearance -2.5019)
				)
			)
		)
	)
	(footprint ""
		(layer "F.Cu")
		(at 38.321488 -161.399728)
		(property "Reference" "R299"
			(at 0 0 0)
			(layer "F.SilkS")
			(hide yes)
			(effects
				(font
					(size 1.27 1.27)
				)
			)
		)
		(property "Value" "4K7R2F-GP"
			(at 0.064008 -3.993896 0)
			(unlocked yes)
			(layer "F.Fab")
			(hide yes)
			(effects
				(font
					(size 1.016 1.016)
					(thickness 0.1524)
				)
			)
		)
		(property "Device Type" "R402H16"
			(at 0.064008 -5.517896 0)
			(unlocked yes)
			(layer "F.Fab")
			(hide yes)
			(effects
				(font
					(size 1.016 1.016)
					(thickness 0.1524)
				)
			)
		)
		(duplicate_pad_numbers_are_jumpers no)
		(fp_line
			(start -0.508 -0.9398)
			(end -0.508 0.9398)
			(stroke
				(width 0.1524)
				(type default)
			)
			(layer "F.SilkS")
		)
		(fp_line
			(start 0.508 -0.9398)
			(end -0.508 -0.9398)
			(stroke
				(width 0.1524)
				(type default)
			)
			(layer "F.SilkS")
		)
		(fp_rect
			(start -0.508 0.9398)
			(end 0.508 -0.9398)
			(stroke
				(width 0)
				(type default)
			)
			(fill no)
			(layer "F.CrtYd")
		)
		(fp_rect
			(start -0.508 0.9398)
			(end 0.508 -0.9398)
			(stroke
				(width 0)
				(type default)
			)
			(fill no)
			(layer "F.Fab")
		)
		(pad "1" smd custom
			(at 0 -0.4445)
			(size 0.1397 0.1397)
			(layers "F.Cu" "F.Mask" "F.Paste")
			(net "P3V3_STBY")
			(options
				(clearance outline)
				(anchor circle)
			)
			(primitives
				(gr_poly
					(pts
						(arc
							(start -0.1778 -0.2794)
							(mid -0.249642 -0.249642)
							(end -0.2794 -0.1778)
						)
						(arc
							(start -0.2794 0.1778)
							(mid -0.249642 0.249642)
							(end -0.1778 0.2794)
						)
						(arc
							(start 0.1778 0.2794)
							(mid 0.249642 0.249642)
							(end 0.2794 0.1778)
						)
						(arc
							(start 0.2794 -0.1778)
							(mid 0.249642 -0.249642)
							(end 0.1778 -0.2794)
						)
					)
					(width 0)
					(fill yes)
				)
			)
		)
		(pad "2" smd custom
			(at 0 0.4445)
			(size 0.1397 0.1397)
			(layers "F.Cu" "F.Mask" "F.Paste")
			(net "UART_BMC_COMP_IN_RX")
			(options
				(clearance outline)
				(anchor circle)
			)
			(primitives
				(gr_poly
					(pts
						(arc
							(start -0.1778 -0.2794)
							(mid -0.249642 -0.249642)
							(end -0.2794 -0.1778)
						)
						(arc
							(start -0.2794 0.1778)
							(mid -0.249642 0.249642)
							(end -0.1778 0.2794)
						)
						(arc
							(start 0.1778 0.2794)
							(mid 0.249642 0.249642)
							(end 0.2794 0.1778)
						)
						(arc
							(start 0.2794 -0.1778)
							(mid 0.249642 -0.249642)
							(end 0.1778 -0.2794)
						)
					)
					(width 0)
					(fill yes)
				)
			)
		)
	)
	(footprint ""
		(layer "F.Cu")
		(at 97.282 -147.8534 180)
		(property "Reference" "R29"
			(at 0 0 180)
			(layer "F.SilkS")
			(hide yes)
			(effects
				(font
					(size 1.27 1.27)
				)
			)
		)
		(property "Value" "4K7R2F-GP"
			(at 0.064008 -3.993896 180)
			(unlocked yes)
			(layer "F.Fab")
			(hide yes)
			(effects
				(font
					(size 1.016 1.016)
					(thickness 0.1524)
				)
			)
		)
		(property "Device Type" "R402H16"
			(at 0.064008 -5.517896 180)
			(unlocked yes)
			(layer "F.Fab")
			(hide yes)
			(effects
				(font
					(size 1.016 1.016)
					(thickness 0.1524)
				)
			)
		)
		(duplicate_pad_numbers_are_jumpers no)
		(fp_line
			(start 0.508 -0.9398)
			(end -0.508 -0.9398)
			(stroke
				(width 0.1524)
				(type default)
			)
			(layer "F.SilkS")
		)
		(fp_line
			(start -0.508 -0.9398)
			(end -0.508 0.9398)
			(stroke
				(width 0.1524)
				(type default)
			)
			(layer "F.SilkS")
		)
		(fp_rect
			(start -0.508 0.9398)
			(end 0.508 -0.9398)
			(stroke
				(width 0)
				(type default)
			)
			(fill no)
			(layer "F.CrtYd")
		)
		(fp_rect
			(start -0.508 0.9398)
			(end 0.508 -0.9398)
			(stroke
				(width 0)
				(type default)
			)
			(fill no)
			(layer "F.Fab")
		)
		(pad "1" smd custom
			(at 0 -0.4445 180)
			(size 0.1397 0.1397)
			(layers "F.Cu" "F.Mask" "F.Paste")
			(net "P3V3_STBY")
			(options
				(clearance outline)
				(anchor circle)
			)
			(primitives
				(gr_poly
					(pts
						(arc
							(start -0.1778 -0.2794)
							(mid -0.249642 -0.249642)
							(end -0.2794 -0.1778)
						)
						(arc
							(start -0.2794 0.1778)
							(mid -0.249642 0.249642)
							(end -0.1778 0.2794)
						)
						(arc
							(start 0.1778 0.2794)
							(mid 0.249642 0.249642)
							(end 0.2794 0.1778)
						)
						(arc
							(start 0.2794 -0.1778)
							(mid 0.249642 -0.249642)
							(end 0.1778 -0.2794)
						)
					)
					(width 0)
					(fill yes)
				)
			)
		)
		(pad "2" smd custom
			(at 0 0.4445 180)
			(size 0.1397 0.1397)
			(layers "F.Cu" "F.Mask" "F.Paste")
			(net "USB_OCS_N2")
			(options
				(clearance outline)
				(anchor circle)
			)
			(primitives
				(gr_poly
					(pts
						(arc
							(start -0.1778 -0.2794)
							(mid -0.249642 -0.249642)
							(end -0.2794 -0.1778)
						)
						(arc
							(start -0.2794 0.1778)
							(mid -0.249642 0.249642)
							(end -0.1778 0.2794)
						)
						(arc
							(start 0.1778 0.2794)
							(mid 0.249642 0.249642)
							(end 0.2794 0.1778)
						)
						(arc
							(start 0.2794 -0.1778)
							(mid 0.249642 -0.249642)
							(end 0.1778 -0.2794)
						)
					)
					(width 0)
					(fill yes)
				)
			)
		)
	)
	(footprint ""
		(layer "F.Cu")
		(at 77.283818 -80.554068 90)
		(property "Reference" "VIA4"
			(at 0 0 90)
			(layer "F.SilkS")
			(hide yes)
			(effects
				(font
					(size 1.27 1.27)
				)
			)
		)
		(property "Value" "85OHM-8L-1D6MM-L16L18-GP"
			(at 4.064 0.6096 90)
			(unlocked yes)
			(layer "F.Fab")
			(hide yes)
			(effects
				(font
					(size 1.016 1.016)
					(thickness 0.1524)
				)
			)
		)
		(property "Device Type" "VIA-PCIE-4P-368076"
			(at 4.064 -0.9144 90)
			(unlocked yes)
			(layer "F.Fab")
			(hide yes)
			(effects
				(font
					(size 1.016 1.016)
					(thickness 0.1524)
				)
			)
		)
		(duplicate_pad_numbers_are_jumpers no)
		(fp_rect
			(start -1.8415 0.381)
			(end 1.8415 -0.381)
			(stroke
				(width 0)
				(type default)
			)
			(fill no)
			(layer "F.CrtYd")
		)
		(fp_rect
			(start -1.8415 0.381)
			(end 1.8415 -0.381)
			(stroke
				(width 0)
				(type default)
			)
			(fill no)
			(layer "F.Fab")
		)
		(pad "1" thru_hole circle
			(at -1.4605 0 90)
			(size 0.508 0.508)
			(drill 0.254)
			(layers "*.Cu" "*.Mask")
			(remove_unused_layers no)
			(net "GND")
			(clearance 0.127)
			(thermal_gap 0.127)
		)
		(pad "2" thru_hole circle
			(at -0.4445 0 90)
			(size 0.508 0.508)
			(drill 0.254)
			(layers "*.Cu" "*.Mask")
			(remove_unused_layers no)
			(net "PCIE_COMP_TO_IOM_19_DP")
			(clearance 0.127)
			(thermal_gap 0.127)
		)
		(pad "3" thru_hole circle
			(at 0.4445 0 90)
			(size 0.508 0.508)
			(drill 0.254)
			(layers "*.Cu" "*.Mask")
			(remove_unused_layers no)
			(net "PCIE_COMP_TO_IOM_19_DN")
			(clearance 0.127)
			(thermal_gap 0.127)
		)
		(pad "4" thru_hole circle
			(at 1.4605 0 90)
			(size 0.508 0.508)
			(drill 0.254)
			(layers "*.Cu" "*.Mask")
			(remove_unused_layers no)
			(net "GND")
			(clearance 0.127)
			(thermal_gap 0.127)
		)
	)
	(footprint ""
		(layer "F.Cu")
		(at 69.5452 -175.1584 180)
		(property "Reference" "U31"
			(at 0 0 180)
			(layer "F.SilkS")
			(hide yes)
			(effects
				(font
					(size 1.27 1.27)
				)
			)
		)
		(property "Value" "SN74LVC1G08DCKR-GP"
			(at -2.3368 -8.6868 180)
			(unlocked yes)
			(layer "F.Fab")
			(hide yes)
			(effects
				(font
					(size 1.016 1.016)
					(thickness 0.1524)
				)
			)
		)
		(property "Device Type" "SC70-5H44"
			(at -2.3114 -10.414 180)
			(unlocked yes)
			(layer "F.Fab")
			(hide yes)
			(effects
				(font
					(size 1.016 1.016)
					(thickness 0.1524)
				)
			)
		)
		(duplicate_pad_numbers_are_jumpers no)
		(fp_line
			(start 1.3843 -1.8034)
			(end 1.3843 -1.1176)
			(stroke
				(width 0.3302)
				(type default)
			)
			(layer "F.SilkS")
		)
		(fp_line
			(start 1.27 1.7018)
			(end -1.27 1.7018)
			(stroke
				(width 0.1524)
				(type default)
			)
			(layer "F.SilkS")
		)
		(fp_line
			(start 1.27 -1.7018)
			(end 1.27 1.7018)
			(stroke
				(width 0.1524)
				(type default)
			)
			(layer "F.SilkS")
		)
		(fp_line
			(start 0.6604 -1.8034)
			(end 1.3843 -1.8034)
			(stroke
				(width 0.3302)
				(type default)
			)
			(layer "F.SilkS")
		)
		(fp_line
			(start -1.27 1.7018)
			(end -1.27 -1.7018)
			(stroke
				(width 0.1524)
				(type default)
			)
			(layer "F.SilkS")
		)
		(fp_line
			(start -1.27 -1.7018)
			(end 1.27 -1.7018)
			(stroke
				(width 0.1524)
				(type default)
			)
			(layer "F.SilkS")
		)
		(fp_rect
			(start -1.524 1.9558)
			(end 1.524 -1.9558)
			(stroke
				(width 0)
				(type default)
			)
			(fill no)
			(layer "F.CrtYd")
		)
		(fp_poly
			(pts
				(xy -1.524 -1.9558) (xy 1.524 -1.9558) (xy 1.524 1.9558) (xy -1.524 1.9558)
			)
			(stroke
				(width 0)
				(type default)
			)
			(fill no)
			(layer "F.Fab")
		)
		(pad "1" smd rect
			(at 0.65024 -0.8255 180)
			(size 0.4064 1.2192)
			(layers "F.Cu" "F.Mask" "F.Paste")
			(net "COMP_TO_BMC_RESET_N_OUT")
		)
		(pad "2" smd rect
			(at 0 -0.8255 180)
			(size 0.4064 1.2192)
			(layers "F.Cu" "F.Mask" "F.Paste")
			(net "BMC_TPM_RST_N")
		)
		(pad "3" smd rect
			(at -0.65024 -0.8255 180)
			(size 0.4064 1.2192)
			(layers "F.Cu" "F.Mask" "F.Paste")
			(net "GND")
		)
		(pad "4" smd rect
			(at -0.65024 0.8255 180)
			(size 0.4064 1.2192)
			(layers "F.Cu" "F.Mask" "F.Paste")
			(net "RST_BMC_EXTRST_N_1")
		)
		(pad "5" smd rect
			(at 0.65024 0.8255 180)
			(size 0.4064 1.2192)
			(layers "F.Cu" "F.Mask" "F.Paste")
			(net "P3V3_STBY")
		)
	)
	(footprint ""
		(layer "F.Cu")
		(at 60.656978 -166.845234 180)
		(property "Reference" "R75"
			(at 0 0 180)
			(layer "F.SilkS")
			(hide yes)
			(effects
				(font
					(size 1.27 1.27)
				)
			)
		)
		(property "Value" "0R2J-2-GP"
			(at 0.064008 -3.993896 180)
			(unlocked yes)
			(layer "F.Fab")
			(hide yes)
			(effects
				(font
					(size 1.016 1.016)
					(thickness 0.1524)
				)
			)
		)
		(property "Device Type" "R402H16"
			(at 0.064008 -5.517896 180)
			(unlocked yes)
			(layer "F.Fab")
			(hide yes)
			(effects
				(font
					(size 1.016 1.016)
					(thickness 0.1524)
				)
			)
		)
		(duplicate_pad_numbers_are_jumpers no)
		(fp_line
			(start 0.508 -0.9398)
			(end -0.508 -0.9398)
			(stroke
				(width 0.1524)
				(type default)
			)
			(layer "F.SilkS")
		)
		(fp_line
			(start -0.508 -0.9398)
			(end -0.508 0.9398)
			(stroke
				(width 0.1524)
				(type default)
			)
			(layer "F.SilkS")
		)
		(fp_rect
			(start -0.508 0.9398)
			(end 0.508 -0.9398)
			(stroke
				(width 0)
				(type default)
			)
			(fill no)
			(layer "F.CrtYd")
		)
		(fp_rect
			(start -0.508 0.9398)
			(end 0.508 -0.9398)
			(stroke
				(width 0)
				(type default)
			)
			(fill no)
			(layer "F.Fab")
		)
		(pad "1" smd custom
			(at 0 -0.4445 180)
			(size 0.1397 0.1397)
			(layers "F.Cu" "F.Mask" "F.Paste")
			(net "BMC_SELF_HW_RST_D")
			(options
				(clearance outline)
				(anchor circle)
			)
			(primitives
				(gr_poly
					(pts
						(arc
							(start -0.1778 -0.2794)
							(mid -0.249642 -0.249642)
							(end -0.2794 -0.1778)
						)
						(arc
							(start -0.2794 0.1778)
							(mid -0.249642 0.249642)
							(end -0.1778 0.2794)
						)
						(arc
							(start 0.1778 0.2794)
							(mid 0.249642 0.249642)
							(end 0.2794 0.1778)
						)
						(arc
							(start 0.2794 -0.1778)
							(mid 0.249642 -0.249642)
							(end 0.1778 -0.2794)
						)
					)
					(width 0)
					(fill yes)
				)
			)
		)
		(pad "2" smd custom
			(at 0 0.4445 180)
			(size 0.1397 0.1397)
			(layers "F.Cu" "F.Mask" "F.Paste")
			(net "FM_TPM_PRSNT_RST_N")
			(options
				(clearance outline)
				(anchor circle)
			)
			(primitives
				(gr_poly
					(pts
						(arc
							(start -0.1778 -0.2794)
							(mid -0.249642 -0.249642)
							(end -0.2794 -0.1778)
						)
						(arc
							(start -0.2794 0.1778)
							(mid -0.249642 0.249642)
							(end -0.1778 0.2794)
						)
						(arc
							(start 0.1778 0.2794)
							(mid 0.249642 0.249642)
							(end 0.2794 0.1778)
						)
						(arc
							(start 0.2794 -0.1778)
							(mid 0.249642 -0.249642)
							(end 0.1778 -0.2794)
						)
					)
					(width 0)
					(fill yes)
				)
			)
		)
	)
	(footprint ""
		(layer "F.Cu")
		(at 222.293688 -28.229052 -90)
		(property "Reference" "C167"
			(at 0 0 270)
			(layer "F.SilkS")
			(hide yes)
			(effects
				(font
					(size 1.27 1.27)
				)
			)
		)
		(property "Value" "ST100U16VDM-3-GP"
			(at 0 -9.6012 270)
			(unlocked yes)
			(layer "F.Fab")
			(hide yes)
			(effects
				(font
					(size 1.016 1.016)
					(thickness 0.1524)
				)
			)
		)
		(property "Device Type" "CT7343H79"
			(at 0 -11.1252 270)
			(unlocked yes)
			(layer "F.Fab")
			(hide yes)
			(effects
				(font
					(size 1.016 1.016)
					(thickness 0.1524)
				)
			)
		)
		(duplicate_pad_numbers_are_jumpers no)
		(fp_line
			(start -2.286 4.8768)
			(end -2.286 2.032)
			(stroke
				(width 0.1524)
				(type default)
			)
			(layer "F.SilkS")
		)
		(fp_line
			(start 2.286 4.8768)
			(end -2.286 4.8768)
			(stroke
				(width 0.1524)
				(type default)
			)
			(layer "F.SilkS")
		)
		(fp_line
			(start 2.286 2.032)
			(end 2.286 4.8768)
			(stroke
				(width 0.1524)
				(type default)
			)
			(layer "F.SilkS")
		)
		(fp_line
			(start 2.286 -2.032)
			(end 2.286 -4.8768)
			(stroke
				(width 0.1524)
				(type default)
			)
			(layer "F.SilkS")
		)
		(fp_line
			(start 2.1082 -4.699)
			(end -2.1082 -4.699)
			(stroke
				(width 0.508)
				(type default)
			)
			(layer "F.SilkS")
		)
		(fp_line
			(start -2.286 -4.8768)
			(end -2.286 -2.032)
			(stroke
				(width 0.1524)
				(type default)
			)
			(layer "F.SilkS")
		)
		(fp_line
			(start 2.286 -4.8768)
			(end -2.286 -4.8768)
			(stroke
				(width 0.1524)
				(type default)
			)
			(layer "F.SilkS")
		)
		(fp_rect
			(start -2.1463 3.6449)
			(end 2.1463 -3.6449)
			(stroke
				(width 0)
				(type default)
			)
			(fill no)
			(layer "F.CrtYd")
		)
		(fp_poly
			(pts
				(xy -2.54 4.953) (xy -2.54 4.2926) (xy -3.81 4.2926) (xy -3.81 -4.2926) (xy -2.54 -4.2926) (xy -2.54 -4.953)
				(xy 2.54 -4.953) (xy 2.54 -4.2926) (xy 3.81 -4.2926) (xy 3.81 -1.6256) (xy 2.1463 -1.6256) (xy 2.1463 -3.6449)
				(xy -2.1463 -3.6449) (xy -2.1463 3.6449) (xy 2.1463 3.6449) (xy 2.1463 -1.6129) (xy 3.81 -1.6129)
				(xy 3.81 4.2926) (xy 2.54 4.2926) (xy 2.54 4.953)
			)
			(stroke
				(width 0)
				(type default)
			)
			(fill no)
			(layer "F.CrtYd")
		)
		(fp_rect
			(start -2.54 4.953)
			(end 2.54 -4.953)
			(stroke
				(width 0)
				(type default)
			)
			(fill no)
			(layer "F.Fab")
		)
		(fp_rect
			(start -3.81 4.2926)
			(end -2.54 -4.2926)
			(stroke
				(width 0)
				(type default)
			)
			(fill no)
			(layer "F.Fab")
		)
		(fp_rect
			(start 2.54 4.2926)
			(end 3.81 -4.2926)
			(stroke
				(width 0)
				(type default)
			)
			(fill no)
			(layer "F.Fab")
		)
		(pad "1" smd rect
			(at 0 -3.1496 270)
			(size 2.413 2.286)
			(layers "F.Cu" "F.Mask" "F.Paste")
			(net "P5V_STBY")
		)
		(pad "2" smd rect
			(at 0 3.1496 270)
			(size 2.413 2.286)
			(layers "F.Cu" "F.Mask" "F.Paste")
			(net "GND")
		)
		(zone
			(layer "F.Cu")
			(hatch none 0.5)
			(connect_pads
				(clearance 0)
			)
			(min_thickness 0.25)
			(keepout
				(tracks allowed)
				(vias not_allowed)
				(pads allowed)
				(copperpour not_allowed)
				(footprints allowed)
			)
			(placement
				(enabled no)
				(sheetname "")
			)
			(fill
				(thermal_gap 0.5)
				(thermal_bridge_width 0.5)
				(island_removal_mode 0)
			)
			(polygon
				(pts
					(xy 217.696288 -29.740352) (xy 217.696288 -26.717752) (xy 220.591888 -26.717752) (xy 220.922088 -26.717752)
					(xy 220.922088 -29.740352) (xy 220.591888 -29.740352)
				)
			)
		)
		(zone
			(layer "F.Cu")
			(hatch none 0.5)
			(connect_pads
				(clearance 0)
			)
			(min_thickness 0.25)
			(keepout
				(tracks allowed)
				(vias not_allowed)
				(pads allowed)
				(copperpour not_allowed)
				(footprints allowed)
			)
			(placement
				(enabled no)
				(sheetname "")
			)
			(fill
				(thermal_gap 0.5)
				(thermal_bridge_width 0.5)
				(island_removal_mode 0)
			)
			(polygon
				(pts
					(xy 223.982788 -26.717752) (xy 226.891088 -26.717752) (xy 226.891088 -29.740352) (xy 223.995488 -29.740352)
					(xy 223.665288 -29.740352) (xy 223.665288 -26.717752)
				)
			)
		)
	)
	(footprint ""
		(layer "F.Cu")
		(at 47.69993 -144.999964 -90)
		(property "Reference" "U2"
			(at 0 0 270)
			(layer "F.SilkS")
			(hide yes)
			(effects
				(font
					(size 1.27 1.27)
				)
			)
		)
		(property "Value" "AST2500A2-GP-GP-U"
			(at -17.0307 -8.584692 270)
			(unlocked yes)
			(layer "F.Fab")
			(hide yes)
			(effects
				(font
					(size 1.016 1.016)
					(thickness 0.1524)
				)
			)
		)
		(property "Device Type" "BGA456D19H58"
			(at -17.0307 -10.108692 270)
			(unlocked yes)
			(layer "F.Fab")
			(hide yes)
			(effects
				(font
					(size 1.016 1.016)
					(thickness 0.1524)
				)
			)
		)
		(duplicate_pad_numbers_are_jumpers no)
		(fp_line
			(start -9.500108 9.500108)
			(end 9.500108 9.500108)
			(stroke
				(width 0.1524)
				(type default)
			)
			(layer "F.SilkS")
		)
		(fp_line
			(start 9.500108 9.500108)
			(end 9.500108 -9.500108)
			(stroke
				(width 0.1524)
				(type default)
			)
			(layer "F.SilkS")
		)
		(fp_line
			(start -9.830308 -8.230108)
			(end -9.830308 -9.830308)
			(stroke
				(width 0.508)
				(type default)
			)
			(layer "F.SilkS")
		)
		(fp_line
			(start -9.500108 -9.500108)
			(end -9.500108 9.500108)
			(stroke
				(width 0.1524)
				(type default)
			)
			(layer "F.SilkS")
		)
		(fp_line
			(start 9.500108 -9.500108)
			(end -9.500108 -9.500108)
			(stroke
				(width 0.1524)
				(type default)
			)
			(layer "F.SilkS")
		)
		(fp_line
			(start -9.830308 -9.830308)
			(end -8.230108 -9.830308)
			(stroke
				(width 0.508)
				(type default)
			)
			(layer "F.SilkS")
		)
		(fp_rect
			(start -9.500108 9.500108)
			(end 9.500108 -9.500108)
			(stroke
				(width 0)
				(type default)
			)
			(fill no)
			(layer "F.CrtYd")
		)
		(fp_poly
			(pts
				(xy 10.500106 -9.500108) (xy -9.500108 -9.500108) (xy -9.500108 9.500108) (xy 9.500108 9.500108)
				(xy 9.500108 -9.487408) (xy 10.500106 -9.487408) (xy 10.500106 10.500106) (xy -10.500106 10.500106)
				(xy -10.500106 -10.500106) (xy 10.500106 -10.500106)
			)
			(stroke
				(width 0)
				(type default)
			)
			(fill no)
			(layer "F.CrtYd")
		)
		(fp_rect
			(start -11.500104 11.500104)
			(end 11.500104 -11.500104)
			(stroke
				(width 0)
				(type default)
			)
			(fill no)
			(layer "F.Fab")
		)
		(pad "A1" smd circle
			(at -8.400034 -8.400034 270)
			(size 0.4064 0.4064)
			(layers "F.Cu" "F.Mask" "F.Paste")
			(net "GND")
		)
		(pad "A2" smd circle
			(at -7.599934 -8.400034 270)
			(size 0.4064 0.4064)
			(layers "F.Cu" "F.Mask" "F.Paste")
			(net "MAC2_TXD0")
		)
		(pad "A3" smd circle
			(at -6.800088 -8.400034 270)
			(size 0.4064 0.4064)
			(layers "F.Cu" "F.Mask" "F.Paste")
			(net "NCSI_RXD0")
		)
		(pad "A4" smd circle
			(at -5.999988 -8.400034 270)
			(size 0.3556 0.3556)
			(layers "F.Cu" "F.Mask" "F.Paste")
			(net "BMC_RGMII_A4_D3")
		)
		(pad "A5" smd circle
			(at -5.199888 -8.400034 270)
			(size 0.3556 0.3556)
			(layers "F.Cu" "F.Mask" "F.Paste")
			(net "NCSI_TXD1_R")
		)
		(pad "A6" smd circle
			(at -4.400042 -8.400034 270)
			(size 0.3556 0.3556)
			(layers "F.Cu" "F.Mask" "F.Paste")
			(net "USB_P3_DN")
		)
		(pad "A7" smd circle
			(at -3.599942 -8.400034 270)
			(size 0.3556 0.3556)
			(layers "F.Cu" "F.Mask" "F.Paste")
			(net "USB_P2_DP")
		)
		(pad "A8" smd circle
			(at -2.800096 -8.400034 270)
			(size 0.3556 0.3556)
			(layers "F.Cu" "F.Mask" "F.Paste")
			(net "USB_P2_DN")
		)
		(pad "A9" smd circle
			(at -1.999996 -8.400034 270)
			(size 0.3556 0.3556)
			(layers "F.Cu" "F.Mask" "F.Paste")
			(net "BMC_SMB4_CLK")
		)
		(pad "A10" smd circle
			(at -1.199896 -8.400034 270)
			(size 0.3556 0.3556)
			(layers "F.Cu" "F.Mask" "F.Paste")
			(net "BMC_SMB3_DAT")
		)
		(pad "A11" smd circle
			(at -0.40005 -8.400034 270)
			(size 0.3556 0.3556)
			(layers "F.Cu" "F.Mask" "F.Paste")
			(net "BMC_SMB3_CLK")
		)
		(pad "A12" smd circle
			(at 0.40005 -8.400034 270)
			(size 0.3556 0.3556)
			(layers "F.Cu" "F.Mask" "F.Paste")
			(net "BMC_SMB10_DAT")
		)
		(pad "A13" smd circle
			(at 1.199896 -8.400034 270)
			(size 0.3556 0.3556)
			(layers "F.Cu" "F.Mask" "F.Paste")
			(net "BMC_SMB9_DAT")
		)
		(pad "A14" smd circle
			(at 1.999996 -8.400034 270)
			(size 0.3556 0.3556)
			(layers "F.Cu" "F.Mask" "F.Paste")
			(net "TP_BMC_GPIOI6")
		)
		(pad "A15" smd circle
			(at 2.800096 -8.400034 270)
			(size 0.3556 0.3556)
			(layers "F.Cu" "F.Mask" "F.Paste")
			(net "TP_BMC_GPIOI7")
		)
		(pad "A16" smd circle
			(at 3.599942 -8.400034 270)
			(size 0.3556 0.3556)
			(layers "F.Cu" "F.Mask" "F.Paste")
			(net "LED_POSTCODE_6")
		)
		(pad "A17" smd circle
			(at 4.400042 -8.400034 270)
			(size 0.3556 0.3556)
			(layers "F.Cu" "F.Mask" "F.Paste")
			(net "LED_POSTCODE_4")
		)
		(pad "A18" smd circle
			(at 5.199888 -8.400034 270)
			(size 0.3556 0.3556)
			(layers "F.Cu" "F.Mask" "F.Paste")
			(net "LED_POSTCODE_0")
		)
		(pad "A19" smd circle
			(at 5.999988 -8.400034 270)
			(size 0.3556 0.3556)
			(layers "F.Cu" "F.Mask" "F.Paste")
			(net "SLOTID_0")
		)
		(pad "A20" smd circle
			(at 6.800088 -8.400034 270)
			(size 0.4064 0.4064)
			(layers "F.Cu" "F.Mask" "F.Paste")
			(net "TP_BMC_EXT2_LED_B")
		)
		(pad "A21" smd circle
			(at 7.599934 -8.400034 270)
			(size 0.4064 0.4064)
			(layers "F.Cu" "F.Mask" "F.Paste")
			(net "SCC_PWR_EN_R")
		)
		(pad "A22" smd circle
			(at 8.400034 -8.400034 270)
			(size 0.4064 0.4064)
			(layers "F.Cu" "F.Mask" "F.Paste")
			(net "GND")
		)
		(pad "AA1" smd circle
			(at -8.400034 7.599934 270)
			(size 0.4064 0.4064)
			(layers "F.Cu" "F.Mask" "F.Paste")
			(net "Net_563")
		)
		(pad "AA2" smd circle
			(at -7.599934 7.599934 270)
			(size 0.4064 0.4064)
			(layers "F.Cu" "F.Mask" "F.Paste")
			(net "Net_562")
		)
		(pad "AA3" smd circle
			(at -6.800088 7.599934 270)
			(size 0.4064 0.4064)
			(layers "F.Cu" "F.Mask" "F.Paste")
			(net "TP_BMC_GPION5")
		)
		(pad "AA4" smd circle
			(at -5.999988 7.599934 270)
			(size 0.3556 0.3556)
			(layers "F.Cu" "F.Mask" "F.Paste")
			(net "COMP_POWER_FAIL_R_N")
		)
		(pad "AA5" smd circle
			(at -5.199888 7.599934 270)
			(size 0.3556 0.3556)
			(layers "F.Cu" "F.Mask" "F.Paste")
			(net "THROTTLE_N")
		)
		(pad "AA6" smd circle
			(at -4.400042 7.599934 270)
			(size 0.3556 0.3556)
			(layers "F.Cu" "F.Mask" "F.Paste")
			(net "MEMDQ_12")
		)
		(pad "AA7" smd circle
			(at -3.599942 7.599934 270)
			(size 0.3556 0.3556)
			(layers "F.Cu" "F.Mask" "F.Paste")
			(net "GND")
		)
		(pad "AA8" smd circle
			(at -2.800096 7.599934 270)
			(size 0.3556 0.3556)
			(layers "F.Cu" "F.Mask" "F.Paste")
			(net "MEMDQ_8")
		)
		(pad "AA9" smd circle
			(at -1.999996 7.599934 270)
			(size 0.3556 0.3556)
			(layers "F.Cu" "F.Mask" "F.Paste")
			(net "GND")
		)
		(pad "AA10" smd circle
			(at -1.199896 7.599934 270)
			(size 0.3556 0.3556)
			(layers "F.Cu" "F.Mask" "F.Paste")
			(net "MEMDQ_3")
		)
		(pad "AA11" smd circle
			(at -0.40005 7.599934 270)
			(size 0.3556 0.3556)
			(layers "F.Cu" "F.Mask" "F.Paste")
			(net "GND")
		)
		(pad "AA12" smd circle
			(at 0.40005 7.599934 270)
			(size 0.3556 0.3556)
			(layers "F.Cu" "F.Mask" "F.Paste")
			(net "MEMCSN")
		)
		(pad "AA13" smd circle
			(at 1.199896 7.599934 270)
			(size 0.3556 0.3556)
			(layers "F.Cu" "F.Mask" "F.Paste")
			(net "GND")
		)
		(pad "AA14" smd circle
			(at 1.999996 7.599934 270)
			(size 0.3556 0.3556)
			(layers "F.Cu" "F.Mask" "F.Paste")
			(net "MEMA_11")
		)
		(pad "AA15" smd circle
			(at 2.800096 7.599934 270)
			(size 0.3556 0.3556)
			(layers "F.Cu" "F.Mask" "F.Paste")
			(net "GND")
		)
		(pad "AA16" smd circle
			(at 3.599942 7.599934 270)
			(size 0.3556 0.3556)
			(layers "F.Cu" "F.Mask" "F.Paste")
			(net "MEMA_7")
		)
		(pad "AA17" smd circle
			(at 4.400042 7.599934 270)
			(size 0.3556 0.3556)
			(layers "F.Cu" "F.Mask" "F.Paste")
			(net "P1V15_STBY")
		)
		(pad "AA18" smd circle
			(at 5.199888 7.599934 270)
			(size 0.3556 0.3556)
			(layers "F.Cu" "F.Mask" "F.Paste")
			(net "BMC_SPI_CLK")
		)
		(pad "AA19" smd circle
			(at 5.999988 7.599934 270)
			(size 0.3556 0.3556)
			(layers "F.Cu" "F.Mask" "F.Paste")
			(net "FLA_CS_1")
		)
		(pad "AA20" smd circle
			(at 6.800088 7.599934 270)
			(size 0.4064 0.4064)
			(layers "F.Cu" "F.Mask" "F.Paste")
			(net "BMC_GPIOS7")
		)
		(pad "AA21" smd circle
			(at 7.599934 7.599934 270)
			(size 0.4064 0.4064)
			(layers "F.Cu" "F.Mask" "F.Paste")
			(net "PLTRST_R")
		)
		(pad "AA22" smd circle
			(at 8.400034 7.599934 270)
			(size 0.4064 0.4064)
			(layers "F.Cu" "F.Mask" "F.Paste")
			(net "TPM_PRSNT_N_R")
		)
		(pad "AB1" smd circle
			(at -8.400034 8.400034 270)
			(size 0.4064 0.4064)
			(layers "F.Cu" "F.Mask" "F.Paste")
			(net "GND")
		)
		(pad "AB2" smd circle
			(at -7.599934 8.400034 270)
			(size 0.4064 0.4064)
			(layers "F.Cu" "F.Mask" "F.Paste")
			(net "Net_561")
		)
		(pad "AB3" smd circle
			(at -6.800088 8.400034 270)
			(size 0.4064 0.4064)
			(layers "F.Cu" "F.Mask" "F.Paste")
			(net "SCC_A_HB_IN_R")
		)
		(pad "AB4" smd circle
			(at -5.999988 8.400034 270)
			(size 0.3556 0.3556)
			(layers "F.Cu" "F.Mask" "F.Paste")
			(net "ENCL_FAULT_LED_R")
		)
		(pad "AB5" smd circle
			(at -5.199888 8.400034 270)
			(size 0.3556 0.3556)
			(layers "F.Cu" "F.Mask" "F.Paste")
			(net "DEBUG_GPIO_BMC_R_1")
		)
		(pad "AB6" smd circle
			(at -4.400042 8.400034 270)
			(size 0.3556 0.3556)
			(layers "F.Cu" "F.Mask" "F.Paste")
			(net "MEMDQS_N1")
		)
		(pad "AB7" smd circle
			(at -3.599942 8.400034 270)
			(size 0.3556 0.3556)
			(layers "F.Cu" "F.Mask" "F.Paste")
			(net "MEMDQS_P1")
		)
		(pad "AB8" smd circle
			(at -2.800096 8.400034 270)
			(size 0.3556 0.3556)
			(layers "F.Cu" "F.Mask" "F.Paste")
			(net "MEMDM_1")
		)
		(pad "AB9" smd circle
			(at -1.999996 8.400034 270)
			(size 0.3556 0.3556)
			(layers "F.Cu" "F.Mask" "F.Paste")
			(net "MEMDQS_P0")
		)
		(pad "AB10" smd circle
			(at -1.199896 8.400034 270)
			(size 0.3556 0.3556)
			(layers "F.Cu" "F.Mask" "F.Paste")
			(net "MEMDQS_N0")
		)
		(pad "AB11" smd circle
			(at -0.40005 8.400034 270)
			(size 0.3556 0.3556)
			(layers "F.Cu" "F.Mask" "F.Paste")
			(net "MEMCK_P")
		)
		(pad "AB12" smd circle
			(at 0.40005 8.400034 270)
			(size 0.3556 0.3556)
			(layers "F.Cu" "F.Mask" "F.Paste")
			(net "MEMCK_N")
		)
		(pad "AB13" smd circle
			(at 1.199896 8.400034 270)
			(size 0.3556 0.3556)
			(layers "F.Cu" "F.Mask" "F.Paste")
			(net "MEMCASN")
		)
		(pad "AB14" smd circle
			(at 1.999996 8.400034 270)
			(size 0.3556 0.3556)
			(layers "F.Cu" "F.Mask" "F.Paste")
			(net "MEMA_1")
		)
		(pad "AB15" smd circle
			(at 2.800096 8.400034 270)
			(size 0.3556 0.3556)
			(layers "F.Cu" "F.Mask" "F.Paste")
			(net "MEMA_13")
		)
		(pad "AB16" smd circle
			(at 3.599942 8.400034 270)
			(size 0.3556 0.3556)
			(layers "F.Cu" "F.Mask" "F.Paste")
			(net "MEMA_6")
		)
		(pad "AB17" smd circle
			(at 4.400042 8.400034 270)
			(size 0.3556 0.3556)
			(layers "F.Cu" "F.Mask" "F.Paste")
			(net "DDR4_RST_N")
		)
		(pad "AB18" smd circle
			(at 5.199888 8.400034 270)
			(size 0.3556 0.3556)
			(layers "F.Cu" "F.Mask" "F.Paste")
			(net "PECI")
		)
		(pad "AB19" smd circle
			(at 5.999988 8.400034 270)
			(size 0.3556 0.3556)
			(layers "F.Cu" "F.Mask" "F.Paste")
			(net "FLA_CS_0")
		)
		(pad "AB20" smd circle
			(at 6.800088 8.400034 270)
			(size 0.4064 0.4064)
			(layers "F.Cu" "F.Mask" "F.Paste")
			(net "BMC_ML_PWR_YELLOW_LED")
		)
		(pad "AB21" smd circle
			(at 7.599934 8.400034 270)
			(size 0.4064 0.4064)
			(layers "F.Cu" "F.Mask" "F.Paste")
			(net "BMC_ML_PWR_BLUE_LED")
		)
		(pad "AB22" smd circle
			(at 8.400034 8.400034 270)
			(size 0.4064 0.4064)
			(layers "F.Cu" "F.Mask" "F.Paste")
			(net "GND")
		)
		(pad "B1" smd circle
			(at -8.400034 -7.599934 270)
			(size 0.4064 0.4064)
			(layers "F.Cu" "F.Mask" "F.Paste")
			(net "MAC2_TXCTL")
		)
		(pad "B2" smd circle
			(at -7.599934 -7.599934 270)
			(size 0.4064 0.4064)
			(layers "F.Cu" "F.Mask" "F.Paste")
			(net "TP_BMC_GPIOT6")
		)
		(pad "B3" smd circle
			(at -6.800088 -7.599934 270)
			(size 0.4064 0.4064)
			(layers "F.Cu" "F.Mask" "F.Paste")
			(net "MAC2_TXD1")
		)
		(pad "B4" smd circle
			(at -5.999988 -7.599934 270)
			(size 0.3556 0.3556)
			(layers "F.Cu" "F.Mask" "F.Paste")
			(net "CLK_50M_BMC_NCSI")
		)
		(pad "B5" smd circle
			(at -5.199888 -7.599934 270)
			(size 0.3556 0.3556)
			(layers "F.Cu" "F.Mask" "F.Paste")
			(net "TP_BMC_GPIOT0")
		)
		(pad "B6" smd circle
			(at -4.400042 -7.599934 270)
			(size 0.3556 0.3556)
			(layers "F.Cu" "F.Mask" "F.Paste")
			(net "USB_P3_DP")
		)
		(pad "B7" smd circle
			(at -3.599942 -7.599934 270)
			(size 0.3556 0.3556)
			(layers "F.Cu" "F.Mask" "F.Paste")
			(net "PD_USB2BVRES")
		)
		(pad "B8" smd circle
			(at -2.800096 -7.599934 270)
			(size 0.3556 0.3556)
			(layers "F.Cu" "F.Mask" "F.Paste")
			(net "PD_USB2AVRES")
		)
		(pad "B9" smd circle
			(at -1.999996 -7.599934 270)
			(size 0.3556 0.3556)
			(layers "F.Cu" "F.Mask" "F.Paste")
			(net "BMC_SMB4_DAT")
		)
		(pad "B10" smd circle
			(at -1.199896 -7.599934 270)
			(size 0.3556 0.3556)
			(layers "F.Cu" "F.Mask" "F.Paste")
			(net "DB_PRSNT_BMC_N")
		)
		(pad "B11" smd circle
			(at -0.40005 -7.599934 270)
			(size 0.3556 0.3556)
			(layers "F.Cu" "F.Mask" "F.Paste")
			(net "BMC_SMB13_DAT")
		)
		(pad "B12" smd circle
			(at 0.40005 -7.599934 270)
			(size 0.3556 0.3556)
			(layers "F.Cu" "F.Mask" "F.Paste")
			(net "BMC_SMB11_CLK")
		)
		(pad "B13" smd circle
			(at 1.199896 -7.599934 270)
			(size 0.3556 0.3556)
			(layers "F.Cu" "F.Mask" "F.Paste")
			(net "TP_BMC_GPIOA7")
		)
		(pad "B14" smd circle
			(at 1.999996 -7.599934 270)
			(size 0.3556 0.3556)
			(layers "F.Cu" "F.Mask" "F.Paste")
			(net "TP_BMC_GPIOA0")
		)
		(pad "B15" smd circle
			(at 2.800096 -7.599934 270)
			(size 0.3556 0.3556)
			(layers "F.Cu" "F.Mask" "F.Paste")
			(net "TP_BMC_GPIOI4")
		)
		(pad "B16" smd circle
			(at 3.599942 -7.599934 270)
			(size 0.3556 0.3556)
			(layers "F.Cu" "F.Mask" "F.Paste")
			(net "TP_BMC_GPIOI2")
		)
		(pad "B17" smd circle
			(at 4.400042 -7.599934 270)
			(size 0.3556 0.3556)
			(layers "F.Cu" "F.Mask" "F.Paste")
			(net "LED_POSTCODE_5")
		)
		(pad "B18" smd circle
			(at 5.199888 -7.599934 270)
			(size 0.3556 0.3556)
			(layers "F.Cu" "F.Mask" "F.Paste")
			(net "LED_POSTCODE_1")
		)
		(pad "B19" smd circle
			(at 5.999988 -7.599934 270)
			(size 0.3556 0.3556)
			(layers "F.Cu" "F.Mask" "F.Paste")
			(net "TP_BMC_EXT2_LED_G")
		)
		(pad "B20" smd circle
			(at 6.800088 -7.599934 270)
			(size 0.4064 0.4064)
			(layers "F.Cu" "F.Mask" "F.Paste")
			(net "M2_1_PRESENT_N")
		)
		(pad "B21" smd circle
			(at 7.599934 -7.599934 270)
			(size 0.4064 0.4064)
			(layers "F.Cu" "F.Mask" "F.Paste")
			(net "EXP_SPARE_1_R")
		)
		(pad "B22" smd circle
			(at 8.400034 -7.599934 270)
			(size 0.4064 0.4064)
			(layers "F.Cu" "F.Mask" "F.Paste")
			(net "EXP_SPARE_0_R")
		)
		(pad "C1" smd circle
			(at -8.400034 -6.800088 270)
			(size 0.4064 0.4064)
			(layers "F.Cu" "F.Mask" "F.Paste")
			(net "BMC_RGMII_A4_D3")
		)
		(pad "C2" smd circle
			(at -7.599934 -6.800088 270)
			(size 0.4064 0.4064)
			(layers "F.Cu" "F.Mask" "F.Paste")
			(net "BMC_RGMII_C2_C3_D1_D2_E6")
		)
		(pad "C3" smd circle
			(at -6.800088 -6.800088 270)
			(size 0.4064 0.4064)
			(layers "F.Cu" "F.Mask" "F.Paste")
			(net "BMC_RGMII_C2_C3_D1_D2_E6")
		)
		(pad "C4" smd circle
			(at -5.999988 -6.800088 270)
			(size 0.3556 0.3556)
			(layers "F.Cu" "F.Mask" "F.Paste")
			(net "NCSI_RX_ER")
		)
		(pad "C5" smd circle
			(at -5.199888 -6.800088 270)
			(size 0.3556 0.3556)
			(layers "F.Cu" "F.Mask" "F.Paste")
			(net "NCSI_RCSDV")
		)
		(pad "C6" smd circle
			(at -4.400042 -6.800088 270)
			(size 0.3556 0.3556)
			(layers "F.Cu" "F.Mask" "F.Paste")
			(net "GND")
		)
		(pad "C7" smd circle
			(at -3.599942 -6.800088 270)
			(size 0.3556 0.3556)
			(layers "F.Cu" "F.Mask" "F.Paste")
			(net "P3V3_STBY")
		)
		(pad "C8" smd circle
			(at -2.800096 -6.800088 270)
			(size 0.3556 0.3556)
			(layers "F.Cu" "F.Mask" "F.Paste")
			(net "JTAG_BMC_TMS")
		)
		(pad "C9" smd circle
			(at -1.999996 -6.800088 270)
			(size 0.3556 0.3556)
			(layers "F.Cu" "F.Mask" "F.Paste")
			(net "BMC0_JTAG_RTCK")
		)
		(pad "C10" smd circle
			(at -1.199896 -6.800088 270)
			(size 0.3556 0.3556)
			(layers "F.Cu" "F.Mask" "F.Paste")
			(net "JTAG_BMC_TCK")
		)
		(pad "C11" smd circle
			(at -0.40005 -6.800088 270)
			(size 0.3556 0.3556)
			(layers "F.Cu" "F.Mask" "F.Paste")
			(net "BMC_SMB13_CLK")
		)
		(pad "C12" smd circle
			(at 0.40005 -6.800088 270)
			(size 0.3556 0.3556)
			(layers "F.Cu" "F.Mask" "F.Paste")
			(net "BMC_SMB10_CLK")
		)
		(pad "C13" smd circle
			(at 1.199896 -6.800088 270)
			(size 0.3556 0.3556)
			(layers "F.Cu" "F.Mask" "F.Paste")
			(net "TP_BMC_GPIOA6")
		)
		(pad "C14" smd circle
			(at 1.999996 -6.800088 270)
			(size 0.3556 0.3556)
			(layers "F.Cu" "F.Mask" "F.Paste")
			(net "BMC_SMB9_CLK")
		)
		(pad "C15" smd circle
			(at 2.800096 -6.800088 270)
			(size 0.3556 0.3556)
			(layers "F.Cu" "F.Mask" "F.Paste")
			(net "TP_BMC_GPIOI5")
		)
		(pad "C16" smd circle
			(at 3.599942 -6.800088 270)
			(size 0.3556 0.3556)
			(layers "F.Cu" "F.Mask" "F.Paste")
			(net "TP_BMC_GPIOI3")
		)
		(pad "C17" smd circle
			(at 4.400042 -6.800088 270)
			(size 0.3556 0.3556)
			(layers "F.Cu" "F.Mask" "F.Paste")
			(net "LED_POSTCODE_3")
		)
		(pad "C18" smd circle
			(at 5.199888 -6.800088 270)
			(size 0.3556 0.3556)
			(layers "F.Cu" "F.Mask" "F.Paste")
			(net "TP_BMC_GPIOI0")
		)
		(pad "C19" smd circle
			(at 5.999988 -6.800088 270)
			(size 0.3556 0.3556)
			(layers "F.Cu" "F.Mask" "F.Paste")
			(net "COMP_SPARE_0_R")
		)
		(pad "C20" smd circle
			(at 6.800088 -6.800088 270)
			(size 0.4064 0.4064)
			(layers "F.Cu" "F.Mask" "F.Paste")
			(net "M2_2_PRESENT_N")
		)
		(pad "C21" smd circle
			(at 7.599934 -6.800088 270)
			(size 0.4064 0.4064)
			(layers "F.Cu" "F.Mask" "F.Paste")
			(net "Net_548")
		)
		(pad "C22" smd circle
			(at 8.400034 -6.800088 270)
			(size 0.4064 0.4064)
			(layers "F.Cu" "F.Mask" "F.Paste")
			(net "LPC_CPU_CLKOUT0")
		)
		(pad "D1" smd circle
			(at -8.400034 -5.999988 270)
			(size 0.3556 0.3556)
			(layers "F.Cu" "F.Mask" "F.Paste")
			(net "BMC_RGMII_C2_C3_D1_D2_E6")
		)
		(pad "D2" smd circle
			(at -7.599934 -5.999988 270)
			(size 0.3556 0.3556)
			(layers "F.Cu" "F.Mask" "F.Paste")
			(net "BMC_RGMII_C2_C3_D1_D2_E6")
		)
		(pad "D3" smd circle
			(at -6.800088 -5.999988 270)
			(size 0.3556 0.3556)
			(layers "F.Cu" "F.Mask" "F.Paste")
			(net "BMC_RGMII_A4_D3")
		)
		(pad "D4" smd circle
			(at -5.999988 -5.999988 270)
			(size 0.3556 0.3556)
			(layers "F.Cu" "F.Mask" "F.Paste")
			(net "MAC2_TXD3")
		)
		(pad "D5" smd circle
			(at -5.199888 -5.999988 270)
			(size 0.3556 0.3556)
			(layers "F.Cu" "F.Mask" "F.Paste")
			(net "MAC2_TXD2")
		)
		(pad "D6" smd circle
			(at -4.400042 -5.999988 270)
			(size 0.3556 0.3556)
			(layers "F.Cu" "F.Mask" "F.Paste")
			(net "NCSI_RXD1")
		)
		(pad "D7" smd circle
			(at -3.599942 -5.999988 270)
			(size 0.3556 0.3556)
			(layers "F.Cu" "F.Mask" "F.Paste")
			(net "MAC1_TXD3")
		)
		(pad "D8" smd circle
			(at -2.800096 -5.999988 270)
			(size 0.3556 0.3556)
			(layers "F.Cu" "F.Mask" "F.Paste")
			(net "RMII_BMC_MDC_R")
		)
		(pad "D9" smd circle
			(at -1.999996 -5.999988 270)
			(size 0.3556 0.3556)
			(layers "F.Cu" "F.Mask" "F.Paste")
			(net "BMC_SMB11_DAT")
		)
		(pad "D10" smd circle
			(at -1.199896 -5.999988 270)
			(size 0.3556 0.3556)
			(layers "F.Cu" "F.Mask" "F.Paste")
			(net "BMC_SMB12_CLK")
		)
		(pad "D11" smd circle
			(at -0.40005 -5.999988 270)
			(size 0.3556 0.3556)
			(layers "F.Cu" "F.Mask" "F.Paste")
			(net "JTAG_BMC_TDO")
		)
		(pad "D12" smd circle
			(at 0.40005 -5.999988 270)
			(size 0.3556 0.3556)
			(layers "F.Cu" "F.Mask" "F.Paste")
			(net "JTAG_BMC_TDI")
		)
		(pad "D13" smd circle
			(at 1.199896 -5.999988 270)
			(size 0.3556 0.3556)
			(layers "F.Cu" "F.Mask" "F.Paste")
			(net "BMC_TO_EXP_RESET_OUT")
		)
		(pad "D14" smd circle
			(at 1.999996 -5.999988 270)
			(size 0.3556 0.3556)
			(layers "F.Cu" "F.Mask" "F.Paste")
			(net "USB_OCS_N1")
		)
		(pad "D15" smd circle
			(at 2.800096 -5.999988 270)
			(size 0.3556 0.3556)
			(layers "F.Cu" "F.Mask" "F.Paste")
			(net "Net_8")
		)
		(pad "D16" smd circle
			(at 3.599942 -5.999988 270)
			(size 0.3556 0.3556)
			(layers "F.Cu" "F.Mask" "F.Paste")
			(net "Net_7")
		)
		(pad "D17" smd circle
			(at 4.400042 -5.999988 270)
			(size 0.3556 0.3556)
			(layers "F.Cu" "F.Mask" "F.Paste")
			(net "LED_POSTCODE_2")
		)
		(pad "D18" smd circle
			(at 5.199888 -5.999988 270)
			(size 0.3556 0.3556)
			(layers "F.Cu" "F.Mask" "F.Paste")
			(net "LED_POSTCODE_7")
		)
		(pad "D19" smd circle
			(at 5.999988 -5.999988 270)
			(size 0.3556 0.3556)
			(layers "F.Cu" "F.Mask" "F.Paste")
			(net "TP_BMC_EXT1_LED_G")
		)
		(pad "D20" smd circle
			(at 6.800088 -5.999988 270)
			(size 0.3556 0.3556)
			(layers "F.Cu" "F.Mask" "F.Paste")
			(net "COMP_PWR_BTN_R_N")
		)
		(pad "D21" smd circle
			(at 7.599934 -5.999988 270)
			(size 0.3556 0.3556)
			(layers "F.Cu" "F.Mask" "F.Paste")
			(net "RSTBTN_OUT_N_R")
		)
		(pad "D22" smd circle
			(at 8.400034 -5.999988 270)
			(size 0.3556 0.3556)
			(layers "F.Cu" "F.Mask" "F.Paste")
			(net "TP_BMC0_LPC_LAD2")
		)
		(pad "E1" smd circle
			(at -8.400034 -5.199888 270)
			(size 0.3556 0.3556)
			(layers "F.Cu" "F.Mask" "F.Paste")
			(net "ADC_P1V8_STBY")
		)
		(pad "E2" smd circle
			(at -7.599934 -5.199888 270)
			(size 0.3556 0.3556)
			(layers "F.Cu" "F.Mask" "F.Paste")
			(net "ADC_P3V3_STBY")
		)
		(pad "E3" smd circle
			(at -6.800088 -5.199888 270)
			(size 0.3556 0.3556)
			(layers "F.Cu" "F.Mask" "F.Paste")
			(net "ADC_P1V2_STBY")
		)
		(pad "E4" smd circle
			(at -5.999988 -5.199888 270)
			(size 0.3556 0.3556)
			(layers "F.Cu" "F.Mask" "F.Paste")
			(net "P3V3_STBY")
		)
		(pad "E5" smd circle
			(at -5.199888 -5.199888 270)
			(size 0.3556 0.3556)
			(layers "F.Cu" "F.Mask" "F.Paste")
			(net "GND")
		)
		(pad "E6" smd circle
			(at -4.400042 -5.199888 270)
			(size 0.3556 0.3556)
			(layers "F.Cu" "F.Mask" "F.Paste")
			(net "BMC_RGMII_C2_C3_D1_D2_E6")
		)
		(pad "E7" smd circle
			(at -3.599942 -5.199888 270)
			(size 0.3556 0.3556)
			(layers "F.Cu" "F.Mask" "F.Paste")
			(net "MAC1_TXD2")
		)
		(pad "E8" smd circle
			(at -2.800096 -5.199888 270)
			(size 0.3556 0.3556)
			(layers "F.Cu" "F.Mask" "F.Paste")
			(net "GND")
		)
		(pad "E9" smd circle
			(at -1.999996 -5.199888 270)
			(size 0.3556 0.3556)
			(layers "F.Cu" "F.Mask" "F.Paste")
			(net "NCSI_TXEN")
		)
		(pad "E10" smd circle
			(at -1.199896 -5.199888 270)
			(size 0.3556 0.3556)
			(layers "F.Cu" "F.Mask" "F.Paste")
			(net "RMII_BMC_MDIO_R")
		)
		(pad "E11" smd circle
			(at -0.40005 -5.199888 270)
			(size 0.3556 0.3556)
			(layers "F.Cu" "F.Mask" "F.Paste")
			(net "JTAG_BMC_TRST_N")
		)
		(pad "E12" smd circle
			(at 0.40005 -5.199888 270)
			(size 0.3556 0.3556)
			(layers "F.Cu" "F.Mask" "F.Paste")
			(net "BMC_SMB12_DAT")
		)
		(pad "E13" smd circle
			(at 1.199896 -5.199888 270)
			(size 0.3556 0.3556)
			(layers "F.Cu" "F.Mask" "F.Paste")
			(net "SYS_PWR_LED")
		)
		(pad "E14" smd circle
			(at 1.999996 -5.199888 270)
			(size 0.3556 0.3556)
			(layers "F.Cu" "F.Mask" "F.Paste")
			(net "I2C_COMP_ALERT_N")
		)
		(pad "E15" smd circle
			(at 2.800096 -5.199888 270)
			(size 0.3556 0.3556)
			(layers "F.Cu" "F.Mask" "F.Paste")
			(net "TP_BMC_GPIOI1")
		)
		(pad "E16" smd circle
			(at 3.599942 -5.199888 270)
			(size 0.3556 0.3556)
			(layers "F.Cu" "F.Mask" "F.Paste")
			(net "COMP_SPARE_1_R")
		)
		(pad "E17" smd circle
			(at 4.400042 -5.199888 270)
			(size 0.3556 0.3556)
			(layers "F.Cu" "F.Mask" "F.Paste")
			(net "SYS_RST_EN")
		)
		(pad "E18" smd circle
			(at 5.199888 -5.199888 270)
			(size 0.3556 0.3556)
			(layers "F.Cu" "F.Mask" "F.Paste")
			(net "TP_BMC_EXT1_LED_B")
		)
		(pad "E19" smd circle
			(at 5.999988 -5.199888 270)
			(size 0.3556 0.3556)
			(layers "F.Cu" "F.Mask" "F.Paste")
			(net "SLOTID_1")
		)
		(pad "E20" smd circle
			(at 6.800088 -5.199888 270)
			(size 0.3556 0.3556)
			(layers "F.Cu" "F.Mask" "F.Paste")
			(net "SYS_RESET_N_OUT_R")
		)
		(pad "E21" smd circle
			(at 7.599934 -5.199888 270)
			(size 0.3556 0.3556)
			(layers "F.Cu" "F.Mask" "F.Paste")
			(net "Net_547")
		)
		(pad "E22" smd circle
			(at 8.400034 -5.199888 270)
			(size 0.3556 0.3556)
			(layers "F.Cu" "F.Mask" "F.Paste")
			(net "TP_BMC0_LPC_LAD3")
		)
		(pad "F1" smd circle
			(at -8.400034 -4.400042 270)
			(size 0.3556 0.3556)
			(layers "F.Cu" "F.Mask" "F.Paste")
			(net "ADC_P3V3_M2")
		)
		(pad "F2" smd circle
			(at -7.599934 -4.400042 270)
			(size 0.3556 0.3556)
			(layers "F.Cu" "F.Mask" "F.Paste")
			(net "ADC_P1V8")
		)
		(pad "F3" smd circle
			(at -6.800088 -4.400042 270)
			(size 0.3556 0.3556)
			(layers "F.Cu" "F.Mask" "F.Paste")
			(net "ADC_P2V5_STBY")
		)
		(pad "F4" smd circle
			(at -5.999988 -4.400042 270)
			(size 0.3556 0.3556)
			(layers "F.Cu" "F.Mask" "F.Paste")
			(net "ADC_12V")
		)
		(pad "F5" smd circle
			(at -5.199888 -4.400042 270)
			(size 0.3556 0.3556)
			(layers "F.Cu" "F.Mask" "F.Paste")
			(net "ADC_P5V_STBY")
		)
		(pad "F6" smd circle
			(at -4.400042 -4.400042 270)
			(size 0.3556 0.3556)
			(layers "F.Cu" "F.Mask" "F.Paste")
			(net "P1V15_STBY")
		)
		(pad "F7" smd circle
			(at -3.599942 -4.400042 270)
			(size 0.3556 0.3556)
			(layers "F.Cu" "F.Mask" "F.Paste")
			(net "P3V3_STBY")
		)
		(pad "F8" smd circle
			(at -2.800096 -4.400042 270)
			(size 0.3556 0.3556)
			(layers "F.Cu" "F.Mask" "F.Paste")
			(net "P3V3_STBY")
		)
		(pad "F9" smd circle
			(at -1.999996 -4.400042 270)
			(size 0.3556 0.3556)
			(layers "F.Cu" "F.Mask" "F.Paste")
			(net "NCSI_TXD0_R")
		)
		(pad "F10" smd circle
			(at -1.199896 -4.400042 270)
			(size 0.3556 0.3556)
			(layers "F.Cu" "F.Mask" "F.Paste")
			(net "P3V3_STBY")
		)
		(pad "F11" smd circle
			(at -0.40005 -4.400042 270)
			(size 0.3556 0.3556)
			(layers "F.Cu" "F.Mask" "F.Paste")
			(net "P3V3_STBY")
		)
		(pad "F12" smd circle
			(at 0.40005 -4.400042 270)
			(size 0.3556 0.3556)
			(layers "F.Cu" "F.Mask" "F.Paste")
			(net "P3V3_STBY")
		)
		(pad "F13" smd circle
			(at 1.199896 -4.400042 270)
			(size 0.3556 0.3556)
			(layers "F.Cu" "F.Mask" "F.Paste")
			(net "P3V3_STBY")
		)
		(pad "F14" smd circle
			(at 1.999996 -4.400042 270)
			(size 0.3556 0.3556)
			(layers "F.Cu" "F.Mask" "F.Paste")
			(net "P3V3_STBY")
		)
		(pad "F15" smd circle
			(at 2.800096 -4.400042 270)
			(size 0.3556 0.3556)
			(layers "F.Cu" "F.Mask" "F.Paste")
			(net "P3V3_STBY")
		)
		(pad "F16" smd circle
			(at 3.599942 -4.400042 270)
			(size 0.3556 0.3556)
			(layers "F.Cu" "F.Mask" "F.Paste")
			(net "GND")
		)
		(pad "F17" smd circle
			(at 4.400042 -4.400042 270)
			(size 0.3556 0.3556)
			(layers "F.Cu" "F.Mask" "F.Paste")
			(net "M2_2_ACTIVE_N")
		)
		(pad "F18" smd circle
			(at 5.199888 -4.400042 270)
			(size 0.3556 0.3556)
			(layers "F.Cu" "F.Mask" "F.Paste")
			(net "M2_1_ACTIVE_N")
		)
		(pad "F19" smd circle
			(at 5.999988 -4.400042 270)
			(size 0.3556 0.3556)
			(layers "F.Cu" "F.Mask" "F.Paste")
			(net "Net_546")
		)
		(pad "F20" smd circle
			(at 6.800088 -4.400042 270)
			(size 0.3556 0.3556)
			(layers "F.Cu" "F.Mask" "F.Paste")
			(net "PWRBTN_OUT_N_R")
		)
		(pad "F21" smd circle
			(at 7.599934 -4.400042 270)
			(size 0.3556 0.3556)
			(layers "F.Cu" "F.Mask" "F.Paste")
			(net "LPC_CPU_FRAME_N")
		)
		(pad "F22" smd circle
			(at 8.400034 -4.400042 270)
			(size 0.3556 0.3556)
			(layers "F.Cu" "F.Mask" "F.Paste")
			(net "IRQ_CPU_SERIAL")
		)
		(pad "G1" smd circle
			(at -8.400034 -3.599942 270)
			(size 0.3556 0.3556)
			(layers "F.Cu" "F.Mask" "F.Paste")
			(net "GND")
		)
		(pad "G2" smd circle
			(at -7.599934 -3.599942 270)
			(size 0.3556 0.3556)
			(layers "F.Cu" "F.Mask" "F.Paste")
			(net "ADC_P0V975")
		)
		(pad "G3" smd circle
			(at -6.800088 -3.599942 270)
			(size 0.3556 0.3556)
			(layers "F.Cu" "F.Mask" "F.Paste")
			(net "ADC_P1V5")
		)
		(pad "G4" smd circle
			(at -5.999988 -3.599942 270)
			(size 0.3556 0.3556)
			(layers "F.Cu" "F.Mask" "F.Paste")
			(net "ADC_P3V3")
		)
		(pad "G5" smd circle
			(at -5.199888 -3.599942 270)
			(size 0.3556 0.3556)
			(layers "F.Cu" "F.Mask" "F.Paste")
			(net "ADC_P1V15_STBY")
		)
		(pad "G6" smd circle
			(at -4.400042 -3.599942 270)
			(size 0.3556 0.3556)
			(layers "F.Cu" "F.Mask" "F.Paste")
			(net "GND")
		)
		(pad "G7" smd circle
			(at -3.599942 -3.599942 270)
			(size 0.3556 0.3556)
			(layers "F.Cu" "F.Mask" "F.Paste")
			(net "P1V15_STBY")
		)
		(pad "G8" smd circle
			(at -2.800096 -3.599942 270)
			(size 0.3556 0.3556)
			(layers "F.Cu" "F.Mask" "F.Paste")
			(net "P1V15_STBY")
		)
		(pad "G9" smd circle
			(at -1.999996 -3.599942 270)
			(size 0.3556 0.3556)
			(layers "F.Cu" "F.Mask" "F.Paste")
			(net "P1V15_STBY")
		)
		(pad "G10" smd circle
			(at -1.199896 -3.599942 270)
			(size 0.3556 0.3556)
			(layers "F.Cu" "F.Mask" "F.Paste")
			(net "P1V15_STBY")
		)
		(pad "G11" smd circle
			(at -0.40005 -3.599942 270)
			(size 0.3556 0.3556)
			(layers "F.Cu" "F.Mask" "F.Paste")
			(net "P1V15_STBY")
		)
		(pad "G12" smd circle
			(at 0.40005 -3.599942 270)
			(size 0.3556 0.3556)
			(layers "F.Cu" "F.Mask" "F.Paste")
			(net "P1V15_STBY")
		)
		(pad "G13" smd circle
			(at 1.199896 -3.599942 270)
			(size 0.3556 0.3556)
			(layers "F.Cu" "F.Mask" "F.Paste")
			(net "P1V15_STBY")
		)
		(pad "G14" smd circle
			(at 1.999996 -3.599942 270)
			(size 0.3556 0.3556)
			(layers "F.Cu" "F.Mask" "F.Paste")
			(net "P1V15_STBY")
		)
		(pad "G15" smd circle
			(at 2.800096 -3.599942 270)
			(size 0.3556 0.3556)
			(layers "F.Cu" "F.Mask" "F.Paste")
			(net "P1V15_STBY")
		)
		(pad "G16" smd circle
			(at 3.599942 -3.599942 270)
			(size 0.3556 0.3556)
			(layers "F.Cu" "F.Mask" "F.Paste")
			(net "P3V3_STBY")
		)
		(pad "G17" smd circle
			(at 4.400042 -3.599942 270)
			(size 0.3556 0.3556)
			(layers "F.Cu" "F.Mask" "F.Paste")
			(net "P12V_A_PGOOD_R")
		)
		(pad "G18" smd circle
			(at 5.199888 -3.599942 270)
			(size 0.3556 0.3556)
			(layers "F.Cu" "F.Mask" "F.Paste")
			(net "Net_545")
		)
		(pad "G19" smd circle
			(at 5.999988 -3.599942 270)
			(size 0.3556 0.3556)
			(layers "F.Cu" "F.Mask" "F.Paste")
			(net "GND")
		)
		(pad "G20" smd circle
			(at 6.800088 -3.599942 270)
			(size 0.3556 0.3556)
			(layers "F.Cu" "F.Mask" "F.Paste")
			(net "TP_BMC0_LPC_LAD1")
		)
		(pad "G21" smd circle
			(at 7.599934 -3.599942 270)
			(size 0.3556 0.3556)
			(layers "F.Cu" "F.Mask" "F.Paste")
			(net "TP_BMC0_LPC_LAD0")
		)
		(pad "G22" smd circle
			(at 8.400034 -3.599942 270)
			(size 0.3556 0.3556)
			(layers "F.Cu" "F.Mask" "F.Paste")
			(net "LPCRST0_N")
		)
		(pad "H1" smd circle
			(at -8.400034 -2.800096 270)
			(size 0.3556 0.3556)
			(layers "F.Cu" "F.Mask" "F.Paste")
			(net "ADCVREFFN")
		)
		(pad "H2" smd circle
			(at -7.599934 -2.800096 270)
			(size 0.3556 0.3556)
			(layers "F.Cu" "F.Mask" "F.Paste")
			(net "ADCVREFFP")
		)
		(pad "H3" smd circle
			(at -6.800088 -2.800096 270)
			(size 0.3556 0.3556)
			(layers "F.Cu" "F.Mask" "F.Paste")
			(net "GND")
		)
		(pad "H4" smd circle
			(at -5.999988 -2.800096 270)
			(size 0.3556 0.3556)
			(layers "F.Cu" "F.Mask" "F.Paste")
			(net "GND")
		)
		(pad "H5" smd circle
			(at -5.199888 -2.800096 270)
			(size 0.3556 0.3556)
			(layers "F.Cu" "F.Mask" "F.Paste")
			(net "GND")
		)
		(pad "H6" smd circle
			(at -4.400042 -2.800096 270)
			(size 0.3556 0.3556)
			(layers "F.Cu" "F.Mask" "F.Paste")
			(net "GND")
		)
		(pad "H7" smd circle
			(at -3.599942 -2.800096 270)
			(size 0.3556 0.3556)
			(layers "F.Cu" "F.Mask" "F.Paste")
			(net "VPLLAV33")
		)
		(pad "H16" smd circle
			(at 3.599942 -2.800096 270)
			(size 0.3556 0.3556)
			(layers "F.Cu" "F.Mask" "F.Paste")
			(net "P1V15_STBY")
		)
		(pad "H17" smd circle
			(at 4.400042 -2.800096 270)
			(size 0.3556 0.3556)
			(layers "F.Cu" "F.Mask" "F.Paste")
			(net "P3V3_STBY")
		)
		(pad "H18" smd circle
			(at 5.199888 -2.800096 270)
			(size 0.3556 0.3556)
			(layers "F.Cu" "F.Mask" "F.Paste")
			(net "SCC_RMT_TYPE_0_R")
		)
		(pad "H19" smd circle
			(at 5.999988 -2.800096 270)
			(size 0.3556 0.3556)
			(layers "F.Cu" "F.Mask" "F.Paste")
			(net "DPB_MISC_ALERT_O_R")
		)
		(pad "H20" smd circle
			(at 6.800088 -2.800096 270)
			(size 0.3556 0.3556)
			(layers "F.Cu" "F.Mask" "F.Paste")
			(net "Net_544")
		)
		(pad "H21" smd circle
			(at 7.599934 -2.800096 270)
			(size 0.3556 0.3556)
			(layers "F.Cu" "F.Mask" "F.Paste")
			(net "M2_2_ALERT#_R")
		)
		(pad "H22" smd circle
			(at 8.400034 -2.800096 270)
			(size 0.3556 0.3556)
			(layers "F.Cu" "F.Mask" "F.Paste")
			(net "Net_543")
		)
		(pad "J1" smd circle
			(at -8.400034 -1.999996 270)
			(size 0.3556 0.3556)
			(layers "F.Cu" "F.Mask" "F.Paste")
			(net "ADCVREXT")
		)
		(pad "J2" smd circle
			(at -7.599934 -1.999996 270)
			(size 0.3556 0.3556)
			(layers "F.Cu" "F.Mask" "F.Paste")
			(net "Net_559")
		)
		(pad "J3" smd circle
			(at -6.800088 -1.999996 270)
			(size 0.3556 0.3556)
			(layers "F.Cu" "F.Mask" "F.Paste")
			(net "Net_558")
		)
		(pad "J4" smd circle
			(at -5.999988 -1.999996 270)
			(size 0.3556 0.3556)
			(layers "F.Cu" "F.Mask" "F.Paste")
			(net "Net_557")
		)
		(pad "J5" smd circle
			(at -5.199888 -1.999996 270)
			(size 0.3556 0.3556)
			(layers "F.Cu" "F.Mask" "F.Paste")
			(net "GND")
		)
		(pad "J6" smd circle
			(at -4.400042 -1.999996 270)
			(size 0.3556 0.3556)
			(layers "F.Cu" "F.Mask" "F.Paste")
			(net "ADCAV33")
		)
		(pad "J7" smd circle
			(at -3.599942 -1.999996 270)
			(size 0.3556 0.3556)
			(layers "F.Cu" "F.Mask" "F.Paste")
			(net "VPLLAV33")
		)
		(pad "J9" smd circle
			(at -1.999996 -1.999996 270)
			(size 0.3556 0.3556)
			(layers "F.Cu" "F.Mask" "F.Paste")
			(net "GND")
		)
		(pad "J10" smd circle
			(at -1.199896 -1.999996 270)
			(size 0.3556 0.3556)
			(layers "F.Cu" "F.Mask" "F.Paste")
			(net "GND")
		)
		(pad "J11" smd circle
			(at -0.40005 -1.999996 270)
			(size 0.3556 0.3556)
			(layers "F.Cu" "F.Mask" "F.Paste")
			(net "GND")
		)
		(pad "J12" smd circle
			(at 0.40005 -1.999996 270)
			(size 0.3556 0.3556)
			(layers "F.Cu" "F.Mask" "F.Paste")
			(net "GND")
		)
		(pad "J13" smd circle
			(at 1.199896 -1.999996 270)
			(size 0.3556 0.3556)
			(layers "F.Cu" "F.Mask" "F.Paste")
			(net "GND")
		)
		(pad "J14" smd circle
			(at 1.999996 -1.999996 270)
			(size 0.3556 0.3556)
			(layers "F.Cu" "F.Mask" "F.Paste")
			(net "GND")
		)
		(pad "J16" smd circle
			(at 3.599942 -1.999996 270)
			(size 0.3556 0.3556)
			(layers "F.Cu" "F.Mask" "F.Paste")
			(net "P1V15_STBY")
		)
		(pad "J17" smd circle
			(at 4.400042 -1.999996 270)
			(size 0.3556 0.3556)
			(layers "F.Cu" "F.Mask" "F.Paste")
			(net "P1V8_STBY")
		)
		(pad "J18" smd circle
			(at 5.199888 -1.999996 270)
			(size 0.3556 0.3556)
			(layers "F.Cu" "F.Mask" "F.Paste")
			(net "SCC_RMT_FULLPWR_EN")
		)
		(pad "J19" smd circle
			(at 5.999988 -1.999996 270)
			(size 0.3556 0.3556)
			(layers "F.Cu" "F.Mask" "F.Paste")
			(net "SCC_LOC_FULLPWR_EN")
		)
		(pad "J20" smd circle
			(at 6.800088 -1.999996 270)
			(size 0.3556 0.3556)
			(layers "F.Cu" "F.Mask" "F.Paste")
			(net "M2_1_ALERT#_R")
		)
		(pad "J21" smd circle
			(at 7.599934 -1.999996 270)
			(size 0.3556 0.3556)
			(layers "F.Cu" "F.Mask" "F.Paste")
			(net "GND")
		)
		(pad "J22" smd circle
			(at 8.400034 -1.999996 270)
			(size 0.3556 0.3556)
			(layers "F.Cu" "F.Mask" "F.Paste")
			(net "GND")
		)
		(pad "K1" smd circle
			(at -8.400034 -1.199896 270)
			(size 0.3556 0.3556)
			(layers "F.Cu" "F.Mask" "F.Paste")
			(net "UART_BMC_R_TX")
		)
		(pad "K2" smd circle
			(at -7.599934 -1.199896 270)
			(size 0.3556 0.3556)
			(layers "F.Cu" "F.Mask" "F.Paste")
			(net "UART_BMC_R_RX")
		)
		(pad "K3" smd circle
			(at -6.800088 -1.199896 270)
			(size 0.3556 0.3556)
			(layers "F.Cu" "F.Mask" "F.Paste")
			(net "BMC_ENTEST")
		)
		(pad "K4" smd circle
			(at -5.999988 -1.199896 270)
			(size 0.3556 0.3556)
			(layers "F.Cu" "F.Mask" "F.Paste")
			(net "DACRSET")
		)
		(pad "K5" smd circle
			(at -5.199888 -1.199896 270)
			(size 0.3556 0.3556)
			(layers "F.Cu" "F.Mask" "F.Paste")
			(net "DACAV33")
		)
		(pad "K6" smd circle
			(at -4.400042 -1.199896 270)
			(size 0.3556 0.3556)
			(layers "F.Cu" "F.Mask" "F.Paste")
			(net "DACAV33")
		)
		(pad "K7" smd circle
			(at -3.599942 -1.199896 270)
			(size 0.3556 0.3556)
			(layers "F.Cu" "F.Mask" "F.Paste")
			(net "P3V3_STBY")
		)
		(pad "K9" smd circle
			(at -1.999996 -1.199896 270)
			(size 0.3556 0.3556)
			(layers "F.Cu" "F.Mask" "F.Paste")
			(net "GND")
		)
		(pad "K10" smd circle
			(at -1.199896 -1.199896 270)
			(size 0.3556 0.3556)
			(layers "F.Cu" "F.Mask" "F.Paste")
			(net "GND")
		)
		(pad "K11" smd circle
			(at -0.40005 -1.199896 270)
			(size 0.3556 0.3556)
			(layers "F.Cu" "F.Mask" "F.Paste")
			(net "GND")
		)
		(pad "K12" smd circle
			(at 0.40005 -1.199896 270)
			(size 0.3556 0.3556)
			(layers "F.Cu" "F.Mask" "F.Paste")
			(net "GND")
		)
		(pad "K13" smd circle
			(at 1.199896 -1.199896 270)
			(size 0.3556 0.3556)
			(layers "F.Cu" "F.Mask" "F.Paste")
			(net "GND")
		)
		(pad "K14" smd circle
			(at 1.999996 -1.199896 270)
			(size 0.3556 0.3556)
			(layers "F.Cu" "F.Mask" "F.Paste")
			(net "GND")
		)
		(pad "K16" smd circle
			(at 3.599942 -1.199896 270)
			(size 0.3556 0.3556)
			(layers "F.Cu" "F.Mask" "F.Paste")
			(net "GND")
		)
		(pad "K17" smd circle
			(at 4.400042 -1.199896 270)
			(size 0.3556 0.3556)
			(layers "F.Cu" "F.Mask" "F.Paste")
			(net "P1V8_STBY")
		)
		(pad "K18" smd circle
			(at 5.199888 -1.199896 270)
			(size 0.3556 0.3556)
			(layers "F.Cu" "F.Mask" "F.Paste")
			(net "Net_555")
		)
		(pad "K19" smd circle
			(at 5.999988 -1.199896 270)
			(size 0.3556 0.3556)
			(layers "F.Cu" "F.Mask" "F.Paste")
			(net "Net_554")
		)
		(pad "K20" smd circle
			(at 6.800088 -1.199896 270)
			(size 0.3556 0.3556)
			(layers "F.Cu" "F.Mask" "F.Paste")
			(net "BMC_PEREXT")
		)
		(pad "K21" smd circle
			(at 7.599934 -1.199896 270)
			(size 0.3556 0.3556)
			(layers "F.Cu" "F.Mask" "F.Paste")
			(net "GND")
		)
		(pad "K22" smd circle
			(at 8.400034 -1.199896 270)
			(size 0.3556 0.3556)
			(layers "F.Cu" "F.Mask" "F.Paste")
			(net "GND")
		)
		(pad "L1" smd circle
			(at -8.400034 -0.40005 270)
			(size 0.3556 0.3556)
			(layers "F.Cu" "F.Mask" "F.Paste")
			(net "BMC_SMB6_CLK")
		)
		(pad "L2" smd circle
			(at -7.599934 -0.40005 270)
			(size 0.3556 0.3556)
			(layers "F.Cu" "F.Mask" "F.Paste")
			(net "BOARD_REV_1")
		)
		(pad "L3" smd circle
			(at -6.800088 -0.40005 270)
			(size 0.3556 0.3556)
			(layers "F.Cu" "F.Mask" "F.Paste")
			(net "BMC_SMB5_CLK")
		)
		(pad "L4" smd circle
			(at -5.999988 -0.40005 270)
			(size 0.3556 0.3556)
			(layers "F.Cu" "F.Mask" "F.Paste")
			(net "BMC_SMB5_DAT")
		)
		(pad "L5" smd circle
			(at -5.199888 -0.40005 270)
			(size 0.3556 0.3556)
			(layers "F.Cu" "F.Mask" "F.Paste")
			(net "V1PLLAV11")
		)
		(pad "L6" smd circle
			(at -4.400042 -0.40005 270)
			(size 0.3556 0.3556)
			(layers "F.Cu" "F.Mask" "F.Paste")
			(net "V1PLLAV11")
		)
		(pad "L7" smd circle
			(at -3.599942 -0.40005 270)
			(size 0.3556 0.3556)
			(layers "F.Cu" "F.Mask" "F.Paste")
			(net "P1V15_STBY")
		)
		(pad "L9" smd circle
			(at -1.999996 -0.40005 270)
			(size 0.3556 0.3556)
			(layers "F.Cu" "F.Mask" "F.Paste")
			(net "GND")
		)
		(pad "L10" smd circle
			(at -1.199896 -0.40005 270)
			(size 0.3556 0.3556)
			(layers "F.Cu" "F.Mask" "F.Paste")
			(net "GND")
		)
		(pad "L11" smd circle
			(at -0.40005 -0.40005 270)
			(size 0.3556 0.3556)
			(layers "F.Cu" "F.Mask" "F.Paste")
			(net "GND")
		)
		(pad "L12" smd circle
			(at 0.40005 -0.40005 270)
			(size 0.3556 0.3556)
			(layers "F.Cu" "F.Mask" "F.Paste")
			(net "GND")
		)
		(pad "L13" smd circle
			(at 1.199896 -0.40005 270)
			(size 0.3556 0.3556)
			(layers "F.Cu" "F.Mask" "F.Paste")
			(net "GND")
		)
		(pad "L14" smd circle
			(at 1.999996 -0.40005 270)
			(size 0.3556 0.3556)
			(layers "F.Cu" "F.Mask" "F.Paste")
			(net "GND")
		)
		(pad "L16" smd circle
			(at 3.599942 -0.40005 270)
			(size 0.3556 0.3556)
			(layers "F.Cu" "F.Mask" "F.Paste")
			(net "P3V3_STBY")
		)
		(pad "L17" smd circle
			(at 4.400042 -0.40005 270)
			(size 0.3556 0.3556)
			(layers "F.Cu" "F.Mask" "F.Paste")
			(net "P1V15_STBY")
		)
		(pad "L18" smd circle
			(at 5.199888 -0.40005 270)
			(size 0.3556 0.3556)
			(layers "F.Cu" "F.Mask" "F.Paste")
			(net "Net_553")
		)
		(pad "L19" smd circle
			(at 5.999988 -0.40005 270)
			(size 0.3556 0.3556)
			(layers "F.Cu" "F.Mask" "F.Paste")
			(net "Net_552")
		)
		(pad "L20" smd circle
			(at 6.800088 -0.40005 270)
			(size 0.3556 0.3556)
			(layers "F.Cu" "F.Mask" "F.Paste")
			(net "PD_PERST_N")
		)
		(pad "L21" smd circle
			(at 7.599934 -0.40005 270)
			(size 0.3556 0.3556)
			(layers "F.Cu" "F.Mask" "F.Paste")
			(net "Net_551")
		)
		(pad "L22" smd circle
			(at 8.400034 -0.40005 270)
			(size 0.3556 0.3556)
			(layers "F.Cu" "F.Mask" "F.Paste")
			(net "Net_550")
		)
		(pad "M1" smd circle
			(at -8.400034 0.40005 270)
			(size 0.3556 0.3556)
			(layers "F.Cu" "F.Mask" "F.Paste")
			(net "GND")
		)
		(pad "M2" smd circle
			(at -7.599934 0.40005 270)
			(size 0.3556 0.3556)
			(layers "F.Cu" "F.Mask" "F.Paste")
			(net "GND")
		)
		(pad "M3" smd circle
			(at -6.800088 0.40005 270)
			(size 0.3556 0.3556)
			(layers "F.Cu" "F.Mask" "F.Paste")
			(net "GND")
		)
		(pad "M4" smd circle
			(at -5.999988 0.40005 270)
			(size 0.3556 0.3556)
			(layers "F.Cu" "F.Mask" "F.Paste")
			(net "GND")
		)
		(pad "M5" smd circle
			(at -5.199888 0.40005 270)
			(size 0.3556 0.3556)
			(layers "F.Cu" "F.Mask" "F.Paste")
			(net "GND")
		)
		(pad "M6" smd circle
			(at -4.400042 0.40005 270)
			(size 0.3556 0.3556)
			(layers "F.Cu" "F.Mask" "F.Paste")
			(net "GND")
		)
		(pad "M7" smd circle
			(at -3.599942 0.40005 270)
			(size 0.3556 0.3556)
			(layers "F.Cu" "F.Mask" "F.Paste")
			(net "GND")
		)
		(pad "M9" smd circle
			(at -1.999996 0.40005 270)
			(size 0.3556 0.3556)
			(layers "F.Cu" "F.Mask" "F.Paste")
			(net "GND")
		)
		(pad "M10" smd circle
			(at -1.199896 0.40005 270)
			(size 0.3556 0.3556)
			(layers "F.Cu" "F.Mask" "F.Paste")
			(net "GND")
		)
		(pad "M11" smd circle
			(at -0.40005 0.40005 270)
			(size 0.3556 0.3556)
			(layers "F.Cu" "F.Mask" "F.Paste")
			(net "GND")
		)
		(pad "M12" smd circle
			(at 0.40005 0.40005 270)
			(size 0.3556 0.3556)
			(layers "F.Cu" "F.Mask" "F.Paste")
			(net "GND")
		)
		(pad "M13" smd circle
			(at 1.199896 0.40005 270)
			(size 0.3556 0.3556)
			(layers "F.Cu" "F.Mask" "F.Paste")
			(net "GND")
		)
		(pad "M14" smd circle
			(at 1.999996 0.40005 270)
			(size 0.3556 0.3556)
			(layers "F.Cu" "F.Mask" "F.Paste")
			(net "GND")
		)
		(pad "M16" smd circle
			(at 3.599942 0.40005 270)
			(size 0.3556 0.3556)
			(layers "F.Cu" "F.Mask" "F.Paste")
			(net "GND")
		)
		(pad "M17" smd circle
			(at 4.400042 0.40005 270)
			(size 0.3556 0.3556)
			(layers "F.Cu" "F.Mask" "F.Paste")
			(net "GND")
		)
		(pad "M18" smd circle
			(at 5.199888 0.40005 270)
			(size 0.3556 0.3556)
			(layers "F.Cu" "F.Mask" "F.Paste")
			(net "BMC_SMB1_CLK")
		)
		(pad "M19" smd circle
			(at 5.999988 0.40005 270)
			(size 0.3556 0.3556)
			(layers "F.Cu" "F.Mask" "F.Paste")
			(net "BMC_SMB1_DAT")
		)
		(pad "M20" smd circle
			(at 6.800088 0.40005 270)
			(size 0.3556 0.3556)
			(layers "F.Cu" "F.Mask" "F.Paste")
			(net "BMC_SMB2_CLK")
		)
		(pad "M21" smd circle
			(at 7.599934 0.40005 270)
			(size 0.3556 0.3556)
			(layers "F.Cu" "F.Mask" "F.Paste")
			(net "GND")
		)
		(pad "M22" smd circle
			(at 8.400034 0.40005 270)
			(size 0.3556 0.3556)
			(layers "F.Cu" "F.Mask" "F.Paste")
			(net "GND")
		)
		(pad "N1" smd circle
			(at -8.400034 1.199896 270)
			(size 0.3556 0.3556)
			(layers "F.Cu" "F.Mask" "F.Paste")
			(net "BMC_SMB7_CLK")
		)
		(pad "N2" smd circle
			(at -7.599934 1.199896 270)
			(size 0.3556 0.3556)
			(layers "F.Cu" "F.Mask" "F.Paste")
			(net "BMC_SMB6_DAT")
		)
		(pad "N3" smd circle
			(at -6.800088 1.199896 270)
			(size 0.3556 0.3556)
			(layers "F.Cu" "F.Mask" "F.Paste")
			(net "BOARD_REV_2")
		)
		(pad "N4" smd circle
			(at -5.999988 1.199896 270)
			(size 0.3556 0.3556)
			(layers "F.Cu" "F.Mask" "F.Paste")
			(net "PCIE_WAKE_N")
		)
		(pad "N5" smd circle
			(at -5.199888 1.199896 270)
			(size 0.3556 0.3556)
			(layers "F.Cu" "F.Mask" "F.Paste")
			(net "IOM_TYPE0")
		)
		(pad "N6" smd circle
			(at -4.400042 1.199896 270)
			(size 0.3556 0.3556)
			(layers "F.Cu" "F.Mask" "F.Paste")
			(net "P3V3_STBY")
		)
		(pad "N7" smd circle
			(at -3.599942 1.199896 270)
			(size 0.3556 0.3556)
			(layers "F.Cu" "F.Mask" "F.Paste")
			(net "P1V15_STBY")
		)
		(pad "N9" smd circle
			(at -1.999996 1.199896 270)
			(size 0.3556 0.3556)
			(layers "F.Cu" "F.Mask" "F.Paste")
			(net "GND")
		)
		(pad "N10" smd circle
			(at -1.199896 1.199896 270)
			(size 0.3556 0.3556)
			(layers "F.Cu" "F.Mask" "F.Paste")
			(net "GND")
		)
		(pad "N11" smd circle
			(at -0.40005 1.199896 270)
			(size 0.3556 0.3556)
			(layers "F.Cu" "F.Mask" "F.Paste")
			(net "GND")
		)
		(pad "N12" smd circle
			(at 0.40005 1.199896 270)
			(size 0.3556 0.3556)
			(layers "F.Cu" "F.Mask" "F.Paste")
			(net "GND")
		)
		(pad "N13" smd circle
			(at 1.199896 1.199896 270)
			(size 0.3556 0.3556)
			(layers "F.Cu" "F.Mask" "F.Paste")
			(net "GND")
		)
		(pad "N14" smd circle
			(at 1.999996 1.199896 270)
			(size 0.3556 0.3556)
			(layers "F.Cu" "F.Mask" "F.Paste")
			(net "GND")
		)
		(pad "N16" smd circle
			(at 3.599942 1.199896 270)
			(size 0.3556 0.3556)
			(layers "F.Cu" "F.Mask" "F.Paste")
			(net "P1V15_STBY")
		)
		(pad "N17" smd circle
			(at 4.400042 1.199896 270)
			(size 0.3556 0.3556)
			(layers "F.Cu" "F.Mask" "F.Paste")
			(net "P3V3_STBY")
		)
		(pad "N18" smd circle
			(at 5.199888 1.199896 270)
			(size 0.3556 0.3556)
			(layers "F.Cu" "F.Mask" "F.Paste")
			(net "I2C_MEZZ_ALERT_N")
		)
		(pad "N19" smd circle
			(at 5.999988 1.199896 270)
			(size 0.3556 0.3556)
			(layers "F.Cu" "F.Mask" "F.Paste")
			(net "IOM_LOC_INS_N")
		)
		(pad "N20" smd circle
			(at 6.800088 1.199896 270)
			(size 0.3556 0.3556)
			(layers "F.Cu" "F.Mask" "F.Paste")
			(net "Net_549")
		)
		(pad "N21" smd circle
			(at 7.599934 1.199896 270)
			(size 0.3556 0.3556)
			(layers "F.Cu" "F.Mask" "F.Paste")
			(net "BMC_SMB14_CLK")
		)
		(pad "N22" smd circle
			(at 8.400034 1.199896 270)
			(size 0.3556 0.3556)
			(layers "F.Cu" "F.Mask" "F.Paste")
			(net "BMC_SMB14_DAT")
		)
		(pad "P1" smd circle
			(at -8.400034 1.999996 270)
			(size 0.3556 0.3556)
			(layers "F.Cu" "F.Mask" "F.Paste")
			(net "BMC_SMB7_DAT")
		)
		(pad "P2" smd circle
			(at -7.599934 1.999996 270)
			(size 0.3556 0.3556)
			(layers "F.Cu" "F.Mask" "F.Paste")
			(net "BMC_SMB8_CLK")
		)
		(pad "P3" smd circle
			(at -6.800088 1.999996 270)
			(size 0.3556 0.3556)
			(layers "F.Cu" "F.Mask" "F.Paste")
			(net "TP_BMC_GPIOL5")
		)
		(pad "P4" smd circle
			(at -5.999988 1.999996 270)
			(size 0.3556 0.3556)
			(layers "F.Cu" "F.Mask" "F.Paste")
			(net "TP_BMC_GPIOL4")
		)
		(pad "P5" smd circle
			(at -5.199888 1.999996 270)
			(size 0.3556 0.3556)
			(layers "F.Cu" "F.Mask" "F.Paste")
			(net "Net_560")
		)
		(pad "P6" smd circle
			(at -4.400042 1.999996 270)
			(size 0.3556 0.3556)
			(layers "F.Cu" "F.Mask" "F.Paste")
			(net "P3V3_STBY")
		)
		(pad "P7" smd circle
			(at -3.599942 1.999996 270)
			(size 0.3556 0.3556)
			(layers "F.Cu" "F.Mask" "F.Paste")
			(net "P1V15_STBY")
		)
		(pad "P9" smd circle
			(at -1.999996 1.999996 270)
			(size 0.3556 0.3556)
			(layers "F.Cu" "F.Mask" "F.Paste")
			(net "P1V15_STBY")
		)
		(pad "P10" smd circle
			(at -1.199896 1.999996 270)
			(size 0.3556 0.3556)
			(layers "F.Cu" "F.Mask" "F.Paste")
			(net "P1V15_STBY")
		)
		(pad "P11" smd circle
			(at -0.40005 1.999996 270)
			(size 0.3556 0.3556)
			(layers "F.Cu" "F.Mask" "F.Paste")
			(net "P1V15_STBY")
		)
		(pad "P12" smd circle
			(at 0.40005 1.999996 270)
			(size 0.3556 0.3556)
			(layers "F.Cu" "F.Mask" "F.Paste")
			(net "P1V15_STBY")
		)
		(pad "P13" smd circle
			(at 1.199896 1.999996 270)
			(size 0.3556 0.3556)
			(layers "F.Cu" "F.Mask" "F.Paste")
			(net "P1V15_STBY")
		)
		(pad "P14" smd circle
			(at 1.999996 1.999996 270)
			(size 0.3556 0.3556)
			(layers "F.Cu" "F.Mask" "F.Paste")
			(net "P1V15_STBY")
		)
		(pad "P16" smd circle
			(at 3.599942 1.999996 270)
			(size 0.3556 0.3556)
			(layers "F.Cu" "F.Mask" "F.Paste")
			(net "P1V15_STBY")
		)
		(pad "P17" smd circle
			(at 4.400042 1.999996 270)
			(size 0.3556 0.3556)
			(layers "F.Cu" "F.Mask" "F.Paste")
			(net "P3V3_STBY")
		)
		(pad "P18" smd circle
			(at 5.199888 1.999996 270)
			(size 0.3556 0.3556)
			(layers "F.Cu" "F.Mask" "F.Paste")
			(net "Net_3")
		)
		(pad "P19" smd circle
			(at 5.999988 1.999996 270)
			(size 0.3556 0.3556)
			(layers "F.Cu" "F.Mask" "F.Paste")
			(net "IOM_FULL_PWR_EN_R")
		)
		(pad "P20" smd circle
			(at 6.800088 1.999996 270)
			(size 0.3556 0.3556)
			(layers "F.Cu" "F.Mask" "F.Paste")
			(net "BMC_SMB2_DAT")
		)
		(pad "P21" smd circle
			(at 7.599934 1.999996 270)
			(size 0.3556 0.3556)
			(layers "F.Cu" "F.Mask" "F.Paste")
			(net "BMC_GPIOY3")
		)
		(pad "P22" smd circle
			(at 8.400034 1.999996 270)
			(size 0.3556 0.3556)
			(layers "F.Cu" "F.Mask" "F.Paste")
			(net "BMC_GPIOY2")
		)
		(pad "R1" smd circle
			(at -8.400034 2.800096 270)
			(size 0.3556 0.3556)
			(layers "F.Cu" "F.Mask" "F.Paste")
			(net "BMC_SMB8_DAT")
		)
		(pad "R2" smd circle
			(at -7.599934 2.800096 270)
			(size 0.3556 0.3556)
			(layers "F.Cu" "F.Mask" "F.Paste")
			(net "BOARD_REV_0")
		)
		(pad "R3" smd circle
			(at -6.800088 2.800096 270)
			(size 0.3556 0.3556)
			(layers "F.Cu" "F.Mask" "F.Paste")
			(net "IOM_TYPE2")
		)
		(pad "R4" smd circle
			(at -5.999988 2.800096 270)
			(size 0.3556 0.3556)
			(layers "F.Cu" "F.Mask" "F.Paste")
			(net "IOM_TYPE1")
		)
		(pad "R5" smd circle
			(at -5.199888 2.800096 270)
			(size 0.3556 0.3556)
			(layers "F.Cu" "F.Mask" "F.Paste")
			(net "UART_EXP_BMC_RX_R")
		)
		(pad "R6" smd circle
			(at -4.400042 2.800096 270)
			(size 0.3556 0.3556)
			(layers "F.Cu" "F.Mask" "F.Paste")
			(net "P3V3_STBY")
		)
		(pad "R7" smd circle
			(at -3.599942 2.800096 270)
			(size 0.3556 0.3556)
			(layers "F.Cu" "F.Mask" "F.Paste")
			(net "P1V15_STBY")
		)
		(pad "R16" smd circle
			(at 3.599942 2.800096 270)
			(size 0.3556 0.3556)
			(layers "F.Cu" "F.Mask" "F.Paste")
			(net "P1V15_STBY")
		)
		(pad "R17" smd circle
			(at 4.400042 2.800096 270)
			(size 0.3556 0.3556)
			(layers "F.Cu" "F.Mask" "F.Paste")
			(net "P3V3_STBY")
		)
		(pad "R18" smd circle
			(at 5.199888 2.800096 270)
			(size 0.3556 0.3556)
			(layers "F.Cu" "F.Mask" "F.Paste")
			(net "BMC_UART_SEL_IN")
		)
		(pad "R19" smd circle
			(at 5.999988 2.800096 270)
			(size 0.3556 0.3556)
			(layers "F.Cu" "F.Mask" "F.Paste")
			(net "BMC_GPIOS4")
		)
		(pad "R20" smd circle
			(at 6.800088 2.800096 270)
			(size 0.3556 0.3556)
			(layers "F.Cu" "F.Mask" "F.Paste")
			(net "Net_108")
		)
		(pad "R21" smd circle
			(at 7.599934 2.800096 270)
			(size 0.3556 0.3556)
			(layers "F.Cu" "F.Mask" "F.Paste")
			(net "BMC_GPIOY1")
		)
		(pad "R22" smd circle
			(at 8.400034 2.800096 270)
			(size 0.3556 0.3556)
			(layers "F.Cu" "F.Mask" "F.Paste")
			(net "BMC_GPIOY0")
		)
		(pad "T1" smd circle
			(at -8.400034 3.599942 270)
			(size 0.3556 0.3556)
			(layers "F.Cu" "F.Mask" "F.Paste")
			(net "TP_BMC_GPIOL1")
		)
		(pad "T2" smd circle
			(at -7.599934 3.599942 270)
			(size 0.3556 0.3556)
			(layers "F.Cu" "F.Mask" "F.Paste")
			(net "TP_BMC_GPIOL0")
		)
		(pad "T3" smd circle
			(at -6.800088 3.599942 270)
			(size 0.3556 0.3556)
			(layers "F.Cu" "F.Mask" "F.Paste")
			(net "IOM_TYPE3")
		)
		(pad "T4" smd circle
			(at -5.999988 3.599942 270)
			(size 0.3556 0.3556)
			(layers "F.Cu" "F.Mask" "F.Paste")
			(net "TP_BMC_GPION7")
		)
		(pad "T5" smd circle
			(at -5.199888 3.599942 270)
			(size 0.3556 0.3556)
			(layers "F.Cu" "F.Mask" "F.Paste")
			(net "UART_EXP_BMC_TX_R")
		)
		(pad "T6" smd circle
			(at -4.400042 3.599942 270)
			(size 0.3556 0.3556)
			(layers "F.Cu" "F.Mask" "F.Paste")
			(net "GND")
		)
		(pad "T7" smd circle
			(at -3.599942 3.599942 270)
			(size 0.3556 0.3556)
			(layers "F.Cu" "F.Mask" "F.Paste")
			(net "GND")
		)
		(pad "T8" smd circle
			(at -2.800096 3.599942 270)
			(size 0.3556 0.3556)
			(layers "F.Cu" "F.Mask" "F.Paste")
			(net "P1V2_STBY")
		)
		(pad "T9" smd circle
			(at -1.999996 3.599942 270)
			(size 0.3556 0.3556)
			(layers "F.Cu" "F.Mask" "F.Paste")
			(net "DDR_VREF")
		)
		(pad "T10" smd circle
			(at -1.199896 3.599942 270)
			(size 0.3556 0.3556)
			(layers "F.Cu" "F.Mask" "F.Paste")
			(net "P1V2_STBY")
		)
		(pad "T11" smd circle
			(at -0.40005 3.599942 270)
			(size 0.3556 0.3556)
			(layers "F.Cu" "F.Mask" "F.Paste")
			(net "MPLLAV33")
		)
		(pad "T12" smd circle
			(at 0.40005 3.599942 270)
			(size 0.3556 0.3556)
			(layers "F.Cu" "F.Mask" "F.Paste")
			(net "P1V2_STBY")
		)
		(pad "T13" smd circle
			(at 1.199896 3.599942 270)
			(size 0.3556 0.3556)
			(layers "F.Cu" "F.Mask" "F.Paste")
			(net "P1V2_STBY")
		)
		(pad "T14" smd circle
			(at 1.999996 3.599942 270)
			(size 0.3556 0.3556)
			(layers "F.Cu" "F.Mask" "F.Paste")
			(net "P1V2_STBY")
		)
		(pad "T15" smd circle
			(at 2.800096 3.599942 270)
			(size 0.3556 0.3556)
			(layers "F.Cu" "F.Mask" "F.Paste")
			(net "P3V3_STBY")
		)
		(pad "T16" smd circle
			(at 3.599942 3.599942 270)
			(size 0.3556 0.3556)
			(layers "F.Cu" "F.Mask" "F.Paste")
			(net "GND")
		)
		(pad "T17" smd circle
			(at 4.400042 3.599942 270)
			(size 0.3556 0.3556)
			(layers "F.Cu" "F.Mask" "F.Paste")
			(net "TP_BMC_GPIOR2")
		)
		(pad "T18" smd circle
			(at 5.199888 3.599942 270)
			(size 0.3556 0.3556)
			(layers "F.Cu" "F.Mask" "F.Paste")
			(net "BMC_SPI_MISO")
		)
		(pad "T19" smd circle
			(at 5.999988 3.599942 270)
			(size 0.3556 0.3556)
			(layers "F.Cu" "F.Mask" "F.Paste")
			(net "TP_BMC_GPIOR1")
		)
		(pad "T20" smd circle
			(at 6.800088 3.599942 270)
			(size 0.3556 0.3556)
			(layers "F.Cu" "F.Mask" "F.Paste")
			(net "Net_90")
		)
		(pad "T21" smd circle
			(at 7.599934 3.599942 270)
			(size 0.3556 0.3556)
			(layers "F.Cu" "F.Mask" "F.Paste")
			(net "IOM_FULL_PGOOD")
		)
		(pad "T22" smd circle
			(at 8.400034 3.599942 270)
			(size 0.3556 0.3556)
			(layers "F.Cu" "F.Mask" "F.Paste")
			(net "BMC_SELF_HW_RST")
		)
		(pad "U1" smd circle
			(at -8.400034 4.400042 270)
			(size 0.3556 0.3556)
			(layers "F.Cu" "F.Mask" "F.Paste")
			(net "TP_BMC_GPIOL2")
		)
		(pad "U2" smd circle
			(at -7.599934 4.400042 270)
			(size 0.3556 0.3556)
			(layers "F.Cu" "F.Mask" "F.Paste")
			(net "TP_BMC_GPIOL3")
		)
		(pad "U3" smd circle
			(at -6.800088 4.400042 270)
			(size 0.3556 0.3556)
			(layers "F.Cu" "F.Mask" "F.Paste")
			(net "TP_BMC_GPION3")
		)
		(pad "U4" smd circle
			(at -5.999988 4.400042 270)
			(size 0.3556 0.3556)
			(layers "F.Cu" "F.Mask" "F.Paste")
			(net "BMC_LOC_HB")
		)
		(pad "U5" smd circle
			(at -5.199888 4.400042 270)
			(size 0.3556 0.3556)
			(layers "F.Cu" "F.Mask" "F.Paste")
			(net "BMC_RMT_HB")
		)
		(pad "U6" smd circle
			(at -4.400042 4.400042 270)
			(size 0.3556 0.3556)
			(layers "F.Cu" "F.Mask" "F.Paste")
			(net "GND")
		)
		(pad "U7" smd circle
			(at -3.599942 4.400042 270)
			(size 0.3556 0.3556)
			(layers "F.Cu" "F.Mask" "F.Paste")
			(net "MEMDQ_15")
		)
		(pad "U8" smd circle
			(at -2.800096 4.400042 270)
			(size 0.3556 0.3556)
			(layers "F.Cu" "F.Mask" "F.Paste")
			(net "MEMDM_0")
		)
		(pad "U9" smd circle
			(at -1.999996 4.400042 270)
			(size 0.3556 0.3556)
			(layers "F.Cu" "F.Mask" "F.Paste")
			(net "MEMDQ_4")
		)
		(pad "U10" smd circle
			(at -1.199896 4.400042 270)
			(size 0.3556 0.3556)
			(layers "F.Cu" "F.Mask" "F.Paste")
			(net "MEMDQ_0")
		)
		(pad "U11" smd circle
			(at -0.40005 4.400042 270)
			(size 0.3556 0.3556)
			(layers "F.Cu" "F.Mask" "F.Paste")
			(net "GND")
		)
		(pad "U12" smd circle
			(at 0.40005 4.400042 270)
			(size 0.3556 0.3556)
			(layers "F.Cu" "F.Mask" "F.Paste")
			(net "MEMBA_0")
		)
		(pad "U13" smd circle
			(at 1.199896 4.400042 270)
			(size 0.3556 0.3556)
			(layers "F.Cu" "F.Mask" "F.Paste")
			(net "MEMA_10")
		)
		(pad "U14" smd circle
			(at 1.999996 4.400042 270)
			(size 0.3556 0.3556)
			(layers "F.Cu" "F.Mask" "F.Paste")
			(net "MEMA_3")
		)
		(pad "U15" smd circle
			(at 2.800096 4.400042 270)
			(size 0.3556 0.3556)
			(layers "F.Cu" "F.Mask" "F.Paste")
			(net "Net_556")
		)
		(pad "U16" smd circle
			(at 3.599942 4.400042 270)
			(size 0.3556 0.3556)
			(layers "F.Cu" "F.Mask" "F.Paste")
			(net "DDR4_ALERT")
		)
		(pad "U17" smd circle
			(at 4.400042 4.400042 270)
			(size 0.3556 0.3556)
			(layers "F.Cu" "F.Mask" "F.Paste")
			(net "BMC_SPI_MOSI")
		)
		(pad "U18" smd circle
			(at 5.199888 4.400042 270)
			(size 0.3556 0.3556)
			(layers "F.Cu" "F.Mask" "F.Paste")
			(net "BMC0_SRST_N")
		)
		(pad "U19" smd circle
			(at 5.999988 4.400042 270)
			(size 0.3556 0.3556)
			(layers "F.Cu" "F.Mask" "F.Paste")
			(net "BMC_UART_SEL_OUT")
		)
		(pad "U20" smd circle
			(at 6.800088 4.400042 270)
			(size 0.3556 0.3556)
			(layers "F.Cu" "F.Mask" "F.Paste")
			(net "BMC_GPIOS6")
		)
		(pad "U21" smd circle
			(at 7.599934 4.400042 270)
			(size 0.3556 0.3556)
			(layers "F.Cu" "F.Mask" "F.Paste")
			(net "BMC_GPIOZ4")
		)
		(pad "U22" smd circle
			(at 8.400034 4.400042 270)
			(size 0.3556 0.3556)
			(layers "F.Cu" "F.Mask" "F.Paste")
			(net "Net_5")
		)
		(pad "V1" smd circle
			(at -8.400034 5.199888 270)
			(size 0.3556 0.3556)
			(layers "F.Cu" "F.Mask" "F.Paste")
			(net "UART_BMC_COMP_IN_RX")
		)
		(pad "V2" smd circle
			(at -7.599934 5.199888 270)
			(size 0.3556 0.3556)
			(layers "F.Cu" "F.Mask" "F.Paste")
			(net "FAN_PWM0_BMC")
		)
		(pad "V3" smd circle
			(at -6.800088 5.199888 270)
			(size 0.3556 0.3556)
			(layers "F.Cu" "F.Mask" "F.Paste")
			(net "TP_BMC_GPION2")
		)
		(pad "V4" smd circle
			(at -5.999988 5.199888 270)
			(size 0.3556 0.3556)
			(layers "F.Cu" "F.Mask" "F.Paste")
			(net "DEBUG_GPIO_BMC_R_6")
		)
		(pad "V5" smd circle
			(at -5.199888 5.199888 270)
			(size 0.3556 0.3556)
			(layers "F.Cu" "F.Mask" "F.Paste")
			(net "FLA0_WP_N_R")
		)
		(pad "V6" smd circle
			(at -4.400042 5.199888 270)
			(size 0.3556 0.3556)
			(layers "F.Cu" "F.Mask" "F.Paste")
			(net "DEBUG_GPIO_BMC_R_5")
		)
		(pad "V7" smd circle
			(at -3.599942 5.199888 270)
			(size 0.3556 0.3556)
			(layers "F.Cu" "F.Mask" "F.Paste")
			(net "MEMDQ_14")
		)
		(pad "V8" smd circle
			(at -2.800096 5.199888 270)
			(size 0.3556 0.3556)
			(layers "F.Cu" "F.Mask" "F.Paste")
			(net "GND")
		)
		(pad "V9" smd circle
			(at -1.999996 5.199888 270)
			(size 0.3556 0.3556)
			(layers "F.Cu" "F.Mask" "F.Paste")
			(net "MEMDQ_7")
		)
		(pad "V10" smd circle
			(at -1.199896 5.199888 270)
			(size 0.3556 0.3556)
			(layers "F.Cu" "F.Mask" "F.Paste")
			(net "GND")
		)
		(pad "V11" smd circle
			(at -0.40005 5.199888 270)
			(size 0.3556 0.3556)
			(layers "F.Cu" "F.Mask" "F.Paste")
			(net "MEMODT")
		)
		(pad "V12" smd circle
			(at 0.40005 5.199888 270)
			(size 0.3556 0.3556)
			(layers "F.Cu" "F.Mask" "F.Paste")
			(net "GND")
		)
		(pad "V13" smd circle
			(at 1.199896 5.199888 270)
			(size 0.3556 0.3556)
			(layers "F.Cu" "F.Mask" "F.Paste")
			(net "MEMA_0")
		)
		(pad "V14" smd circle
			(at 1.999996 5.199888 270)
			(size 0.3556 0.3556)
			(layers "F.Cu" "F.Mask" "F.Paste")
			(net "GND")
		)
		(pad "V15" smd circle
			(at 2.800096 5.199888 270)
			(size 0.3556 0.3556)
			(layers "F.Cu" "F.Mask" "F.Paste")
			(net "MEMA_5")
		)
		(pad "V16" smd circle
			(at 3.599942 5.199888 270)
			(size 0.3556 0.3556)
			(layers "F.Cu" "F.Mask" "F.Paste")
			(net "GND")
		)
		(pad "V17" smd circle
			(at 4.400042 5.199888 270)
			(size 0.3556 0.3556)
			(layers "F.Cu" "F.Mask" "F.Paste")
			(net "P1V15_STBY")
		)
		(pad "V18" smd circle
			(at 5.199888 5.199888 270)
			(size 0.3556 0.3556)
			(layers "F.Cu" "F.Mask" "F.Paste")
			(net "BMC_EXTRST_N")
		)
		(pad "V19" smd circle
			(at 5.999988 5.199888 270)
			(size 0.3556 0.3556)
			(layers "F.Cu" "F.Mask" "F.Paste")
			(net "TP_BMC_GPIOR5")
		)
		(pad "V20" smd circle
			(at 6.800088 5.199888 270)
			(size 0.3556 0.3556)
			(layers "F.Cu" "F.Mask" "F.Paste")
			(net "EXP_UART_EN")
		)
		(pad "V21" smd circle
			(at 7.599934 5.199888 270)
			(size 0.3556 0.3556)
			(layers "F.Cu" "F.Mask" "F.Paste")
			(net "CONN_A_PRSNTA")
		)
		(pad "V22" smd circle
			(at 8.400034 5.199888 270)
			(size 0.3556 0.3556)
			(layers "F.Cu" "F.Mask" "F.Paste")
			(net "BMC_GPIOZ6")
		)
		(pad "W1" smd circle
			(at -8.400034 5.999988 270)
			(size 0.3556 0.3556)
			(layers "F.Cu" "F.Mask" "F.Paste")
			(net "UART_COMP_OUT_TX_R")
		)
		(pad "W2" smd circle
			(at -7.599934 5.999988 270)
			(size 0.3556 0.3556)
			(layers "F.Cu" "F.Mask" "F.Paste")
			(net "FAN_PWM1_BMC")
		)
		(pad "W3" smd circle
			(at -6.800088 5.999988 270)
			(size 0.3556 0.3556)
			(layers "F.Cu" "F.Mask" "F.Paste")
			(net "TP_BMC_GPION4")
		)
		(pad "W4" smd circle
			(at -5.999988 5.999988 270)
			(size 0.3556 0.3556)
			(layers "F.Cu" "F.Mask" "F.Paste")
			(net "COMP_PWR_EN_R")
		)
		(pad "W5" smd circle
			(at -5.199888 5.999988 270)
			(size 0.3556 0.3556)
			(layers "F.Cu" "F.Mask" "F.Paste")
			(net "Net_107")
		)
		(pad "W6" smd circle
			(at -4.400042 5.999988 270)
			(size 0.3556 0.3556)
			(layers "F.Cu" "F.Mask" "F.Paste")
			(net "DEBUG_GPIO_BMC_R_4")
		)
		(pad "W7" smd circle
			(at -3.599942 5.999988 270)
			(size 0.3556 0.3556)
			(layers "F.Cu" "F.Mask" "F.Paste")
			(net "MEMDQ_13")
		)
		(pad "W8" smd circle
			(at -2.800096 5.999988 270)
			(size 0.3556 0.3556)
			(layers "F.Cu" "F.Mask" "F.Paste")
			(net "MEMDQ_11")
		)
		(pad "W9" smd circle
			(at -1.999996 5.999988 270)
			(size 0.3556 0.3556)
			(layers "F.Cu" "F.Mask" "F.Paste")
			(net "MEMDQ_6")
		)
		(pad "W10" smd circle
			(at -1.199896 5.999988 270)
			(size 0.3556 0.3556)
			(layers "F.Cu" "F.Mask" "F.Paste")
			(net "MEMDQ_1")
		)
		(pad "W11" smd circle
			(at -0.40005 5.999988 270)
			(size 0.3556 0.3556)
			(layers "F.Cu" "F.Mask" "F.Paste")
			(net "MIOZ")
		)
		(pad "W12" smd circle
			(at 0.40005 5.999988 270)
			(size 0.3556 0.3556)
			(layers "F.Cu" "F.Mask" "F.Paste")
			(net "MEMRASN")
		)
		(pad "W13" smd circle
			(at 1.199896 5.999988 270)
			(size 0.3556 0.3556)
			(layers "F.Cu" "F.Mask" "F.Paste")
			(net "MEMBG_0")
		)
		(pad "W14" smd circle
			(at 1.999996 5.999988 270)
			(size 0.3556 0.3556)
			(layers "F.Cu" "F.Mask" "F.Paste")
			(net "MEMA_2")
		)
		(pad "W15" smd circle
			(at 2.800096 5.999988 270)
			(size 0.3556 0.3556)
			(layers "F.Cu" "F.Mask" "F.Paste")
			(net "MEMA_4")
		)
		(pad "W16" smd circle
			(at 3.599942 5.999988 270)
			(size 0.3556 0.3556)
			(layers "F.Cu" "F.Mask" "F.Paste")
			(net "MEMA_8")
		)
		(pad "W17" smd circle
			(at 4.400042 5.999988 270)
			(size 0.3556 0.3556)
			(layers "F.Cu" "F.Mask" "F.Paste")
			(net "MPLLAV33")
		)
		(pad "W18" smd circle
			(at 5.199888 5.999988 270)
			(size 0.3556 0.3556)
			(layers "F.Cu" "F.Mask" "F.Paste")
			(net "CLKIN_24M_BMC")
		)
		(pad "W19" smd circle
			(at 5.999988 5.999988 270)
			(size 0.3556 0.3556)
			(layers "F.Cu" "F.Mask" "F.Paste")
			(net "TP_BMC_GPIOR4")
		)
		(pad "W20" smd circle
			(at 6.800088 5.999988 270)
			(size 0.3556 0.3556)
			(layers "F.Cu" "F.Mask" "F.Paste")
			(net "BMC_GPIOS5")
		)
		(pad "W21" smd circle
			(at 7.599934 5.999988 270)
			(size 0.3556 0.3556)
			(layers "F.Cu" "F.Mask" "F.Paste")
			(net "BMC_GPIOZ7")
		)
		(pad "W22" smd circle
			(at 8.400034 5.999988 270)
			(size 0.3556 0.3556)
			(layers "F.Cu" "F.Mask" "F.Paste")
			(net "BMC_GPIOZ5")
		)
		(pad "Y1" smd circle
			(at -8.400034 6.800088 270)
			(size 0.4064 0.4064)
			(layers "F.Cu" "F.Mask" "F.Paste")
			(net "Net_565")
		)
		(pad "Y2" smd circle
			(at -7.599934 6.800088 270)
			(size 0.4064 0.4064)
			(layers "F.Cu" "F.Mask" "F.Paste")
			(net "Net_564")
		)
		(pad "Y3" smd circle
			(at -6.800088 6.800088 270)
			(size 0.4064 0.4064)
			(layers "F.Cu" "F.Mask" "F.Paste")
			(net "TP_BMC_GPION6")
		)
		(pad "Y4" smd circle
			(at -5.999988 6.800088 270)
			(size 0.3556 0.3556)
			(layers "F.Cu" "F.Mask" "F.Paste")
			(net "SCC_B_HB_IN_R")
		)
		(pad "Y5" smd circle
			(at -5.199888 6.800088 270)
			(size 0.3556 0.3556)
			(layers "F.Cu" "F.Mask" "F.Paste")
			(net "DEBUG_GPIO_BMC_R_3")
		)
		(pad "Y6" smd circle
			(at -4.400042 6.800088 270)
			(size 0.3556 0.3556)
			(layers "F.Cu" "F.Mask" "F.Paste")
			(net "DEBUG_GPIO_BMC_R_2")
		)
		(pad "Y7" smd circle
			(at -3.599942 6.800088 270)
			(size 0.3556 0.3556)
			(layers "F.Cu" "F.Mask" "F.Paste")
			(net "MEMDQ_10")
		)
		(pad "Y8" smd circle
			(at -2.800096 6.800088 270)
			(size 0.3556 0.3556)
			(layers "F.Cu" "F.Mask" "F.Paste")
			(net "MEMDQ_9")
		)
		(pad "Y9" smd circle
			(at -1.999996 6.800088 270)
			(size 0.3556 0.3556)
			(layers "F.Cu" "F.Mask" "F.Paste")
			(net "MEMDQ_5")
		)
		(pad "Y10" smd circle
			(at -1.199896 6.800088 270)
			(size 0.3556 0.3556)
			(layers "F.Cu" "F.Mask" "F.Paste")
			(net "MEMDQ_2")
		)
		(pad "Y11" smd circle
			(at -0.40005 6.800088 270)
			(size 0.3556 0.3556)
			(layers "F.Cu" "F.Mask" "F.Paste")
			(net "MEMCKE")
		)
		(pad "Y12" smd circle
			(at 0.40005 6.800088 270)
			(size 0.3556 0.3556)
			(layers "F.Cu" "F.Mask" "F.Paste")
			(net "MEMWEN")
		)
		(pad "Y13" smd circle
			(at 1.199896 6.800088 270)
			(size 0.3556 0.3556)
			(layers "F.Cu" "F.Mask" "F.Paste")
			(net "MEMBA_1")
		)
		(pad "Y14" smd circle
			(at 1.999996 6.800088 270)
			(size 0.3556 0.3556)
			(layers "F.Cu" "F.Mask" "F.Paste")
			(net "MEMA_12")
		)
		(pad "Y15" smd circle
			(at 2.800096 6.800088 270)
			(size 0.3556 0.3556)
			(layers "F.Cu" "F.Mask" "F.Paste")
			(net "DDR4_ACT")
		)
		(pad "Y16" smd circle
			(at 3.599942 6.800088 270)
			(size 0.3556 0.3556)
			(layers "F.Cu" "F.Mask" "F.Paste")
			(net "MEMA_9")
		)
		(pad "Y17" smd circle
			(at 4.400042 6.800088 270)
			(size 0.3556 0.3556)
			(layers "F.Cu" "F.Mask" "F.Paste")
			(net "MPLLAV33")
		)
		(pad "Y18" smd circle
			(at 5.199888 6.800088 270)
			(size 0.3556 0.3556)
			(layers "F.Cu" "F.Mask" "F.Paste")
			(net "BMC_HBLED")
		)
		(pad "Y19" smd circle
			(at 5.999988 6.800088 270)
			(size 0.3556 0.3556)
			(layers "F.Cu" "F.Mask" "F.Paste")
			(net "TP_BMC_GPIOR3")
		)
		(pad "Y20" smd circle
			(at 6.800088 6.800088 270)
			(size 0.4064 0.4064)
			(layers "F.Cu" "F.Mask" "F.Paste")
			(net "DEBUG_RST_BTN_N")
		)
		(pad "Y21" smd circle
			(at 7.599934 6.800088 270)
			(size 0.4064 0.4064)
			(layers "F.Cu" "F.Mask" "F.Paste")
			(net "Net_80")
		)
		(pad "Y22" smd circle
			(at 8.400034 6.800088 270)
			(size 0.4064 0.4064)
			(layers "F.Cu" "F.Mask" "F.Paste")
			(net "Net_4")
		)
	)
	(footprint ""
		(layer "F.Cu")
		(at 68.686426 -145.913348 90)
		(property "Reference" "R763"
			(at 0 0 90)
			(layer "F.SilkS")
			(hide yes)
			(effects
				(font
					(size 1.27 1.27)
				)
			)
		)
		(property "Value" "33R2J-2-GP"
			(at 0.064008 -3.993896 90)
			(unlocked yes)
			(layer "F.Fab")
			(hide yes)
			(effects
				(font
					(size 1.016 1.016)
					(thickness 0.1524)
				)
			)
		)
		(property "Device Type" "R402H16"
			(at 0.064008 -5.517896 90)
			(unlocked yes)
			(layer "F.Fab")
			(hide yes)
			(effects
				(font
					(size 1.016 1.016)
					(thickness 0.1524)
				)
			)
		)
		(duplicate_pad_numbers_are_jumpers no)
		(fp_line
			(start 0.508 -0.9398)
			(end -0.508 -0.9398)
			(stroke
				(width 0.1524)
				(type default)
			)
			(layer "F.SilkS")
		)
		(fp_line
			(start -0.508 -0.9398)
			(end -0.508 0.9398)
			(stroke
				(width 0.1524)
				(type default)
			)
			(layer "F.SilkS")
		)
		(fp_rect
			(start -0.508 0.9398)
			(end 0.508 -0.9398)
			(stroke
				(width 0)
				(type default)
			)
			(fill no)
			(layer "F.CrtYd")
		)
		(fp_rect
			(start -0.508 0.9398)
			(end 0.508 -0.9398)
			(stroke
				(width 0)
				(type default)
			)
			(fill no)
			(layer "F.Fab")
		)
		(pad "1" smd custom
			(at 0 -0.4445 90)
			(size 0.1397 0.1397)
			(layers "F.Cu" "F.Mask" "F.Paste")
			(net "NCSI_RCLK_R")
			(options
				(clearance outline)
				(anchor circle)
			)
			(primitives
				(gr_poly
					(pts
						(arc
							(start -0.1778 -0.2794)
							(mid -0.249642 -0.249642)
							(end -0.2794 -0.1778)
						)
						(arc
							(start -0.2794 0.1778)
							(mid -0.249642 0.249642)
							(end -0.1778 0.2794)
						)
						(arc
							(start 0.1778 0.2794)
							(mid 0.249642 0.249642)
							(end 0.2794 0.1778)
						)
						(arc
							(start 0.2794 -0.1778)
							(mid 0.249642 -0.249642)
							(end 0.1778 -0.2794)
						)
					)
					(width 0)
					(fill yes)
				)
			)
		)
		(pad "2" smd custom
			(at 0 0.4445 90)
			(size 0.1397 0.1397)
			(layers "F.Cu" "F.Mask" "F.Paste")
			(net "NCSI_RCLK")
			(options
				(clearance outline)
				(anchor circle)
			)
			(primitives
				(gr_poly
					(pts
						(arc
							(start -0.1778 -0.2794)
							(mid -0.249642 -0.249642)
							(end -0.2794 -0.1778)
						)
						(arc
							(start -0.2794 0.1778)
							(mid -0.249642 0.249642)
							(end -0.1778 0.2794)
						)
						(arc
							(start 0.1778 0.2794)
							(mid 0.249642 0.249642)
							(end 0.2794 0.1778)
						)
						(arc
							(start 0.2794 -0.1778)
							(mid 0.249642 -0.249642)
							(end 0.1778 -0.2794)
						)
					)
					(width 0)
					(fill yes)
				)
			)
		)
	)
	(footprint ""
		(layer "F.Cu")
		(at 75.946 -167.5892)
		(property "Reference" "R539"
			(at 0 0 0)
			(layer "F.SilkS")
			(hide yes)
			(effects
				(font
					(size 1.27 1.27)
				)
			)
		)
		(property "Value" "10KR2F-2-GP"
			(at 0.064008 -3.993896 0)
			(unlocked yes)
			(layer "F.Fab")
			(hide yes)
			(effects
				(font
					(size 1.016 1.016)
					(thickness 0.1524)
				)
			)
		)
		(property "Device Type" "R402H16"
			(at 0.064008 -5.517896 0)
			(unlocked yes)
			(layer "F.Fab")
			(hide yes)
			(effects
				(font
					(size 1.016 1.016)
					(thickness 0.1524)
				)
			)
		)
		(duplicate_pad_numbers_are_jumpers no)
		(fp_line
			(start -0.508 -0.9398)
			(end -0.508 0.9398)
			(stroke
				(width 0.1524)
				(type default)
			)
			(layer "F.SilkS")
		)
		(fp_line
			(start 0.508 -0.9398)
			(end -0.508 -0.9398)
			(stroke
				(width 0.1524)
				(type default)
			)
			(layer "F.SilkS")
		)
		(fp_rect
			(start -0.508 0.9398)
			(end 0.508 -0.9398)
			(stroke
				(width 0)
				(type default)
			)
			(fill no)
			(layer "F.CrtYd")
		)
		(fp_rect
			(start -0.508 0.9398)
			(end 0.508 -0.9398)
			(stroke
				(width 0)
				(type default)
			)
			(fill no)
			(layer "F.Fab")
		)
		(pad "1" smd custom
			(at 0 -0.4445)
			(size 0.1397 0.1397)
			(layers "F.Cu" "F.Mask" "F.Paste")
			(net "P3V3_STBY")
			(options
				(clearance outline)
				(anchor circle)
			)
			(primitives
				(gr_poly
					(pts
						(arc
							(start -0.1778 -0.2794)
							(mid -0.249642 -0.249642)
							(end -0.2794 -0.1778)
						)
						(arc
							(start -0.2794 0.1778)
							(mid -0.249642 0.249642)
							(end -0.1778 0.2794)
						)
						(arc
							(start 0.1778 0.2794)
							(mid 0.249642 0.249642)
							(end 0.2794 0.1778)
						)
						(arc
							(start 0.2794 -0.1778)
							(mid 0.249642 -0.249642)
							(end 0.1778 -0.2794)
						)
					)
					(width 0)
					(fill yes)
				)
			)
		)
		(pad "2" smd custom
			(at 0 0.4445)
			(size 0.1397 0.1397)
			(layers "F.Cu" "F.Mask" "F.Paste")
			(net "P1V15_STBY_PG")
			(options
				(clearance outline)
				(anchor circle)
			)
			(primitives
				(gr_poly
					(pts
						(arc
							(start -0.1778 -0.2794)
							(mid -0.249642 -0.249642)
							(end -0.2794 -0.1778)
						)
						(arc
							(start -0.2794 0.1778)
							(mid -0.249642 0.249642)
							(end -0.1778 0.2794)
						)
						(arc
							(start 0.1778 0.2794)
							(mid 0.249642 0.249642)
							(end 0.2794 0.1778)
						)
						(arc
							(start 0.2794 -0.1778)
							(mid 0.249642 -0.249642)
							(end 0.1778 -0.2794)
						)
					)
					(width 0)
					(fill yes)
				)
			)
		)
	)
	(footprint ""
		(layer "F.Cu")
		(at 80.140048 -150.060914 90)
		(property "Reference" "U102"
			(at 0 0 90)
			(layer "F.SilkS")
			(hide yes)
			(effects
				(font
					(size 1.27 1.27)
				)
			)
		)
		(property "Value" "SN74LVC1G14DCKR-GP"
			(at -2.3368 -8.6868 90)
			(unlocked yes)
			(layer "F.Fab")
			(hide yes)
			(effects
				(font
					(size 1.016 1.016)
					(thickness 0.1524)
				)
			)
		)
		(property "Device Type" "SC70-5H44"
			(at -2.3114 -10.414 90)
			(unlocked yes)
			(layer "F.Fab")
			(hide yes)
			(effects
				(font
					(size 1.016 1.016)
					(thickness 0.1524)
				)
			)
		)
		(duplicate_pad_numbers_are_jumpers no)
		(fp_line
			(start 1.3843 -1.8034)
			(end 1.3843 -1.1176)
			(stroke
				(width 0.3302)
				(type default)
			)
			(layer "F.SilkS")
		)
		(fp_line
			(start 0.6604 -1.8034)
			(end 1.3843 -1.8034)
			(stroke
				(width 0.3302)
				(type default)
			)
			(layer "F.SilkS")
		)
		(fp_line
			(start 1.27 -1.7018)
			(end 1.27 1.7018)
			(stroke
				(width 0.1524)
				(type default)
			)
			(layer "F.SilkS")
		)
		(fp_line
			(start -1.27 -1.7018)
			(end 1.27 -1.7018)
			(stroke
				(width 0.1524)
				(type default)
			)
			(layer "F.SilkS")
		)
		(fp_line
			(start 1.27 1.7018)
			(end -1.27 1.7018)
			(stroke
				(width 0.1524)
				(type default)
			)
			(layer "F.SilkS")
		)
		(fp_line
			(start -1.27 1.7018)
			(end -1.27 -1.7018)
			(stroke
				(width 0.1524)
				(type default)
			)
			(layer "F.SilkS")
		)
		(fp_rect
			(start -1.524 1.9558)
			(end 1.524 -1.9558)
			(stroke
				(width 0)
				(type default)
			)
			(fill no)
			(layer "F.CrtYd")
		)
		(fp_poly
			(pts
				(xy -1.524 -1.9558) (xy 1.524 -1.9558) (xy 1.524 1.9558) (xy -1.524 1.9558)
			)
			(stroke
				(width 0)
				(type default)
			)
			(fill no)
			(layer "F.Fab")
		)
		(pad "1" smd rect
			(at 0.65024 -0.8255 90)
			(size 0.4064 1.2192)
			(layers "F.Cu" "F.Mask" "F.Paste")
			(net "Net_44")
		)
		(pad "2" smd rect
			(at 0 -0.8255 90)
			(size 0.4064 1.2192)
			(layers "F.Cu" "F.Mask" "F.Paste")
			(net "COMP_TO_BMC_RESET_R")
		)
		(pad "3" smd rect
			(at -0.65024 -0.8255 90)
			(size 0.4064 1.2192)
			(layers "F.Cu" "F.Mask" "F.Paste")
			(net "GND")
		)
		(pad "4" smd rect
			(at -0.65024 0.8255 90)
			(size 0.4064 1.2192)
			(layers "F.Cu" "F.Mask" "F.Paste")
			(net "COMP_TO_BMC_RESET_N_OUT")
		)
		(pad "5" smd rect
			(at 0.65024 0.8255 90)
			(size 0.4064 1.2192)
			(layers "F.Cu" "F.Mask" "F.Paste")
			(net "P3V3_STBY")
		)
	)
	(footprint ""
		(layer "F.Cu")
		(at 132.918454 -13.372846)
		(property "Reference" "C134"
			(at 0 0 0)
			(layer "F.SilkS")
			(hide yes)
			(effects
				(font
					(size 1.27 1.27)
				)
			)
		)
		(property "Value" "SCD015U25V2KX-GP"
			(at 1.1811 -2.7051 0)
			(unlocked yes)
			(layer "F.Fab")
			(hide yes)
			(effects
				(font
					(size 1.016 1.016)
					(thickness 0.1524)
				)
			)
		)
		(property "Device Type" "C402H22"
			(at 1.1811 -4.2291 0)
			(unlocked yes)
			(layer "F.Fab")
			(hide yes)
			(effects
				(font
					(size 1.016 1.016)
					(thickness 0.1524)
				)
			)
		)
		(duplicate_pad_numbers_are_jumpers no)
		(fp_rect
			(start -0.4318 0.9525)
			(end 0.4318 -0.9525)
			(stroke
				(width 0)
				(type default)
			)
			(fill no)
			(layer "F.CrtYd")
		)
		(fp_rect
			(start -0.4318 0.9525)
			(end 0.4318 -0.9525)
			(stroke
				(width 0)
				(type default)
			)
			(fill no)
			(layer "F.Fab")
		)
		(pad "1" smd custom
			(at 0 -0.4445)
			(size 0.1524 0.1524)
			(layers "F.Cu" "F.Mask" "F.Paste")
			(net "ADM1278_HS_P")
			(options
				(clearance outline)
				(anchor circle)
			)
			(primitives
				(gr_poly
					(pts
						(arc
							(start 0.3048 -0.2032)
							(mid 0.275042 -0.275042)
							(end 0.2032 -0.3048)
						)
						(arc
							(start -0.2032 -0.3048)
							(mid -0.275042 -0.275042)
							(end -0.3048 -0.2032)
						)
						(arc
							(start -0.3048 0.2032)
							(mid -0.275042 0.275042)
							(end -0.2032 0.3048)
						)
						(arc
							(start 0.2032 0.3048)
							(mid 0.275042 0.275042)
							(end 0.3048 0.2032)
						)
					)
					(width 0)
					(fill yes)
				)
			)
		)
		(pad "2" smd custom
			(at 0 0.4445)
			(size 0.1524 0.1524)
			(layers "F.Cu" "F.Mask" "F.Paste")
			(net "ADM1278_HS_N")
			(options
				(clearance outline)
				(anchor circle)
			)
			(primitives
				(gr_poly
					(pts
						(arc
							(start 0.3048 -0.2032)
							(mid 0.275042 -0.275042)
							(end 0.2032 -0.3048)
						)
						(arc
							(start -0.2032 -0.3048)
							(mid -0.275042 -0.275042)
							(end -0.3048 -0.2032)
						)
						(arc
							(start -0.3048 0.2032)
							(mid -0.275042 0.275042)
							(end -0.2032 0.3048)
						)
						(arc
							(start 0.2032 0.3048)
							(mid 0.275042 0.275042)
							(end 0.3048 0.2032)
						)
					)
					(width 0)
					(fill yes)
				)
			)
		)
	)
	(footprint ""
		(layer "F.Cu")
		(at 68.8848 -171.2976 180)
		(property "Reference" "R332"
			(at 0 0 180)
			(layer "F.SilkS")
			(hide yes)
			(effects
				(font
					(size 1.27 1.27)
				)
			)
		)
		(property "Value" "4K7R2F-GP"
			(at 0.064008 -3.993896 180)
			(unlocked yes)
			(layer "F.Fab")
			(hide yes)
			(effects
				(font
					(size 1.016 1.016)
					(thickness 0.1524)
				)
			)
		)
		(property "Device Type" "R402H16"
			(at 0.064008 -5.517896 180)
			(unlocked yes)
			(layer "F.Fab")
			(hide yes)
			(effects
				(font
					(size 1.016 1.016)
					(thickness 0.1524)
				)
			)
		)
		(duplicate_pad_numbers_are_jumpers no)
		(fp_line
			(start 0.508 -0.9398)
			(end -0.508 -0.9398)
			(stroke
				(width 0.1524)
				(type default)
			)
			(layer "F.SilkS")
		)
		(fp_line
			(start -0.508 -0.9398)
			(end -0.508 0.9398)
			(stroke
				(width 0.1524)
				(type default)
			)
			(layer "F.SilkS")
		)
		(fp_rect
			(start -0.508 0.9398)
			(end 0.508 -0.9398)
			(stroke
				(width 0)
				(type default)
			)
			(fill no)
			(layer "F.CrtYd")
		)
		(fp_rect
			(start -0.508 0.9398)
			(end 0.508 -0.9398)
			(stroke
				(width 0)
				(type default)
			)
			(fill no)
			(layer "F.Fab")
		)
		(pad "1" smd custom
			(at 0 -0.4445 180)
			(size 0.1397 0.1397)
			(layers "F.Cu" "F.Mask" "F.Paste")
			(net "P3V3_STBY")
			(options
				(clearance outline)
				(anchor circle)
			)
			(primitives
				(gr_poly
					(pts
						(arc
							(start -0.1778 -0.2794)
							(mid -0.249642 -0.249642)
							(end -0.2794 -0.1778)
						)
						(arc
							(start -0.2794 0.1778)
							(mid -0.249642 0.249642)
							(end -0.1778 0.2794)
						)
						(arc
							(start 0.1778 0.2794)
							(mid 0.249642 0.249642)
							(end 0.2794 0.1778)
						)
						(arc
							(start 0.2794 -0.1778)
							(mid 0.249642 -0.249642)
							(end 0.1778 -0.2794)
						)
					)
					(width 0)
					(fill yes)
				)
			)
		)
		(pad "2" smd custom
			(at 0 0.4445 180)
			(size 0.1397 0.1397)
			(layers "F.Cu" "F.Mask" "F.Paste")
			(net "COMP_TO_BMC_RESET_N_OUT")
			(options
				(clearance outline)
				(anchor circle)
			)
			(primitives
				(gr_poly
					(pts
						(arc
							(start -0.1778 -0.2794)
							(mid -0.249642 -0.249642)
							(end -0.2794 -0.1778)
						)
						(arc
							(start -0.2794 0.1778)
							(mid -0.249642 0.249642)
							(end -0.1778 0.2794)
						)
						(arc
							(start 0.1778 0.2794)
							(mid 0.249642 0.249642)
							(end 0.2794 0.1778)
						)
						(arc
							(start 0.2794 -0.1778)
							(mid 0.249642 -0.249642)
							(end 0.1778 -0.2794)
						)
					)
					(width 0)
					(fill yes)
				)
			)
		)
	)
	(footprint ""
		(layer "F.Cu")
		(at 92.623894 -164.807646 180)
		(property "Reference" "X1"
			(at 0 0 180)
			(layer "F.SilkS")
			(hide yes)
			(effects
				(font
					(size 1.27 1.27)
				)
			)
		)
		(property "Value" "XTAL-24MHZ-87-GP"
			(at -0.0889 -3.0988 180)
			(unlocked yes)
			(layer "F.Fab")
			(hide yes)
			(effects
				(font
					(size 1.016 1.016)
					(thickness 0.1524)
				)
			)
		)
		(property "Device Type" "OSC-3225-4P-4H30"
			(at -0.0889 -4.6228 180)
			(unlocked yes)
			(layer "F.Fab")
			(hide yes)
			(effects
				(font
					(size 1.016 1.016)
					(thickness 0.1524)
				)
			)
		)
		(duplicate_pad_numbers_are_jumpers no)
		(fp_line
			(start 2.1209 1.5494)
			(end 2.1209 -1.5494)
			(stroke
				(width 0.1524)
				(type default)
			)
			(layer "F.SilkS")
		)
		(fp_line
			(start 2.1209 -1.5494)
			(end -2.1209 -1.5494)
			(stroke
				(width 0.1524)
				(type default)
			)
			(layer "F.SilkS")
		)
		(fp_line
			(start -1.143 1.651)
			(end -2.2098 1.651)
			(stroke
				(width 0.3302)
				(type default)
			)
			(layer "F.SilkS")
		)
		(fp_line
			(start -2.1209 1.5494)
			(end 2.1209 1.5494)
			(stroke
				(width 0.1524)
				(type default)
			)
			(layer "F.SilkS")
		)
		(fp_line
			(start -2.1209 -1.5494)
			(end -2.1209 1.5494)
			(stroke
				(width 0.1524)
				(type default)
			)
			(layer "F.SilkS")
		)
		(fp_line
			(start -2.2098 1.651)
			(end -2.2098 0.6604)
			(stroke
				(width 0.3302)
				(type default)
			)
			(layer "F.SilkS")
		)
		(fp_poly
			(pts
				(xy -2.6289 1.1938) (xy -2.6289 0.3302) (xy -2.1971 0.762)
			)
			(stroke
				(width 0)
				(type default)
			)
			(fill yes)
			(layer "F.SilkS")
		)
		(fp_rect
			(start -1.6002 1.2446)
			(end 1.6002 -1.2446)
			(stroke
				(width 0)
				(type default)
			)
			(fill no)
			(layer "F.CrtYd")
		)
		(fp_poly
			(pts
				(xy -2.3749 1.8034) (xy -2.3749 -1.8034) (xy 2.3749 -1.8034) (xy 2.3749 1.8034) (xy 0.00254 1.8034)
				(xy 0.00254 1.2446) (xy 1.6002 1.2446) (xy 1.6002 -1.2446) (xy -1.6002 -1.2446) (xy -1.6002 1.2446)
				(xy -0.00254 1.2446) (xy -0.00254 1.8034)
			)
			(stroke
				(width 0)
				(type default)
			)
			(fill no)
			(layer "F.CrtYd")
		)
		(fp_rect
			(start -2.3749 1.8034)
			(end 2.3749 -1.8034)
			(stroke
				(width 0)
				(type default)
			)
			(fill no)
			(layer "F.Fab")
		)
		(pad "1" smd rect
			(at -1.171448 0.756412 180)
			(size 1.397 1.0668)
			(layers "F.Cu" "F.Mask" "F.Paste")
			(net "USB_HUB_XTAL_OUT")
		)
		(pad "2" smd rect
			(at 1.171448 0.756412 180)
			(size 1.397 1.0668)
			(layers "F.Cu" "F.Mask" "F.Paste")
			(net "GND")
		)
		(pad "3" smd rect
			(at 1.171448 -0.756412 180)
			(size 1.397 1.0668)
			(layers "F.Cu" "F.Mask" "F.Paste")
			(net "USB_HUB_XTAL_IN")
		)
		(pad "4" smd rect
			(at -1.171448 -0.756412 180)
			(size 1.397 1.0668)
			(layers "F.Cu" "F.Mask" "F.Paste")
			(net "GND")
		)
		(zone
			(layer "F.Cu")
			(hatch none 0.5)
			(connect_pads
				(clearance 0)
			)
			(min_thickness 0.25)
			(keepout
				(tracks not_allowed)
				(vias allowed)
				(pads allowed)
				(copperpour not_allowed)
				(footprints allowed)
			)
			(placement
				(enabled no)
				(sheetname "")
			)
			(fill
				(thermal_gap 0.5)
				(thermal_bridge_width 0.5)
				(island_removal_mode 0)
			)
			(polygon
				(pts
					(xy 92.674694 -164.858446) (xy 92.573094 -164.858446) (xy 92.573094 -164.756846) (xy 92.674694 -164.756846)
				)
			)
		)
		(zone
			(layer "F.Cu")
			(hatch none 0.5)
			(connect_pads
				(clearance 0)
			)
			(min_thickness 0.25)
			(keepout
				(tracks allowed)
				(vias not_allowed)
				(pads allowed)
				(copperpour not_allowed)
				(footprints allowed)
			)
			(placement
				(enabled no)
				(sheetname "")
			)
			(fill
				(thermal_gap 0.5)
				(thermal_bridge_width 0.5)
				(island_removal_mode 0)
			)
			(polygon
				(pts
					(xy 93.096842 -163.517834) (xy 92.150946 -163.517834) (xy 92.150946 -164.584634) (xy 90.753946 -164.584634)
					(xy 90.753946 -165.030658) (xy 92.150946 -165.030658) (xy 92.150946 -166.097458) (xy 93.096842 -166.097458)
					(xy 93.096842 -165.030658) (xy 94.493842 -165.030658) (xy 94.493842 -164.584634) (xy 93.096842 -164.584634)
				)
			)
		)
	)
	(footprint ""
		(layer "F.Cu")
		(at 68.5038 -120.49252 90)
		(property "Reference" "R764"
			(at 0 0 90)
			(layer "F.SilkS")
			(hide yes)
			(effects
				(font
					(size 1.27 1.27)
				)
			)
		)
		(property "Value" "0R2J-2-GP"
			(at 0.064008 -3.993896 90)
			(unlocked yes)
			(layer "F.Fab")
			(hide yes)
			(effects
				(font
					(size 1.016 1.016)
					(thickness 0.1524)
				)
			)
		)
		(property "Device Type" "R402H16"
			(at 0.064008 -5.517896 90)
			(unlocked yes)
			(layer "F.Fab")
			(hide yes)
			(effects
				(font
					(size 1.016 1.016)
					(thickness 0.1524)
				)
			)
		)
		(duplicate_pad_numbers_are_jumpers no)
		(fp_line
			(start 0.508 -0.9398)
			(end -0.508 -0.9398)
			(stroke
				(width 0.1524)
				(type default)
			)
			(layer "F.SilkS")
		)
		(fp_line
			(start -0.508 -0.9398)
			(end -0.508 0.9398)
			(stroke
				(width 0.1524)
				(type default)
			)
			(layer "F.SilkS")
		)
		(fp_rect
			(start -0.508 0.9398)
			(end 0.508 -0.9398)
			(stroke
				(width 0)
				(type default)
			)
			(fill no)
			(layer "F.CrtYd")
		)
		(fp_rect
			(start -0.508 0.9398)
			(end 0.508 -0.9398)
			(stroke
				(width 0)
				(type default)
			)
			(fill no)
			(layer "F.Fab")
		)
		(pad "1" smd custom
			(at 0 -0.4445 90)
			(size 0.1397 0.1397)
			(layers "F.Cu" "F.Mask" "F.Paste")
			(net "FLA1_SPI_RST")
			(options
				(clearance outline)
				(anchor circle)
			)
			(primitives
				(gr_poly
					(pts
						(arc
							(start -0.1778 -0.2794)
							(mid -0.249642 -0.249642)
							(end -0.2794 -0.1778)
						)
						(arc
							(start -0.2794 0.1778)
							(mid -0.249642 0.249642)
							(end -0.1778 0.2794)
						)
						(arc
							(start 0.1778 0.2794)
							(mid 0.249642 0.249642)
							(end 0.2794 0.1778)
						)
						(arc
							(start 0.2794 -0.1778)
							(mid 0.249642 -0.249642)
							(end 0.1778 -0.2794)
						)
					)
					(width 0)
					(fill yes)
				)
			)
		)
		(pad "2" smd custom
			(at 0 0.4445 90)
			(size 0.1397 0.1397)
			(layers "F.Cu" "F.Mask" "F.Paste")
			(net "RST_BMC_EXTRST_N")
			(options
				(clearance outline)
				(anchor circle)
			)
			(primitives
				(gr_poly
					(pts
						(arc
							(start -0.1778 -0.2794)
							(mid -0.249642 -0.249642)
							(end -0.2794 -0.1778)
						)
						(arc
							(start -0.2794 0.1778)
							(mid -0.249642 0.249642)
							(end -0.1778 0.2794)
						)
						(arc
							(start 0.1778 0.2794)
							(mid 0.249642 0.249642)
							(end 0.2794 0.1778)
						)
						(arc
							(start 0.2794 -0.1778)
							(mid 0.249642 -0.249642)
							(end 0.1778 -0.2794)
						)
					)
					(width 0)
					(fill yes)
				)
			)
		)
	)
	(footprint ""
		(layer "F.Cu")
		(at 40.105584 -131.475226 180)
		(property "Reference" "R378"
			(at 0 0 180)
			(layer "F.SilkS")
			(hide yes)
			(effects
				(font
					(size 1.27 1.27)
				)
			)
		)
		(property "Value" "4K7R2F-GP"
			(at 0.064008 -3.993896 180)
			(unlocked yes)
			(layer "F.Fab")
			(hide yes)
			(effects
				(font
					(size 1.016 1.016)
					(thickness 0.1524)
				)
			)
		)
		(property "Device Type" "R402H16"
			(at 0.064008 -5.517896 180)
			(unlocked yes)
			(layer "F.Fab")
			(hide yes)
			(effects
				(font
					(size 1.016 1.016)
					(thickness 0.1524)
				)
			)
		)
		(duplicate_pad_numbers_are_jumpers no)
		(fp_line
			(start 0.508 -0.9398)
			(end -0.508 -0.9398)
			(stroke
				(width 0.1524)
				(type default)
			)
			(layer "F.SilkS")
		)
		(fp_line
			(start -0.508 -0.9398)
			(end -0.508 0.9398)
			(stroke
				(width 0.1524)
				(type default)
			)
			(layer "F.SilkS")
		)
		(fp_rect
			(start -0.508 0.9398)
			(end 0.508 -0.9398)
			(stroke
				(width 0)
				(type default)
			)
			(fill no)
			(layer "F.CrtYd")
		)
		(fp_rect
			(start -0.508 0.9398)
			(end 0.508 -0.9398)
			(stroke
				(width 0)
				(type default)
			)
			(fill no)
			(layer "F.Fab")
		)
		(pad "1" smd custom
			(at 0 -0.4445 180)
			(size 0.1397 0.1397)
			(layers "F.Cu" "F.Mask" "F.Paste")
			(net "P3V3_STBY")
			(options
				(clearance outline)
				(anchor circle)
			)
			(primitives
				(gr_poly
					(pts
						(arc
							(start -0.1778 -0.2794)
							(mid -0.249642 -0.249642)
							(end -0.2794 -0.1778)
						)
						(arc
							(start -0.2794 0.1778)
							(mid -0.249642 0.249642)
							(end -0.1778 0.2794)
						)
						(arc
							(start 0.1778 0.2794)
							(mid 0.249642 0.249642)
							(end 0.2794 0.1778)
						)
						(arc
							(start 0.2794 -0.1778)
							(mid 0.249642 -0.249642)
							(end 0.1778 -0.2794)
						)
					)
					(width 0)
					(fill yes)
				)
			)
		)
		(pad "2" smd custom
			(at 0 0.4445 180)
			(size 0.1397 0.1397)
			(layers "F.Cu" "F.Mask" "F.Paste")
			(net "BMC_GPIOZ6")
			(options
				(clearance outline)
				(anchor circle)
			)
			(primitives
				(gr_poly
					(pts
						(arc
							(start -0.1778 -0.2794)
							(mid -0.249642 -0.249642)
							(end -0.2794 -0.1778)
						)
						(arc
							(start -0.2794 0.1778)
							(mid -0.249642 0.249642)
							(end -0.1778 0.2794)
						)
						(arc
							(start 0.1778 0.2794)
							(mid 0.249642 0.249642)
							(end 0.2794 0.1778)
						)
						(arc
							(start 0.2794 -0.1778)
							(mid 0.249642 -0.249642)
							(end 0.1778 -0.2794)
						)
					)
					(width 0)
					(fill yes)
				)
			)
		)
	)
	(footprint ""
		(layer "F.Cu")
		(at 66.3702 -169.164 90)
		(property "Reference" "C38"
			(at 0 0 90)
			(layer "F.SilkS")
			(hide yes)
			(effects
				(font
					(size 1.27 1.27)
				)
			)
		)
		(property "Value" "SCD1U16V2KX-3GP"
			(at 1.1811 -2.7051 90)
			(unlocked yes)
			(layer "F.Fab")
			(hide yes)
			(effects
				(font
					(size 1.016 1.016)
					(thickness 0.1524)
				)
			)
		)
		(property "Device Type" "C402H22"
			(at 1.1811 -4.2291 90)
			(unlocked yes)
			(layer "F.Fab")
			(hide yes)
			(effects
				(font
					(size 1.016 1.016)
					(thickness 0.1524)
				)
			)
		)
		(duplicate_pad_numbers_are_jumpers no)
		(fp_rect
			(start -0.4318 0.9525)
			(end 0.4318 -0.9525)
			(stroke
				(width 0)
				(type default)
			)
			(fill no)
			(layer "F.CrtYd")
		)
		(fp_rect
			(start -0.4318 0.9525)
			(end 0.4318 -0.9525)
			(stroke
				(width 0)
				(type default)
			)
			(fill no)
			(layer "F.Fab")
		)
		(pad "1" smd custom
			(at 0 -0.4445 90)
			(size 0.1524 0.1524)
			(layers "F.Cu" "F.Mask" "F.Paste")
			(net "Q4_G")
			(options
				(clearance outline)
				(anchor circle)
			)
			(primitives
				(gr_poly
					(pts
						(arc
							(start 0.3048 -0.2032)
							(mid 0.275042 -0.275042)
							(end 0.2032 -0.3048)
						)
						(arc
							(start -0.2032 -0.3048)
							(mid -0.275042 -0.275042)
							(end -0.3048 -0.2032)
						)
						(arc
							(start -0.3048 0.2032)
							(mid -0.275042 0.275042)
							(end -0.2032 0.3048)
						)
						(arc
							(start 0.2032 0.3048)
							(mid 0.275042 0.275042)
							(end 0.3048 0.2032)
						)
					)
					(width 0)
					(fill yes)
				)
			)
		)
		(pad "2" smd custom
			(at 0 0.4445 90)
			(size 0.1524 0.1524)
			(layers "F.Cu" "F.Mask" "F.Paste")
			(net "GND")
			(options
				(clearance outline)
				(anchor circle)
			)
			(primitives
				(gr_poly
					(pts
						(arc
							(start 0.3048 -0.2032)
							(mid 0.275042 -0.275042)
							(end 0.2032 -0.3048)
						)
						(arc
							(start -0.2032 -0.3048)
							(mid -0.275042 -0.275042)
							(end -0.3048 -0.2032)
						)
						(arc
							(start -0.3048 0.2032)
							(mid -0.275042 0.275042)
							(end -0.2032 0.3048)
						)
						(arc
							(start 0.2032 0.3048)
							(mid 0.275042 0.275042)
							(end 0.3048 0.2032)
						)
					)
					(width 0)
					(fill yes)
				)
			)
		)
	)
	(footprint ""
		(layer "F.Cu")
		(at 177.97526 -140.28801 -135)
		(property "Reference" "VIA61"
			(at 0 0 225)
			(layer "F.SilkS")
			(hide yes)
			(effects
				(font
					(size 1.27 1.27)
				)
			)
		)
		(property "Value" "85OHM-8L-1D6MM-L16L18-GP"
			(at 4.064105 0.609655 225)
			(unlocked yes)
			(layer "F.Fab")
			(hide yes)
			(effects
				(font
					(size 1.016 1.016)
					(thickness 0.1524)
				)
			)
		)
		(property "Device Type" "VIA-PCIE-4P-368076"
			(at 4.064105 -0.914474 225)
			(unlocked yes)
			(layer "F.Fab")
			(hide yes)
			(effects
				(font
					(size 1.016 1.016)
					(thickness 0.1524)
				)
			)
		)
		(duplicate_pad_numbers_are_jumpers no)
		(fp_poly
			(pts
				(xy -1.841491 -0.381057) (xy 1.841509 -0.381058) (xy 1.841508 0.380942) (xy -1.841491 0.380942)
			)
			(stroke
				(width 0)
				(type default)
			)
			(fill no)
			(layer "F.CrtYd")
		)
		(fp_poly
			(pts
				(xy -1.841491 -0.381057) (xy 1.841509 -0.381058) (xy 1.841508 0.380942) (xy -1.841491 0.380942)
			)
			(stroke
				(width 0)
				(type default)
			)
			(fill no)
			(layer "F.Fab")
		)
		(pad "1" thru_hole circle
			(at -1.460499 0 225)
			(size 0.508 0.508)
			(drill 0.254)
			(layers "*.Cu" "*.Mask")
			(remove_unused_layers no)
			(net "GND")
			(clearance 0.127)
			(thermal_gap 0.127)
		)
		(pad "2" thru_hole circle
			(at -0.4445 0 225)
			(size 0.508 0.508)
			(drill 0.254)
			(layers "*.Cu" "*.Mask")
			(remove_unused_layers no)
			(net "PCIE_IOM_TO_COMP_13_DP")
			(clearance 0.127)
			(thermal_gap 0.127)
		)
		(pad "3" thru_hole circle
			(at 0.4445 0 225)
			(size 0.508 0.508)
			(drill 0.254)
			(layers "*.Cu" "*.Mask")
			(remove_unused_layers no)
			(net "PCIE_IOM_TO_COMP_13_DN")
			(clearance 0.127)
			(thermal_gap 0.127)
		)
		(pad "4" thru_hole circle
			(at 1.460499 0 225)
			(size 0.508 0.508)
			(drill 0.254)
			(layers "*.Cu" "*.Mask")
			(remove_unused_layers no)
			(net "GND")
			(clearance 0.127)
			(thermal_gap 0.127)
		)
	)
	(footprint ""
		(layer "F.Cu")
		(at 161.708338 -14.886178 180)
		(property "Reference" "R519"
			(at 0 0 180)
			(layer "F.SilkS")
			(hide yes)
			(effects
				(font
					(size 1.27 1.27)
				)
			)
		)
		(property "Value" "1KR2F-3-GP"
			(at 0.064008 -3.993896 180)
			(unlocked yes)
			(layer "F.Fab")
			(hide yes)
			(effects
				(font
					(size 1.016 1.016)
					(thickness 0.1524)
				)
			)
		)
		(property "Device Type" "R402H16"
			(at 0.064008 -5.517896 180)
			(unlocked yes)
			(layer "F.Fab")
			(hide yes)
			(effects
				(font
					(size 1.016 1.016)
					(thickness 0.1524)
				)
			)
		)
		(duplicate_pad_numbers_are_jumpers no)
		(fp_line
			(start 0.508 -0.9398)
			(end -0.508 -0.9398)
			(stroke
				(width 0.1524)
				(type default)
			)
			(layer "F.SilkS")
		)
		(fp_line
			(start -0.508 -0.9398)
			(end -0.508 0.9398)
			(stroke
				(width 0.1524)
				(type default)
			)
			(layer "F.SilkS")
		)
		(fp_rect
			(start -0.508 0.9398)
			(end 0.508 -0.9398)
			(stroke
				(width 0)
				(type default)
			)
			(fill no)
			(layer "F.CrtYd")
		)
		(fp_rect
			(start -0.508 0.9398)
			(end 0.508 -0.9398)
			(stroke
				(width 0)
				(type default)
			)
			(fill no)
			(layer "F.Fab")
		)
		(pad "1" smd custom
			(at 0 -0.4445 180)
			(size 0.1397 0.1397)
			(layers "F.Cu" "F.Mask" "F.Paste")
			(net "P1V8_STBY_SW")
			(options
				(clearance outline)
				(anchor circle)
			)
			(primitives
				(gr_poly
					(pts
						(arc
							(start -0.1778 -0.2794)
							(mid -0.249642 -0.249642)
							(end -0.2794 -0.1778)
						)
						(arc
							(start -0.2794 0.1778)
							(mid -0.249642 0.249642)
							(end -0.1778 0.2794)
						)
						(arc
							(start 0.1778 0.2794)
							(mid 0.249642 0.249642)
							(end 0.2794 0.1778)
						)
						(arc
							(start 0.2794 -0.1778)
							(mid 0.249642 -0.249642)
							(end 0.1778 -0.2794)
						)
					)
					(width 0)
					(fill yes)
				)
			)
		)
		(pad "2" smd custom
			(at 0 0.4445 180)
			(size 0.1397 0.1397)
			(layers "F.Cu" "F.Mask" "F.Paste")
			(net "P1V8_STBY_VFB_R")
			(options
				(clearance outline)
				(anchor circle)
			)
			(primitives
				(gr_poly
					(pts
						(arc
							(start -0.1778 -0.2794)
							(mid -0.249642 -0.249642)
							(end -0.2794 -0.1778)
						)
						(arc
							(start -0.2794 0.1778)
							(mid -0.249642 0.249642)
							(end -0.1778 0.2794)
						)
						(arc
							(start 0.1778 0.2794)
							(mid 0.249642 0.249642)
							(end 0.2794 0.1778)
						)
						(arc
							(start 0.2794 -0.1778)
							(mid 0.249642 -0.249642)
							(end 0.1778 -0.2794)
						)
					)
					(width 0)
					(fill yes)
				)
			)
		)
	)
	(footprint ""
		(layer "F.Cu")
		(at 34.2138 -176.8094 180)
		(property "Reference" "G3"
			(at 0 0 180)
			(layer "F.SilkS")
			(hide yes)
			(effects
				(font
					(size 1.27 1.27)
				)
			)
		)
		(property "Value" "COPPER-CLOSE-GP-U"
			(at 0.0762 -2.8702 180)
			(unlocked yes)
			(layer "F.Fab")
			(hide yes)
			(effects
				(font
					(size 1.016 1.016)
					(thickness 0.1524)
				)
			)
		)
		(property "Device Type" "CON2C-U"
			(at 0.0762 -4.3942 180)
			(unlocked yes)
			(layer "F.Fab")
			(hide yes)
			(effects
				(font
					(size 1.016 1.016)
					(thickness 0.1524)
				)
			)
		)
		(duplicate_pad_numbers_are_jumpers no)
		(fp_rect
			(start -0.9398 0.9652)
			(end 0.9398 -0.9652)
			(stroke
				(width 0)
				(type default)
			)
			(fill no)
			(layer "F.CrtYd")
		)
		(fp_rect
			(start -0.9398 0.9652)
			(end 0.9398 -0.9652)
			(stroke
				(width 0)
				(type default)
			)
			(fill no)
			(layer "F.Fab")
		)
		(pad "1" smd custom
			(at 0 -0.5334 180)
			(size 0.17145 0.17145)
			(layers "F.Cu" "F.Mask" "F.Paste")
			(net "AGND_P3V3_STBY")
			(options
				(clearance outline)
				(anchor circle)
			)
			(primitives
				(gr_poly
					(pts
						(xy -0.127 0.3429) (xy -0.127 0.1651) (xy -0.635 -0.3429) (xy 0.635 -0.3429) (xy 0.127 0.1651)
						(xy 0.127 0.3429)
					)
					(width 0)
					(fill yes)
				)
			)
		)
		(pad "2" smd custom
			(at 0 0.5334 180)
			(size 0.17145 0.17145)
			(layers "F.Cu" "F.Mask" "F.Paste")
			(net "GND")
			(options
				(clearance outline)
				(anchor circle)
			)
			(primitives
				(gr_poly
					(pts
						(xy -0.635 0.3429) (xy -0.127 -0.1651) (xy -0.127 -0.3429) (xy 0.127 -0.3429) (xy 0.127 -0.1651)
						(xy 0.635 0.3429)
					)
					(width 0)
					(fill yes)
				)
			)
		)
	)
	(footprint ""
		(layer "F.Cu")
		(at 30.848046 -175.906938 180)
		(property "Reference" "R497"
			(at 0 0 180)
			(layer "F.SilkS")
			(hide yes)
			(effects
				(font
					(size 1.27 1.27)
				)
			)
		)
		(property "Value" "619KR2F-GP"
			(at 0.064008 -3.993896 180)
			(unlocked yes)
			(layer "F.Fab")
			(hide yes)
			(effects
				(font
					(size 1.016 1.016)
					(thickness 0.1524)
				)
			)
		)
		(property "Device Type" "R402H16"
			(at 0.064008 -5.517896 180)
			(unlocked yes)
			(layer "F.Fab")
			(hide yes)
			(effects
				(font
					(size 1.016 1.016)
					(thickness 0.1524)
				)
			)
		)
		(duplicate_pad_numbers_are_jumpers no)
		(fp_line
			(start 0.508 -0.9398)
			(end -0.508 -0.9398)
			(stroke
				(width 0.1524)
				(type default)
			)
			(layer "F.SilkS")
		)
		(fp_line
			(start -0.508 -0.9398)
			(end -0.508 0.9398)
			(stroke
				(width 0.1524)
				(type default)
			)
			(layer "F.SilkS")
		)
		(fp_rect
			(start -0.508 0.9398)
			(end 0.508 -0.9398)
			(stroke
				(width 0)
				(type default)
			)
			(fill no)
			(layer "F.CrtYd")
		)
		(fp_rect
			(start -0.508 0.9398)
			(end 0.508 -0.9398)
			(stroke
				(width 0)
				(type default)
			)
			(fill no)
			(layer "F.Fab")
		)
		(pad "1" smd custom
			(at 0 -0.4445 180)
			(size 0.1397 0.1397)
			(layers "F.Cu" "F.Mask" "F.Paste")
			(net "AGND_P3V3_STBY")
			(options
				(clearance outline)
				(anchor circle)
			)
			(primitives
				(gr_poly
					(pts
						(arc
							(start -0.1778 -0.2794)
							(mid -0.249642 -0.249642)
							(end -0.2794 -0.1778)
						)
						(arc
							(start -0.2794 0.1778)
							(mid -0.249642 0.249642)
							(end -0.1778 0.2794)
						)
						(arc
							(start 0.1778 0.2794)
							(mid 0.249642 0.249642)
							(end 0.2794 0.1778)
						)
						(arc
							(start 0.2794 -0.1778)
							(mid 0.249642 -0.249642)
							(end 0.1778 -0.2794)
						)
					)
					(width 0)
					(fill yes)
				)
			)
		)
		(pad "2" smd custom
			(at 0 0.4445 180)
			(size 0.1397 0.1397)
			(layers "F.Cu" "F.Mask" "F.Paste")
			(net "P3V3_STBY_RF")
			(options
				(clearance outline)
				(anchor circle)
			)
			(primitives
				(gr_poly
					(pts
						(arc
							(start -0.1778 -0.2794)
							(mid -0.249642 -0.249642)
							(end -0.2794 -0.1778)
						)
						(arc
							(start -0.2794 0.1778)
							(mid -0.249642 0.249642)
							(end -0.1778 0.2794)
						)
						(arc
							(start 0.1778 0.2794)
							(mid 0.249642 0.249642)
							(end 0.2794 0.1778)
						)
						(arc
							(start 0.2794 -0.1778)
							(mid 0.249642 -0.249642)
							(end 0.1778 -0.2794)
						)
					)
					(width 0)
					(fill yes)
				)
			)
		)
	)
	(footprint ""
		(layer "F.Cu")
		(at 71.81723 -142.670276 90)
		(property "Reference" "R52"
			(at 0 0 90)
			(layer "F.SilkS")
			(hide yes)
			(effects
				(font
					(size 1.27 1.27)
				)
			)
		)
		(property "Value" "33R2F-3-GP"
			(at 0.064008 -3.993896 90)
			(unlocked yes)
			(layer "F.Fab")
			(hide yes)
			(effects
				(font
					(size 1.016 1.016)
					(thickness 0.1524)
				)
			)
		)
		(property "Device Type" "R402H16"
			(at 0.064008 -5.517896 90)
			(unlocked yes)
			(layer "F.Fab")
			(hide yes)
			(effects
				(font
					(size 1.016 1.016)
					(thickness 0.1524)
				)
			)
		)
		(duplicate_pad_numbers_are_jumpers no)
		(fp_line
			(start 0.508 -0.9398)
			(end -0.508 -0.9398)
			(stroke
				(width 0.1524)
				(type default)
			)
			(layer "F.SilkS")
		)
		(fp_line
			(start -0.508 -0.9398)
			(end -0.508 0.9398)
			(stroke
				(width 0.1524)
				(type default)
			)
			(layer "F.SilkS")
		)
		(fp_rect
			(start -0.508 0.9398)
			(end 0.508 -0.9398)
			(stroke
				(width 0)
				(type default)
			)
			(fill no)
			(layer "F.CrtYd")
		)
		(fp_rect
			(start -0.508 0.9398)
			(end 0.508 -0.9398)
			(stroke
				(width 0)
				(type default)
			)
			(fill no)
			(layer "F.Fab")
		)
		(pad "1" smd custom
			(at 0 -0.4445 90)
			(size 0.1397 0.1397)
			(layers "F.Cu" "F.Mask" "F.Paste")
			(net "FP_PWRBTN")
			(options
				(clearance outline)
				(anchor circle)
			)
			(primitives
				(gr_poly
					(pts
						(arc
							(start -0.1778 -0.2794)
							(mid -0.249642 -0.249642)
							(end -0.2794 -0.1778)
						)
						(arc
							(start -0.2794 0.1778)
							(mid -0.249642 0.249642)
							(end -0.1778 0.2794)
						)
						(arc
							(start 0.1778 0.2794)
							(mid 0.249642 0.249642)
							(end 0.2794 0.1778)
						)
						(arc
							(start 0.2794 -0.1778)
							(mid 0.249642 -0.249642)
							(end 0.1778 -0.2794)
						)
					)
					(width 0)
					(fill yes)
				)
			)
		)
		(pad "2" smd custom
			(at 0 0.4445 90)
			(size 0.1397 0.1397)
			(layers "F.Cu" "F.Mask" "F.Paste")
			(net "PWRBTN_OUT_N")
			(options
				(clearance outline)
				(anchor circle)
			)
			(primitives
				(gr_poly
					(pts
						(arc
							(start -0.1778 -0.2794)
							(mid -0.249642 -0.249642)
							(end -0.2794 -0.1778)
						)
						(arc
							(start -0.2794 0.1778)
							(mid -0.249642 0.249642)
							(end -0.1778 0.2794)
						)
						(arc
							(start 0.1778 0.2794)
							(mid 0.249642 0.249642)
							(end 0.2794 0.1778)
						)
						(arc
							(start 0.2794 -0.1778)
							(mid 0.249642 -0.249642)
							(end 0.1778 -0.2794)
						)
					)
					(width 0)
					(fill yes)
				)
			)
		)
	)
	(footprint ""
		(layer "F.Cu")
		(at 225.880168 -53.12029 90)
		(property "Reference" "C151"
			(at 0 0 90)
			(layer "F.SilkS")
			(hide yes)
			(effects
				(font
					(size 1.27 1.27)
				)
			)
		)
		(property "Value" "SC10U16V5KX-7-GP-U"
			(at -0.0762 -6.1214 90)
			(unlocked yes)
			(layer "F.Fab")
			(hide yes)
			(effects
				(font
					(size 1.016 1.016)
					(thickness 0.1524)
				)
			)
		)
		(property "Device Type" "C805H58"
			(at -0.0762 -8.1534 90)
			(unlocked yes)
			(layer "F.Fab")
			(hide yes)
			(effects
				(font
					(size 1.016 1.016)
					(thickness 0.1524)
				)
			)
		)
		(duplicate_pad_numbers_are_jumpers no)
		(fp_line
			(start 0.635 0)
			(end -0.635 0)
			(stroke
				(width 0.508)
				(type default)
			)
			(layer "F.SilkS")
		)
		(fp_rect
			(start -0.9652 1.778)
			(end 0.9652 -1.778)
			(stroke
				(width 0)
				(type default)
			)
			(fill no)
			(layer "F.CrtYd")
		)
		(fp_poly
			(pts
				(xy -0.9652 -1.778) (xy 0.9652 -1.778) (xy 0.9652 1.778) (xy -0.9652 1.778)
			)
			(stroke
				(width 0)
				(type default)
			)
			(fill no)
			(layer "F.Fab")
		)
		(pad "1" smd rect
			(at 0 -0.9652 90)
			(size 1.397 1.143)
			(layers "F.Cu" "F.Mask" "F.Paste")
			(net "P12V_STBY_VIN_PU1")
		)
		(pad "2" smd rect
			(at 0 0.9652 90)
			(size 1.397 1.143)
			(layers "F.Cu" "F.Mask" "F.Paste")
			(net "GND")
		)
	)
	(footprint ""
		(layer "F.Cu")
		(at 34.284158 -155.71724 -90)
		(property "Reference" "R322"
			(at 0 0 270)
			(layer "F.SilkS")
			(hide yes)
			(effects
				(font
					(size 1.27 1.27)
				)
			)
		)
		(property "Value" "0R2J-2-GP"
			(at 0.064008 -3.993896 270)
			(unlocked yes)
			(layer "F.Fab")
			(hide yes)
			(effects
				(font
					(size 1.016 1.016)
					(thickness 0.1524)
				)
			)
		)
		(property "Device Type" "R402H16"
			(at 0.064008 -5.517896 270)
			(unlocked yes)
			(layer "F.Fab")
			(hide yes)
			(effects
				(font
					(size 1.016 1.016)
					(thickness 0.1524)
				)
			)
		)
		(duplicate_pad_numbers_are_jumpers no)
		(fp_line
			(start -0.508 -0.9398)
			(end -0.508 0.9398)
			(stroke
				(width 0.1524)
				(type default)
			)
			(layer "F.SilkS")
		)
		(fp_line
			(start 0.508 -0.9398)
			(end -0.508 -0.9398)
			(stroke
				(width 0.1524)
				(type default)
			)
			(layer "F.SilkS")
		)
		(fp_rect
			(start -0.508 0.9398)
			(end 0.508 -0.9398)
			(stroke
				(width 0)
				(type default)
			)
			(fill no)
			(layer "F.CrtYd")
		)
		(fp_rect
			(start -0.508 0.9398)
			(end 0.508 -0.9398)
			(stroke
				(width 0)
				(type default)
			)
			(fill no)
			(layer "F.Fab")
		)
		(pad "1" smd custom
			(at 0 -0.4445 270)
			(size 0.1397 0.1397)
			(layers "F.Cu" "F.Mask" "F.Paste")
			(net "COMP_POWER_FAIL_R_N")
			(options
				(clearance outline)
				(anchor circle)
			)
			(primitives
				(gr_poly
					(pts
						(arc
							(start -0.1778 -0.2794)
							(mid -0.249642 -0.249642)
							(end -0.2794 -0.1778)
						)
						(arc
							(start -0.2794 0.1778)
							(mid -0.249642 0.249642)
							(end -0.1778 0.2794)
						)
						(arc
							(start 0.1778 0.2794)
							(mid 0.249642 0.249642)
							(end 0.2794 0.1778)
						)
						(arc
							(start 0.2794 -0.1778)
							(mid 0.249642 -0.249642)
							(end 0.1778 -0.2794)
						)
					)
					(width 0)
					(fill yes)
				)
			)
		)
		(pad "2" smd custom
			(at 0 0.4445 270)
			(size 0.1397 0.1397)
			(layers "F.Cu" "F.Mask" "F.Paste")
			(net "COMP_POWER_FAIL_N")
			(options
				(clearance outline)
				(anchor circle)
			)
			(primitives
				(gr_poly
					(pts
						(arc
							(start -0.1778 -0.2794)
							(mid -0.249642 -0.249642)
							(end -0.2794 -0.1778)
						)
						(arc
							(start -0.2794 0.1778)
							(mid -0.249642 0.249642)
							(end -0.1778 0.2794)
						)
						(arc
							(start 0.1778 0.2794)
							(mid 0.249642 0.249642)
							(end 0.2794 0.1778)
						)
						(arc
							(start 0.2794 -0.1778)
							(mid 0.249642 -0.249642)
							(end 0.1778 -0.2794)
						)
					)
					(width 0)
					(fill yes)
				)
			)
		)
	)
	(footprint ""
		(layer "F.Cu")
		(at 36.900866 -157.70098)
		(property "Reference" "R714"
			(at 0 0 0)
			(layer "F.SilkS")
			(hide yes)
			(effects
				(font
					(size 1.27 1.27)
				)
			)
		)
		(property "Value" "0R2J-2-GP"
			(at 0.064008 -3.993896 0)
			(unlocked yes)
			(layer "F.Fab")
			(hide yes)
			(effects
				(font
					(size 1.016 1.016)
					(thickness 0.1524)
				)
			)
		)
		(property "Device Type" "R402H16"
			(at 0.064008 -5.517896 0)
			(unlocked yes)
			(layer "F.Fab")
			(hide yes)
			(effects
				(font
					(size 1.016 1.016)
					(thickness 0.1524)
				)
			)
		)
		(duplicate_pad_numbers_are_jumpers no)
		(fp_line
			(start -0.508 -0.9398)
			(end -0.508 0.9398)
			(stroke
				(width 0.1524)
				(type default)
			)
			(layer "F.SilkS")
		)
		(fp_line
			(start 0.508 -0.9398)
			(end -0.508 -0.9398)
			(stroke
				(width 0.1524)
				(type default)
			)
			(layer "F.SilkS")
		)
		(fp_rect
			(start -0.508 0.9398)
			(end 0.508 -0.9398)
			(stroke
				(width 0)
				(type default)
			)
			(fill no)
			(layer "F.CrtYd")
		)
		(fp_rect
			(start -0.508 0.9398)
			(end 0.508 -0.9398)
			(stroke
				(width 0)
				(type default)
			)
			(fill no)
			(layer "F.Fab")
		)
		(pad "1" smd custom
			(at 0 -0.4445)
			(size 0.1397 0.1397)
			(layers "F.Cu" "F.Mask" "F.Paste")
			(net "PWM_OUT_ZONE_D")
			(options
				(clearance outline)
				(anchor circle)
			)
			(primitives
				(gr_poly
					(pts
						(arc
							(start -0.1778 -0.2794)
							(mid -0.249642 -0.249642)
							(end -0.2794 -0.1778)
						)
						(arc
							(start -0.2794 0.1778)
							(mid -0.249642 0.249642)
							(end -0.1778 0.2794)
						)
						(arc
							(start 0.1778 0.2794)
							(mid 0.249642 0.249642)
							(end 0.2794 0.1778)
						)
						(arc
							(start 0.2794 -0.1778)
							(mid 0.249642 -0.249642)
							(end 0.1778 -0.2794)
						)
					)
					(width 0)
					(fill yes)
				)
			)
		)
		(pad "2" smd custom
			(at 0 0.4445)
			(size 0.1397 0.1397)
			(layers "F.Cu" "F.Mask" "F.Paste")
			(net "FAN_PWM1_BMC")
			(options
				(clearance outline)
				(anchor circle)
			)
			(primitives
				(gr_poly
					(pts
						(arc
							(start -0.1778 -0.2794)
							(mid -0.249642 -0.249642)
							(end -0.2794 -0.1778)
						)
						(arc
							(start -0.2794 0.1778)
							(mid -0.249642 0.249642)
							(end -0.1778 0.2794)
						)
						(arc
							(start 0.1778 0.2794)
							(mid 0.249642 0.249642)
							(end 0.2794 0.1778)
						)
						(arc
							(start 0.2794 -0.1778)
							(mid 0.249642 -0.249642)
							(end 0.1778 -0.2794)
						)
					)
					(width 0)
					(fill yes)
				)
			)
		)
	)
	(footprint ""
		(layer "F.Cu")
		(at 76.9874 -167.59682 180)
		(property "Reference" "C524"
			(at 0 0 180)
			(layer "F.SilkS")
			(hide yes)
			(effects
				(font
					(size 1.27 1.27)
				)
			)
		)
		(property "Value" "SC1U16V2KX-7-GP"
			(at 1.7526 -1.6002 180)
			(unlocked yes)
			(layer "F.Fab")
			(hide yes)
			(effects
				(font
					(size 1.016 1.016)
					(thickness 0.1524)
				)
			)
		)
		(property "Device Type" "C402-TO0D2H24"
			(at 1.7526 -3.1242 180)
			(unlocked yes)
			(layer "F.Fab")
			(hide yes)
			(effects
				(font
					(size 1.016 1.016)
					(thickness 0.1524)
				)
			)
		)
		(duplicate_pad_numbers_are_jumpers no)
		(fp_rect
			(start -0.4826 0.889)
			(end 0.4826 -0.889)
			(stroke
				(width 0)
				(type default)
			)
			(fill no)
			(layer "F.CrtYd")
		)
		(fp_rect
			(start -0.4826 0.889)
			(end 0.4826 -0.889)
			(stroke
				(width 0)
				(type default)
			)
			(fill no)
			(layer "F.Fab")
		)
		(pad "1" smd custom
			(at 0 -0.4572 180)
			(size 0.1524 0.1524)
			(layers "F.Cu" "F.Mask" "F.Paste")
			(net "P1V15_STBY_PG")
			(options
				(clearance outline)
				(anchor circle)
			)
			(primitives
				(gr_poly
					(pts
						(arc
							(start -0.254 0.3048)
							(mid -0.325842 0.275042)
							(end -0.3556 0.2032)
						)
						(arc
							(start -0.3556 -0.2032)
							(mid -0.325842 -0.275042)
							(end -0.254 -0.3048)
						)
						(arc
							(start 0.254 -0.3048)
							(mid 0.325842 -0.275042)
							(end 0.3556 -0.2032)
						)
						(arc
							(start 0.3556 0.2032)
							(mid 0.325842 0.275042)
							(end 0.254 0.3048)
						)
					)
					(width 0)
					(fill yes)
				)
			)
		)
		(pad "2" smd custom
			(at 0 0.4572 180)
			(size 0.1524 0.1524)
			(layers "F.Cu" "F.Mask" "F.Paste")
			(net "GND")
			(options
				(clearance outline)
				(anchor circle)
			)
			(primitives
				(gr_poly
					(pts
						(arc
							(start -0.254 0.3048)
							(mid -0.325842 0.275042)
							(end -0.3556 0.2032)
						)
						(arc
							(start -0.3556 -0.2032)
							(mid -0.325842 -0.275042)
							(end -0.254 -0.3048)
						)
						(arc
							(start 0.254 -0.3048)
							(mid 0.325842 -0.275042)
							(end 0.3556 -0.2032)
						)
						(arc
							(start 0.3556 0.2032)
							(mid 0.325842 0.275042)
							(end 0.254 0.3048)
						)
					)
					(width 0)
					(fill yes)
				)
			)
		)
	)
	(footprint ""
		(layer "F.Cu")
		(at 27.502358 -145.377154)
		(property "Reference" "R219"
			(at 0 0 0)
			(layer "F.SilkS")
			(hide yes)
			(effects
				(font
					(size 1.27 1.27)
				)
			)
		)
		(property "Value" "240R2F-1-GP"
			(at 0.064008 -3.993896 0)
			(unlocked yes)
			(layer "F.Fab")
			(hide yes)
			(effects
				(font
					(size 1.016 1.016)
					(thickness 0.1524)
				)
			)
		)
		(property "Device Type" "R402H16"
			(at 0.064008 -5.517896 0)
			(unlocked yes)
			(layer "F.Fab")
			(hide yes)
			(effects
				(font
					(size 1.016 1.016)
					(thickness 0.1524)
				)
			)
		)
		(duplicate_pad_numbers_are_jumpers no)
		(fp_line
			(start -0.508 -0.9398)
			(end -0.508 0.9398)
			(stroke
				(width 0.1524)
				(type default)
			)
			(layer "F.SilkS")
		)
		(fp_line
			(start 0.508 -0.9398)
			(end -0.508 -0.9398)
			(stroke
				(width 0.1524)
				(type default)
			)
			(layer "F.SilkS")
		)
		(fp_rect
			(start -0.508 0.9398)
			(end 0.508 -0.9398)
			(stroke
				(width 0)
				(type default)
			)
			(fill no)
			(layer "F.CrtYd")
		)
		(fp_rect
			(start -0.508 0.9398)
			(end 0.508 -0.9398)
			(stroke
				(width 0)
				(type default)
			)
			(fill no)
			(layer "F.Fab")
		)
		(pad "1" smd custom
			(at 0 -0.4445)
			(size 0.1397 0.1397)
			(layers "F.Cu" "F.Mask" "F.Paste")
			(net "GND")
			(options
				(clearance outline)
				(anchor circle)
			)
			(primitives
				(gr_poly
					(pts
						(arc
							(start -0.1778 -0.2794)
							(mid -0.249642 -0.249642)
							(end -0.2794 -0.1778)
						)
						(arc
							(start -0.2794 0.1778)
							(mid -0.249642 0.249642)
							(end -0.1778 0.2794)
						)
						(arc
							(start 0.1778 0.2794)
							(mid 0.249642 0.249642)
							(end 0.2794 0.1778)
						)
						(arc
							(start 0.2794 -0.1778)
							(mid 0.249642 -0.249642)
							(end 0.1778 -0.2794)
						)
					)
					(width 0)
					(fill yes)
				)
			)
		)
		(pad "2" smd custom
			(at 0 0.4445)
			(size 0.1397 0.1397)
			(layers "F.Cu" "F.Mask" "F.Paste")
			(net "PD_ZQ")
			(options
				(clearance outline)
				(anchor circle)
			)
			(primitives
				(gr_poly
					(pts
						(arc
							(start -0.1778 -0.2794)
							(mid -0.249642 -0.249642)
							(end -0.2794 -0.1778)
						)
						(arc
							(start -0.2794 0.1778)
							(mid -0.249642 0.249642)
							(end -0.1778 0.2794)
						)
						(arc
							(start 0.1778 0.2794)
							(mid 0.249642 0.249642)
							(end 0.2794 0.1778)
						)
						(arc
							(start 0.2794 -0.1778)
							(mid 0.249642 -0.249642)
							(end 0.1778 -0.2794)
						)
					)
					(width 0)
					(fill yes)
				)
			)
		)
	)
	(footprint ""
		(layer "F.Cu")
		(at 88.844628 -65.475612 90)
		(property "Reference" "R9"
			(at 0 0 90)
			(layer "F.SilkS")
			(hide yes)
			(effects
				(font
					(size 1.27 1.27)
				)
			)
		)
		(property "Value" "0R2J-2-GP"
			(at 0.064008 -3.993896 90)
			(unlocked yes)
			(layer "F.Fab")
			(hide yes)
			(effects
				(font
					(size 1.016 1.016)
					(thickness 0.1524)
				)
			)
		)
		(property "Device Type" "R402H16"
			(at 0.064008 -5.517896 90)
			(unlocked yes)
			(layer "F.Fab")
			(hide yes)
			(effects
				(font
					(size 1.016 1.016)
					(thickness 0.1524)
				)
			)
		)
		(duplicate_pad_numbers_are_jumpers no)
		(fp_line
			(start 0.508 -0.9398)
			(end -0.508 -0.9398)
			(stroke
				(width 0.1524)
				(type default)
			)
			(layer "F.SilkS")
		)
		(fp_line
			(start -0.508 -0.9398)
			(end -0.508 0.9398)
			(stroke
				(width 0.1524)
				(type default)
			)
			(layer "F.SilkS")
		)
		(fp_rect
			(start -0.508 0.9398)
			(end 0.508 -0.9398)
			(stroke
				(width 0)
				(type default)
			)
			(fill no)
			(layer "F.CrtYd")
		)
		(fp_rect
			(start -0.508 0.9398)
			(end 0.508 -0.9398)
			(stroke
				(width 0)
				(type default)
			)
			(fill no)
			(layer "F.Fab")
		)
		(pad "1" smd custom
			(at 0 -0.4445 90)
			(size 0.1397 0.1397)
			(layers "F.Cu" "F.Mask" "F.Paste")
			(net "NCSI_RX_ER_R")
			(options
				(clearance outline)
				(anchor circle)
			)
			(primitives
				(gr_poly
					(pts
						(arc
							(start -0.1778 -0.2794)
							(mid -0.249642 -0.249642)
							(end -0.2794 -0.1778)
						)
						(arc
							(start -0.2794 0.1778)
							(mid -0.249642 0.249642)
							(end -0.1778 0.2794)
						)
						(arc
							(start 0.1778 0.2794)
							(mid 0.249642 0.249642)
							(end 0.2794 0.1778)
						)
						(arc
							(start 0.2794 -0.1778)
							(mid 0.249642 -0.249642)
							(end 0.1778 -0.2794)
						)
					)
					(width 0)
					(fill yes)
				)
			)
		)
		(pad "2" smd custom
			(at 0 0.4445 90)
			(size 0.1397 0.1397)
			(layers "F.Cu" "F.Mask" "F.Paste")
			(net "NCSI_RX_ER")
			(options
				(clearance outline)
				(anchor circle)
			)
			(primitives
				(gr_poly
					(pts
						(arc
							(start -0.1778 -0.2794)
							(mid -0.249642 -0.249642)
							(end -0.2794 -0.1778)
						)
						(arc
							(start -0.2794 0.1778)
							(mid -0.249642 0.249642)
							(end -0.1778 0.2794)
						)
						(arc
							(start 0.1778 0.2794)
							(mid 0.249642 0.249642)
							(end 0.2794 0.1778)
						)
						(arc
							(start 0.2794 -0.1778)
							(mid 0.249642 -0.249642)
							(end 0.1778 -0.2794)
						)
					)
					(width 0)
					(fill yes)
				)
			)
		)
	)
	(footprint ""
		(layer "F.Cu")
		(at 69.596762 -178.901598 90)
		(property "Reference" "C196"
			(at 0 0 90)
			(layer "F.SilkS")
			(hide yes)
			(effects
				(font
					(size 1.27 1.27)
				)
			)
		)
		(property "Value" "SC470P50V2KX-3GP"
			(at 1.1811 -2.7051 90)
			(unlocked yes)
			(layer "F.Fab")
			(hide yes)
			(effects
				(font
					(size 1.016 1.016)
					(thickness 0.1524)
				)
			)
		)
		(property "Device Type" "C402H22"
			(at 1.1811 -4.2291 90)
			(unlocked yes)
			(layer "F.Fab")
			(hide yes)
			(effects
				(font
					(size 1.016 1.016)
					(thickness 0.1524)
				)
			)
		)
		(duplicate_pad_numbers_are_jumpers no)
		(fp_rect
			(start -0.4318 0.9525)
			(end 0.4318 -0.9525)
			(stroke
				(width 0)
				(type default)
			)
			(fill no)
			(layer "F.CrtYd")
		)
		(fp_rect
			(start -0.4318 0.9525)
			(end 0.4318 -0.9525)
			(stroke
				(width 0)
				(type default)
			)
			(fill no)
			(layer "F.Fab")
		)
		(pad "1" smd custom
			(at 0 -0.4445 90)
			(size 0.1524 0.1524)
			(layers "F.Cu" "F.Mask" "F.Paste")
			(net "GND")
			(options
				(clearance outline)
				(anchor circle)
			)
			(primitives
				(gr_poly
					(pts
						(arc
							(start 0.3048 -0.2032)
							(mid 0.275042 -0.275042)
							(end 0.2032 -0.3048)
						)
						(arc
							(start -0.2032 -0.3048)
							(mid -0.275042 -0.275042)
							(end -0.3048 -0.2032)
						)
						(arc
							(start -0.3048 0.2032)
							(mid -0.275042 0.275042)
							(end -0.2032 0.3048)
						)
						(arc
							(start 0.2032 0.3048)
							(mid 0.275042 0.275042)
							(end 0.3048 0.2032)
						)
					)
					(width 0)
					(fill yes)
				)
			)
		)
		(pad "2" smd custom
			(at 0 0.4445 90)
			(size 0.1524 0.1524)
			(layers "F.Cu" "F.Mask" "F.Paste")
			(net "TPS74801_P2V5_STBY_SS")
			(options
				(clearance outline)
				(anchor circle)
			)
			(primitives
				(gr_poly
					(pts
						(arc
							(start 0.3048 -0.2032)
							(mid 0.275042 -0.275042)
							(end 0.2032 -0.3048)
						)
						(arc
							(start -0.2032 -0.3048)
							(mid -0.275042 -0.275042)
							(end -0.3048 -0.2032)
						)
						(arc
							(start -0.3048 0.2032)
							(mid -0.275042 0.275042)
							(end -0.2032 0.3048)
						)
						(arc
							(start 0.2032 0.3048)
							(mid 0.275042 0.275042)
							(end 0.3048 0.2032)
						)
					)
					(width 0)
					(fill yes)
				)
			)
		)
	)
	(footprint ""
		(layer "F.Cu")
		(at 54.280054 -172.699934)
		(property "Reference" "TPM1"
			(at 0 0 0)
			(layer "F.SilkS")
			(hide yes)
			(effects
				(font
					(size 1.27 1.27)
				)
			)
		)
		(property "Value" "FCI-CONN11-2-GP"
			(at -7.4803 1.3589 0)
			(unlocked yes)
			(layer "F.Fab")
			(hide yes)
			(effects
				(font
					(size 1.016 1.016)
					(thickness 0.1524)
				)
			)
		)
		(property "Device Type" "91932-31111LF"
			(at -7.4803 -0.1651 0)
			(unlocked yes)
			(layer "F.Fab")
			(hide yes)
			(effects
				(font
					(size 1.016 1.016)
					(thickness 0.1524)
				)
			)
		)
		(duplicate_pad_numbers_are_jumpers no)
		(fp_line
			(start -5.4102 -3.556)
			(end -5.4102 3.556)
			(stroke
				(width 0.1524)
				(type default)
			)
			(layer "F.SilkS")
		)
		(fp_line
			(start -5.4102 3.556)
			(end 5.4102 3.556)
			(stroke
				(width 0.1524)
				(type default)
			)
			(layer "F.SilkS")
		)
		(fp_line
			(start -2.8321 3.6449)
			(end -2.2479 3.6449)
			(stroke
				(width 0.3302)
				(type default)
			)
			(layer "F.SilkS")
		)
		(fp_line
			(start 5.4102 -3.556)
			(end -5.4102 -3.556)
			(stroke
				(width 0.1524)
				(type default)
			)
			(layer "F.SilkS")
		)
		(fp_line
			(start 5.4102 3.556)
			(end 5.4102 -3.556)
			(stroke
				(width 0.1524)
				(type default)
			)
			(layer "F.SilkS")
		)
		(fp_poly
			(pts
				(xy -2.591054 4.361434) (xy -3.226054 4.996434) (xy -1.956054 4.996434)
			)
			(stroke
				(width 0)
				(type default)
			)
			(fill yes)
			(layer "F.SilkS")
		)
		(fp_poly
			(pts
				(xy -2.8067 1.08839)
				(arc
					(start -2.8067 -0.422402)
					(mid -2.451868 -0.675672)
					(end -2.3114 -1.08839)
				)
				(arc
					(start 2.3114 -1.08839)
					(mid 2.451818 -0.675634)
					(end 2.8067 -0.422402)
				)
				(xy 2.8067 1.08839)
			)
			(stroke
				(width 0)
				(type default)
			)
			(fill yes)
			(layer "F.SilkS")
		)
		(fp_rect
			(start -5.1562 2.794)
			(end 5.1562 -2.794)
			(stroke
				(width 0)
				(type default)
			)
			(fill no)
			(layer "F.CrtYd")
		)
		(fp_poly
			(pts
				(xy 5.6642 -2.794) (xy -5.1562 -2.794) (xy -5.1562 2.794) (xy 5.1562 2.794) (xy 5.1562 -2.7813)
				(xy 5.6642 -2.7813) (xy 5.6642 3.81) (xy -5.6642 3.81) (xy -5.6642 -3.81) (xy 5.6642 -3.81)
			)
			(stroke
				(width 0)
				(type default)
			)
			(fill no)
			(layer "F.CrtYd")
		)
		(fp_rect
			(start -5.6642 3.81)
			(end 5.6642 -3.81)
			(stroke
				(width 0)
				(type default)
			)
			(fill no)
			(layer "F.Fab")
		)
		(pad "" np_thru_hole circle
			(at -3.0226 -1.100074)
			(size 0.254 0.254)
			(drill 0.8128)
			(layers "*.Cu" "*.Mask")
			(clearance 0.635)
			(thermal_gap 0.635)
		)
		(pad "" np_thru_hole circle
			(at 3.0226 -1.100074)
			(size 0.254 0.254)
			(drill 0.8128)
			(layers "*.Cu" "*.Mask")
			(clearance 0.635)
			(thermal_gap 0.635)
		)
		(pad "1" smd rect
			(at -2.500122 2.29489)
			(size 0.6096 2.0066)
			(layers "F.Cu" "F.Mask" "F.Paste")
			(net "Net_579")
		)
		(pad "2" smd rect
			(at -1.500124 2.29489)
			(size 0.6096 2.0066)
			(layers "F.Cu" "F.Mask" "F.Paste")
			(net "Net_578")
		)
		(pad "3" smd rect
			(at -0.500126 2.29489)
			(size 0.6096 2.0066)
			(layers "F.Cu" "F.Mask" "F.Paste")
			(net "Net_577")
		)
		(pad "4" smd rect
			(at 0.500126 2.29489)
			(size 0.6096 2.0066)
			(layers "F.Cu" "F.Mask" "F.Paste")
			(net "Net_576")
		)
		(pad "5" smd rect
			(at 1.500124 2.29489)
			(size 0.6096 2.0066)
			(layers "F.Cu" "F.Mask" "F.Paste")
			(net "Net_575")
		)
		(pad "6" smd rect
			(at 2.500122 2.29489)
			(size 0.6096 2.0066)
			(layers "F.Cu" "F.Mask" "F.Paste")
			(net "I2C_TPM_SDA")
		)
		(pad "7" smd rect
			(at -1.999996 -2.29489)
			(size 0.6096 2.0066)
			(layers "F.Cu" "F.Mask" "F.Paste")
			(net "P3V3_STBY")
		)
		(pad "8" smd rect
			(at -0.999998 -2.29489)
			(size 0.6096 2.0066)
			(layers "F.Cu" "F.Mask" "F.Paste")
			(net "FM_TPM_PRSNT_RST_N")
		)
		(pad "9" smd rect
			(at 0 -2.29489)
			(size 0.6096 2.0066)
			(layers "F.Cu" "F.Mask" "F.Paste")
			(net "Net_580")
		)
		(pad "10" smd rect
			(at 0.999998 -2.29489)
			(size 0.6096 2.0066)
			(layers "F.Cu" "F.Mask" "F.Paste")
			(net "I2C_TPM_SCL")
		)
		(pad "11" smd rect
			(at 1.999996 -2.29489)
			(size 0.6096 2.0066)
			(layers "F.Cu" "F.Mask" "F.Paste")
			(net "GND")
		)
		(pad "G1" smd custom
			(at -4.219956 0)
			(size 0.34925 0.34925)
			(layers "F.Cu" "F.Mask" "F.Paste")
			(net "GND")
			(options
				(clearance outline)
				(anchor circle)
			)
			(primitives
				(gr_poly
					(pts
						(xy -0.6985 2.921) (xy -0.6985 -2.921) (xy 0.6985 -2.921)
						(arc
							(start 0.6985 -1.610106)
							(mid 0.482924 -1.100074)
							(end 0.6985 -0.590042)
						)
						(xy 0.6985 2.921)
					)
					(width 0)
					(fill yes)
				)
			)
		)
		(pad "G2" smd custom
			(at 4.219956 0)
			(size 0.34925 0.34925)
			(layers "F.Cu" "F.Mask" "F.Paste")
			(net "GND")
			(options
				(clearance outline)
				(anchor circle)
			)
			(primitives
				(gr_poly
					(pts
						(xy -0.6985 2.921)
						(arc
							(start -0.6985 -0.590042)
							(mid -0.482924 -1.100074)
							(end -0.6985 -1.610106)
						)
						(xy -0.6985 -2.921) (xy 0.6985 -2.921) (xy 0.6985 2.921)
					)
					(width 0)
					(fill yes)
				)
			)
		)
		(zone
			(layer "F.Cu")
			(hatch none 0.5)
			(connect_pads
				(clearance 0)
			)
			(min_thickness 0.25)
			(keepout
				(tracks not_allowed)
				(vias allowed)
				(pads allowed)
				(copperpour not_allowed)
				(footprints allowed)
			)
			(placement
				(enabled no)
				(sheetname "")
			)
			(fill
				(thermal_gap 0.5)
				(thermal_bridge_width 0.5)
				(island_removal_mode 0)
			)
			(polygon
				(pts
					(xy 51.473354 -171.408344) (xy 57.086754 -171.408344) (xy 57.086754 -173.991524) (xy 51.473354 -173.991524)
				)
			)
		)
		(zone
			(layer "F.Cu")
			(hatch none 0.5)
			(connect_pads
				(clearance 0)
			)
			(min_thickness 0.25)
			(keepout
				(tracks allowed)
				(vias not_allowed)
				(pads allowed)
				(copperpour not_allowed)
				(footprints allowed)
			)
			(placement
				(enabled no)
				(sheetname "")
			)
			(fill
				(thermal_gap 0.5)
				(thermal_bridge_width 0.5)
				(island_removal_mode 0)
			)
			(polygon
				(pts
					(xy 51.473354 -171.408344) (xy 57.086754 -171.408344) (xy 57.086754 -173.991524) (xy 51.473354 -173.991524)
				)
			)
		)
		(zone
			(layer "F.Cu")
			(hatch none 0.5)
			(connect_pads
				(clearance 0)
			)
			(min_thickness 0.25)
			(keepout
				(tracks allowed)
				(vias not_allowed)
				(pads allowed)
				(copperpour not_allowed)
				(footprints allowed)
			)
			(placement
				(enabled no)
				(sheetname "")
			)
			(fill
				(thermal_gap 0.5)
				(thermal_bridge_width 0.5)
				(island_removal_mode 0)
			)
			(polygon
				(pts
					(xy 51.473354 -171.408344) (xy 57.086754 -171.408344) (xy 57.086754 -171.916344) (xy 51.473354 -171.916344)
				)
			)
		)
		(zone
			(layer "F.Cu")
			(hatch none 0.5)
			(connect_pads
				(clearance 0)
			)
			(min_thickness 0.25)
			(keepout
				(tracks allowed)
				(vias not_allowed)
				(pads allowed)
				(copperpour not_allowed)
				(footprints allowed)
			)
			(placement
				(enabled no)
				(sheetname "")
			)
			(fill
				(thermal_gap 0.5)
				(thermal_bridge_width 0.5)
				(island_removal_mode 0)
			)
			(polygon
				(pts
					(xy 51.968654 -173.483524) (xy 56.591454 -173.483524) (xy 56.591454 -173.991524) (xy 51.968654 -173.991524)
				)
			)
		)
		(zone
			(layers "F.Cu" "B.Cu" "In1.Cu" "In2.Cu" "In3.Cu" "In4.Cu" "In5.Cu" "In6.Cu")
			(hatch none 0.5)
			(connect_pads
				(clearance 0)
			)
			(min_thickness 0.25)
			(keepout
				(tracks not_allowed)
				(vias allowed)
				(pads allowed)
				(copperpour not_allowed)
				(footprints allowed)
			)
			(placement
				(enabled no)
				(sheetname "")
			)
			(fill
				(thermal_gap 0.5)
				(thermal_bridge_width 0.5)
				(island_removal_mode 0)
			)
			(polygon
				(pts
					(arc
						(start 51.968654 -173.800008)
						(mid 50.546254 -173.800008)
						(end 51.968654 -173.800008)
					)
				)
			)
		)
		(zone
			(layers "F.Cu" "B.Cu" "In1.Cu" "In2.Cu" "In3.Cu" "In4.Cu" "In5.Cu" "In6.Cu")
			(hatch none 0.5)
			(connect_pads
				(clearance 0)
			)
			(min_thickness 0.25)
			(keepout
				(tracks not_allowed)
				(vias allowed)
				(pads allowed)
				(copperpour not_allowed)
				(footprints allowed)
			)
			(placement
				(enabled no)
				(sheetname "")
			)
			(fill
				(thermal_gap 0.5)
				(thermal_bridge_width 0.5)
				(island_removal_mode 0)
			)
			(polygon
				(pts
					(arc
						(start 58.013854 -173.800008)
						(mid 56.591454 -173.800008)
						(end 58.013854 -173.800008)
					)
				)
			)
		)
	)
	(footprint ""
		(layer "F.Cu")
		(at 17.99971 -120.000014)
		(property "Reference" ""
			(at 0 0 0)
			(layer "F.SilkS")
			(hide yes)
			(effects
				(font
					(size 1.27 1.27)
				)
			)
		)
		(property "Value" "*"
			(at -6.38175 0.19685 0)
			(unlocked yes)
			(layer "F.Fab")
			(hide yes)
			(effects
				(font
					(size 1.016 1.016)
					(thickness 0.1524)
				)
			)
		)
		(duplicate_pad_numbers_are_jumpers no)
		(fp_poly
			(pts
				(arc
					(start 5.0673 0)
					(mid -5.0673 0)
					(end 5.0673 0)
				)
			)
			(stroke
				(width 0)
				(type default)
			)
			(fill no)
			(layer "B.CrtYd")
		)
		(fp_poly
			(pts
				(arc
					(start 5.0673 0)
					(mid -5.0673 0)
					(end 5.0673 0)
				)
			)
			(stroke
				(width 0)
				(type default)
			)
			(fill no)
			(layer "F.CrtYd")
		)
		(fp_poly
			(pts
				(arc
					(start 5.0673 0)
					(mid -5.0673 0)
					(end 5.0673 0)
				)
			)
			(stroke
				(width 0)
				(type default)
			)
			(fill no)
			(layer "B.Fab")
		)
		(fp_poly
			(pts
				(arc
					(start 5.0673 0)
					(mid -5.0673 0)
					(end 5.0673 0)
				)
			)
			(stroke
				(width 0)
				(type default)
			)
			(fill no)
			(layer "F.Fab")
		)
		(pad "1" thru_hole circle
			(at 0 0)
			(size 9.525 9.525)
			(drill 3.5052)
			(layers "*.Cu" "*.Mask")
			(remove_unused_layers no)
			(net "Net_38")
			(clearance -2.5019)
			(thermal_gap 0.3048)
			(padstack
				(mode front_inner_back)
				(layer "Inner"
					(shape circle)
					(size 3.9116 3.9116)
					(clearance 0.3048)
				)
				(layer "B.Cu"
					(shape circle)
					(size 9.525 9.525)
					(clearance -2.5019)
				)
			)
		)
	)
	(footprint ""
		(layer "F.Cu")
		(at 44.2976 -130.6576 180)
		(property "Reference" "R525"
			(at 0 0 180)
			(layer "F.SilkS")
			(hide yes)
			(effects
				(font
					(size 1.27 1.27)
				)
			)
		)
		(property "Value" "0R2J-2-GP"
			(at 0.064008 -3.993896 180)
			(unlocked yes)
			(layer "F.Fab")
			(hide yes)
			(effects
				(font
					(size 1.016 1.016)
					(thickness 0.1524)
				)
			)
		)
		(property "Device Type" "R402H16"
			(at 0.064008 -5.517896 180)
			(unlocked yes)
			(layer "F.Fab")
			(hide yes)
			(effects
				(font
					(size 1.016 1.016)
					(thickness 0.1524)
				)
			)
		)
		(duplicate_pad_numbers_are_jumpers no)
		(fp_line
			(start 0.508 -0.9398)
			(end -0.508 -0.9398)
			(stroke
				(width 0.1524)
				(type default)
			)
			(layer "F.SilkS")
		)
		(fp_line
			(start -0.508 -0.9398)
			(end -0.508 0.9398)
			(stroke
				(width 0.1524)
				(type default)
			)
			(layer "F.SilkS")
		)
		(fp_rect
			(start -0.508 0.9398)
			(end 0.508 -0.9398)
			(stroke
				(width 0)
				(type default)
			)
			(fill no)
			(layer "F.CrtYd")
		)
		(fp_rect
			(start -0.508 0.9398)
			(end 0.508 -0.9398)
			(stroke
				(width 0)
				(type default)
			)
			(fill no)
			(layer "F.Fab")
		)
		(pad "1" smd custom
			(at 0 -0.4445 180)
			(size 0.1397 0.1397)
			(layers "F.Cu" "F.Mask" "F.Paste")
			(net "PCIE_COMP_TO_IOM_RST_4")
			(options
				(clearance outline)
				(anchor circle)
			)
			(primitives
				(gr_poly
					(pts
						(arc
							(start -0.1778 -0.2794)
							(mid -0.249642 -0.249642)
							(end -0.2794 -0.1778)
						)
						(arc
							(start -0.2794 0.1778)
							(mid -0.249642 0.249642)
							(end -0.1778 0.2794)
						)
						(arc
							(start 0.1778 0.2794)
							(mid 0.249642 0.249642)
							(end 0.2794 0.1778)
						)
						(arc
							(start 0.2794 -0.1778)
							(mid 0.249642 -0.249642)
							(end 0.1778 -0.2794)
						)
					)
					(width 0)
					(fill yes)
				)
			)
		)
		(pad "2" smd custom
			(at 0 0.4445 180)
			(size 0.1397 0.1397)
			(layers "F.Cu" "F.Mask" "F.Paste")
			(net "PLTRST_R")
			(options
				(clearance outline)
				(anchor circle)
			)
			(primitives
				(gr_poly
					(pts
						(arc
							(start -0.1778 -0.2794)
							(mid -0.249642 -0.249642)
							(end -0.2794 -0.1778)
						)
						(arc
							(start -0.2794 0.1778)
							(mid -0.249642 0.249642)
							(end -0.1778 0.2794)
						)
						(arc
							(start 0.1778 0.2794)
							(mid 0.249642 0.249642)
							(end 0.2794 0.1778)
						)
						(arc
							(start 0.2794 -0.1778)
							(mid 0.249642 -0.249642)
							(end 0.1778 -0.2794)
						)
					)
					(width 0)
					(fill yes)
				)
			)
		)
	)
	(footprint ""
		(layer "F.Cu")
		(at 26.416 -124.206)
		(property "Reference" "R781"
			(at 0 0 0)
			(layer "F.SilkS")
			(hide yes)
			(effects
				(font
					(size 1.27 1.27)
				)
			)
		)
		(property "Value" "0R2J-2-GP"
			(at 0.064008 -3.993896 0)
			(unlocked yes)
			(layer "F.Fab")
			(hide yes)
			(effects
				(font
					(size 1.016 1.016)
					(thickness 0.1524)
				)
			)
		)
		(property "Device Type" "R402H16"
			(at 0.064008 -5.517896 0)
			(unlocked yes)
			(layer "F.Fab")
			(hide yes)
			(effects
				(font
					(size 1.016 1.016)
					(thickness 0.1524)
				)
			)
		)
		(duplicate_pad_numbers_are_jumpers no)
		(fp_line
			(start -0.508 -0.9398)
			(end -0.508 0.9398)
			(stroke
				(width 0.1524)
				(type default)
			)
			(layer "F.SilkS")
		)
		(fp_line
			(start 0.508 -0.9398)
			(end -0.508 -0.9398)
			(stroke
				(width 0.1524)
				(type default)
			)
			(layer "F.SilkS")
		)
		(fp_rect
			(start -0.508 0.9398)
			(end 0.508 -0.9398)
			(stroke
				(width 0)
				(type default)
			)
			(fill no)
			(layer "F.CrtYd")
		)
		(fp_rect
			(start -0.508 0.9398)
			(end 0.508 -0.9398)
			(stroke
				(width 0)
				(type default)
			)
			(fill no)
			(layer "F.Fab")
		)
		(pad "1" smd custom
			(at 0 -0.4445)
			(size 0.1397 0.1397)
			(layers "F.Cu" "F.Mask" "F.Paste")
			(net "FLA0_WP_N")
			(options
				(clearance outline)
				(anchor circle)
			)
			(primitives
				(gr_poly
					(pts
						(arc
							(start -0.1778 -0.2794)
							(mid -0.249642 -0.249642)
							(end -0.2794 -0.1778)
						)
						(arc
							(start -0.2794 0.1778)
							(mid -0.249642 0.249642)
							(end -0.1778 0.2794)
						)
						(arc
							(start 0.1778 0.2794)
							(mid 0.249642 0.249642)
							(end 0.2794 0.1778)
						)
						(arc
							(start 0.2794 -0.1778)
							(mid 0.249642 -0.249642)
							(end 0.1778 -0.2794)
						)
					)
					(width 0)
					(fill yes)
				)
			)
		)
		(pad "2" smd custom
			(at 0 0.4445)
			(size 0.1397 0.1397)
			(layers "F.Cu" "F.Mask" "F.Paste")
			(net "WP_ENABLE")
			(options
				(clearance outline)
				(anchor circle)
			)
			(primitives
				(gr_poly
					(pts
						(arc
							(start -0.1778 -0.2794)
							(mid -0.249642 -0.249642)
							(end -0.2794 -0.1778)
						)
						(arc
							(start -0.2794 0.1778)
							(mid -0.249642 0.249642)
							(end -0.1778 0.2794)
						)
						(arc
							(start 0.1778 0.2794)
							(mid 0.249642 0.249642)
							(end 0.2794 0.1778)
						)
						(arc
							(start 0.2794 -0.1778)
							(mid 0.249642 -0.249642)
							(end 0.1778 -0.2794)
						)
					)
					(width 0)
					(fill yes)
				)
			)
		)
	)
	(footprint ""
		(layer "F.Cu")
		(at 88.844628 -45.384212 90)
		(property "Reference" "R10"
			(at 0 0 90)
			(layer "F.SilkS")
			(hide yes)
			(effects
				(font
					(size 1.27 1.27)
				)
			)
		)
		(property "Value" "0R2J-2-GP"
			(at 0.064008 -3.993896 90)
			(unlocked yes)
			(layer "F.Fab")
			(hide yes)
			(effects
				(font
					(size 1.016 1.016)
					(thickness 0.1524)
				)
			)
		)
		(property "Device Type" "R402H16"
			(at 0.064008 -5.517896 90)
			(unlocked yes)
			(layer "F.Fab")
			(hide yes)
			(effects
				(font
					(size 1.016 1.016)
					(thickness 0.1524)
				)
			)
		)
		(duplicate_pad_numbers_are_jumpers no)
		(fp_line
			(start 0.508 -0.9398)
			(end -0.508 -0.9398)
			(stroke
				(width 0.1524)
				(type default)
			)
			(layer "F.SilkS")
		)
		(fp_line
			(start -0.508 -0.9398)
			(end -0.508 0.9398)
			(stroke
				(width 0.1524)
				(type default)
			)
			(layer "F.SilkS")
		)
		(fp_rect
			(start -0.508 0.9398)
			(end 0.508 -0.9398)
			(stroke
				(width 0)
				(type default)
			)
			(fill no)
			(layer "F.CrtYd")
		)
		(fp_rect
			(start -0.508 0.9398)
			(end 0.508 -0.9398)
			(stroke
				(width 0)
				(type default)
			)
			(fill no)
			(layer "F.Fab")
		)
		(pad "1" smd custom
			(at 0 -0.4445 90)
			(size 0.1397 0.1397)
			(layers "F.Cu" "F.Mask" "F.Paste")
			(net "MEZZA_PRSNT1_N")
			(options
				(clearance outline)
				(anchor circle)
			)
			(primitives
				(gr_poly
					(pts
						(arc
							(start -0.1778 -0.2794)
							(mid -0.249642 -0.249642)
							(end -0.2794 -0.1778)
						)
						(arc
							(start -0.2794 0.1778)
							(mid -0.249642 0.249642)
							(end -0.1778 0.2794)
						)
						(arc
							(start 0.1778 0.2794)
							(mid 0.249642 0.249642)
							(end 0.2794 0.1778)
						)
						(arc
							(start 0.2794 -0.1778)
							(mid 0.249642 -0.249642)
							(end 0.1778 -0.2794)
						)
					)
					(width 0)
					(fill yes)
				)
			)
		)
		(pad "2" smd custom
			(at 0 0.4445 90)
			(size 0.1397 0.1397)
			(layers "F.Cu" "F.Mask" "F.Paste")
			(net "GND")
			(options
				(clearance outline)
				(anchor circle)
			)
			(primitives
				(gr_poly
					(pts
						(arc
							(start -0.1778 -0.2794)
							(mid -0.249642 -0.249642)
							(end -0.2794 -0.1778)
						)
						(arc
							(start -0.2794 0.1778)
							(mid -0.249642 0.249642)
							(end -0.1778 0.2794)
						)
						(arc
							(start 0.1778 0.2794)
							(mid 0.249642 0.249642)
							(end 0.2794 0.1778)
						)
						(arc
							(start 0.2794 -0.1778)
							(mid 0.249642 -0.249642)
							(end 0.1778 -0.2794)
						)
					)
					(width 0)
					(fill yes)
				)
			)
		)
	)
	(footprint ""
		(layer "F.Cu")
		(at 95.06458 -13.4112 90)
		(property "Reference" "D15"
			(at 0 0 90)
			(layer "F.SilkS")
			(hide yes)
			(effects
				(font
					(size 1.27 1.27)
				)
			)
		)
		(property "Value" "PESD5V0S1BL-1-GP"
			(at 1.8923 -1.5621 90)
			(unlocked yes)
			(layer "F.Fab")
			(hide yes)
			(effects
				(font
					(size 1.016 1.016)
					(thickness 0.1524)
				)
			)
		)
		(property "Device Type" "SOD882-10D6-1H20"
			(at 1.8923 -3.0861 90)
			(unlocked yes)
			(layer "F.Fab")
			(hide yes)
			(effects
				(font
					(size 1.016 1.016)
					(thickness 0.1524)
				)
			)
		)
		(duplicate_pad_numbers_are_jumpers no)
		(fp_line
			(start -0.3048 -0.9271)
			(end 0.3048 -0.9271)
			(stroke
				(width 0.254)
				(type default)
			)
			(layer "F.SilkS")
		)
		(fp_rect
			(start -0.2921 0.4953)
			(end 0.2921 -0.4953)
			(stroke
				(width 0)
				(type default)
			)
			(fill no)
			(layer "F.CrtYd")
		)
		(fp_poly
			(pts
				(xy -0.4318 0.8001) (xy -0.4318 -0.266192) (xy -0.2921 -0.266192) (xy -0.2921 0.4953) (xy 0.2921 0.4953)
				(xy 0.2921 -0.4953) (xy -0.2921 -0.4953) (xy -0.2921 -0.2667) (xy -0.4318 -0.2667) (xy -0.4318 -0.8001)
				(xy 0.4318 -0.8001) (xy 0.4318 0.8001)
			)
			(stroke
				(width 0)
				(type default)
			)
			(fill no)
			(layer "F.CrtYd")
		)
		(fp_rect
			(start -0.4318 0.8001)
			(end 0.4318 -0.8001)
			(stroke
				(width 0)
				(type default)
			)
			(fill no)
			(layer "F.Fab")
		)
		(pad "1" smd custom
			(at 0 -0.4445 90)
			(size 0.1143 0.1143)
			(layers "F.Cu" "F.Mask" "F.Paste")
			(net "I2C_DEBUG_SDA")
			(options
				(clearance outline)
				(anchor circle)
			)
			(primitives
				(gr_poly
					(pts
						(arc
							(start -0.2032 0.2286)
							(mid -0.275042 0.198842)
							(end -0.3048 0.127)
						)
						(arc
							(start -0.3048 -0.127)
							(mid -0.275042 -0.198842)
							(end -0.2032 -0.2286)
						)
						(arc
							(start 0.2032 -0.2286)
							(mid 0.275042 -0.198842)
							(end 0.3048 -0.127)
						)
						(arc
							(start 0.3048 0.127)
							(mid 0.275042 0.198842)
							(end 0.2032 0.2286)
						)
					)
					(width 0)
					(fill yes)
				)
			)
		)
		(pad "2" smd custom
			(at 0 0.4445 90)
			(size 0.1143 0.1143)
			(layers "F.Cu" "F.Mask" "F.Paste")
			(net "GND")
			(options
				(clearance outline)
				(anchor circle)
			)
			(primitives
				(gr_poly
					(pts
						(arc
							(start 0.2032 -0.2286)
							(mid 0.275042 -0.198842)
							(end 0.3048 -0.127)
						)
						(arc
							(start 0.3048 0.127)
							(mid 0.275042 0.198842)
							(end 0.2032 0.2286)
						)
						(arc
							(start -0.2032 0.2286)
							(mid -0.275042 0.198842)
							(end -0.3048 0.127)
						)
						(arc
							(start -0.3048 -0.127)
							(mid -0.275042 -0.198842)
							(end -0.2032 -0.2286)
						)
					)
					(width 0)
					(fill yes)
				)
			)
		)
	)
	(footprint ""
		(layer "F.Cu")
		(at 225.390964 -96.854264 90)
		(property "Reference" "R838"
			(at 0 0 90)
			(layer "F.SilkS")
			(hide yes)
			(effects
				(font
					(size 1.27 1.27)
				)
			)
		)
		(property "Value" "3D01R5F-GP"
			(at 0 -8.9535 90)
			(unlocked yes)
			(layer "F.Fab")
			(hide yes)
			(effects
				(font
					(size 1.27 1.016)
					(thickness 0.1524)
				)
			)
		)
		(property "Device Type" "R805H24"
			(at 0 -10.6299 90)
			(unlocked yes)
			(layer "F.Fab")
			(hide yes)
			(effects
				(font
					(size 1.27 1.016)
					(thickness 0.1524)
				)
			)
		)
		(duplicate_pad_numbers_are_jumpers no)
		(fp_line
			(start 0.889 -1.7018)
			(end -0.889 -1.7018)
			(stroke
				(width 0.1524)
				(type default)
			)
			(layer "F.SilkS")
		)
		(fp_line
			(start 0.889 -1.7018)
			(end 0.889 -0.381)
			(stroke
				(width 0.1524)
				(type default)
			)
			(layer "F.SilkS")
		)
		(fp_line
			(start -0.889 -1.7018)
			(end -0.889 0.2794)
			(stroke
				(width 0.1524)
				(type default)
			)
			(layer "F.SilkS")
		)
		(fp_line
			(start -0.889 0.0762)
			(end -0.889 1.7018)
			(stroke
				(width 0.1524)
				(type default)
			)
			(layer "F.SilkS")
		)
		(fp_line
			(start 0.889 1.7018)
			(end 0.889 -0.508)
			(stroke
				(width 0.1524)
				(type default)
			)
			(layer "F.SilkS")
		)
		(fp_line
			(start -0.889 1.7018)
			(end 0.889 1.7018)
			(stroke
				(width 0.1524)
				(type default)
			)
			(layer "F.SilkS")
		)
		(fp_poly
			(pts
				(xy 0.9652 -1.778) (xy 0.9652 1.778) (xy -0.9652 1.778) (xy -0.9652 -1.778)
			)
			(stroke
				(width 0)
				(type default)
			)
			(fill no)
			(layer "F.CrtYd")
		)
		(fp_rect
			(start -0.9652 1.778)
			(end 0.9652 -1.778)
			(stroke
				(width 0)
				(type default)
			)
			(fill no)
			(layer "F.Fab")
		)
		(pad "1" smd rect
			(at 0 -0.9652 90)
			(size 1.397 1.143)
			(layers "F.Cu" "F.Mask" "F.Paste")
			(net "GND")
		)
		(pad "2" smd rect
			(at 0 0.9652 90)
			(size 1.397 1.143)
			(layers "F.Cu" "F.Mask" "F.Paste")
			(net "P3V3_M2_SNB")
		)
	)
	(footprint ""
		(layer "F.Cu")
		(at 54.539642 -166.064184)
		(property "Reference" "R779"
			(at 0 0 0)
			(layer "F.SilkS")
			(hide yes)
			(effects
				(font
					(size 1.27 1.27)
				)
			)
		)
		(property "Value" "1KR2F-3-GP"
			(at 0.064008 -3.993896 0)
			(unlocked yes)
			(layer "F.Fab")
			(hide yes)
			(effects
				(font
					(size 1.016 1.016)
					(thickness 0.1524)
				)
			)
		)
		(property "Device Type" "R402H16"
			(at 0.064008 -5.517896 0)
			(unlocked yes)
			(layer "F.Fab")
			(hide yes)
			(effects
				(font
					(size 1.016 1.016)
					(thickness 0.1524)
				)
			)
		)
		(duplicate_pad_numbers_are_jumpers no)
		(fp_line
			(start -0.508 -0.9398)
			(end -0.508 0.9398)
			(stroke
				(width 0.1524)
				(type default)
			)
			(layer "F.SilkS")
		)
		(fp_line
			(start 0.508 -0.9398)
			(end -0.508 -0.9398)
			(stroke
				(width 0.1524)
				(type default)
			)
			(layer "F.SilkS")
		)
		(fp_rect
			(start -0.508 0.9398)
			(end 0.508 -0.9398)
			(stroke
				(width 0)
				(type default)
			)
			(fill no)
			(layer "F.CrtYd")
		)
		(fp_rect
			(start -0.508 0.9398)
			(end 0.508 -0.9398)
			(stroke
				(width 0)
				(type default)
			)
			(fill no)
			(layer "F.Fab")
		)
		(pad "1" smd custom
			(at 0 -0.4445)
			(size 0.1397 0.1397)
			(layers "F.Cu" "F.Mask" "F.Paste")
			(net "ADC_P2V5_STBY")
			(options
				(clearance outline)
				(anchor circle)
			)
			(primitives
				(gr_poly
					(pts
						(arc
							(start -0.1778 -0.2794)
							(mid -0.249642 -0.249642)
							(end -0.2794 -0.1778)
						)
						(arc
							(start -0.2794 0.1778)
							(mid -0.249642 0.249642)
							(end -0.1778 0.2794)
						)
						(arc
							(start 0.1778 0.2794)
							(mid 0.249642 0.249642)
							(end 0.2794 0.1778)
						)
						(arc
							(start 0.2794 -0.1778)
							(mid 0.249642 -0.249642)
							(end 0.1778 -0.2794)
						)
					)
					(width 0)
					(fill yes)
				)
			)
		)
		(pad "2" smd custom
			(at 0 0.4445)
			(size 0.1397 0.1397)
			(layers "F.Cu" "F.Mask" "F.Paste")
			(net "GND")
			(options
				(clearance outline)
				(anchor circle)
			)
			(primitives
				(gr_poly
					(pts
						(arc
							(start -0.1778 -0.2794)
							(mid -0.249642 -0.249642)
							(end -0.2794 -0.1778)
						)
						(arc
							(start -0.2794 0.1778)
							(mid -0.249642 0.249642)
							(end -0.1778 0.2794)
						)
						(arc
							(start 0.1778 0.2794)
							(mid 0.249642 0.249642)
							(end 0.2794 0.1778)
						)
						(arc
							(start 0.2794 -0.1778)
							(mid 0.249642 -0.249642)
							(end 0.1778 -0.2794)
						)
					)
					(width 0)
					(fill yes)
				)
			)
		)
	)
	(footprint ""
		(layer "F.Cu")
		(at 65.679828 -163.118546 -90)
		(property "Reference" "R76"
			(at 0 0 270)
			(layer "F.SilkS")
			(hide yes)
			(effects
				(font
					(size 1.27 1.27)
				)
			)
		)
		(property "Value" "47KR2F-GP"
			(at 0.064008 -3.993896 270)
			(unlocked yes)
			(layer "F.Fab")
			(hide yes)
			(effects
				(font
					(size 1.016 1.016)
					(thickness 0.1524)
				)
			)
		)
		(property "Device Type" "R402H16"
			(at 0.064008 -5.517896 270)
			(unlocked yes)
			(layer "F.Fab")
			(hide yes)
			(effects
				(font
					(size 1.016 1.016)
					(thickness 0.1524)
				)
			)
		)
		(duplicate_pad_numbers_are_jumpers no)
		(fp_line
			(start -0.508 -0.9398)
			(end -0.508 0.9398)
			(stroke
				(width 0.1524)
				(type default)
			)
			(layer "F.SilkS")
		)
		(fp_line
			(start 0.508 -0.9398)
			(end -0.508 -0.9398)
			(stroke
				(width 0.1524)
				(type default)
			)
			(layer "F.SilkS")
		)
		(fp_rect
			(start -0.508 0.9398)
			(end 0.508 -0.9398)
			(stroke
				(width 0)
				(type default)
			)
			(fill no)
			(layer "F.CrtYd")
		)
		(fp_rect
			(start -0.508 0.9398)
			(end 0.508 -0.9398)
			(stroke
				(width 0)
				(type default)
			)
			(fill no)
			(layer "F.Fab")
		)
		(pad "1" smd custom
			(at 0 -0.4445 270)
			(size 0.1397 0.1397)
			(layers "F.Cu" "F.Mask" "F.Paste")
			(net "FM_TPM_PRSNT_RST_N")
			(options
				(clearance outline)
				(anchor circle)
			)
			(primitives
				(gr_poly
					(pts
						(arc
							(start -0.1778 -0.2794)
							(mid -0.249642 -0.249642)
							(end -0.2794 -0.1778)
						)
						(arc
							(start -0.2794 0.1778)
							(mid -0.249642 0.249642)
							(end -0.1778 0.2794)
						)
						(arc
							(start 0.1778 0.2794)
							(mid 0.249642 0.249642)
							(end 0.2794 0.1778)
						)
						(arc
							(start 0.2794 -0.1778)
							(mid 0.249642 -0.249642)
							(end 0.1778 -0.2794)
						)
					)
					(width 0)
					(fill yes)
				)
			)
		)
		(pad "2" smd custom
			(at 0 0.4445 270)
			(size 0.1397 0.1397)
			(layers "F.Cu" "F.Mask" "F.Paste")
			(net "FM_TPM_PRSNT_RST_N_R")
			(options
				(clearance outline)
				(anchor circle)
			)
			(primitives
				(gr_poly
					(pts
						(arc
							(start -0.1778 -0.2794)
							(mid -0.249642 -0.249642)
							(end -0.2794 -0.1778)
						)
						(arc
							(start -0.2794 0.1778)
							(mid -0.249642 0.249642)
							(end -0.1778 0.2794)
						)
						(arc
							(start 0.1778 0.2794)
							(mid 0.249642 0.249642)
							(end 0.2794 0.1778)
						)
						(arc
							(start 0.2794 -0.1778)
							(mid 0.249642 -0.249642)
							(end 0.1778 -0.2794)
						)
					)
					(width 0)
					(fill yes)
				)
			)
		)
	)
	(footprint ""
		(layer "F.Cu")
		(at 62.6618 -172.1104)
		(property "Reference" "R74"
			(at 0 0 0)
			(layer "F.SilkS")
			(hide yes)
			(effects
				(font
					(size 1.27 1.27)
				)
			)
		)
		(property "Value" "0R2J-2-GP"
			(at 0.064008 -3.993896 0)
			(unlocked yes)
			(layer "F.Fab")
			(hide yes)
			(effects
				(font
					(size 1.016 1.016)
					(thickness 0.1524)
				)
			)
		)
		(property "Device Type" "R402H16"
			(at 0.064008 -5.517896 0)
			(unlocked yes)
			(layer "F.Fab")
			(hide yes)
			(effects
				(font
					(size 1.016 1.016)
					(thickness 0.1524)
				)
			)
		)
		(duplicate_pad_numbers_are_jumpers no)
		(fp_line
			(start -0.508 -0.9398)
			(end -0.508 0.9398)
			(stroke
				(width 0.1524)
				(type default)
			)
			(layer "F.SilkS")
		)
		(fp_line
			(start 0.508 -0.9398)
			(end -0.508 -0.9398)
			(stroke
				(width 0.1524)
				(type default)
			)
			(layer "F.SilkS")
		)
		(fp_rect
			(start -0.508 0.9398)
			(end 0.508 -0.9398)
			(stroke
				(width 0)
				(type default)
			)
			(fill no)
			(layer "F.CrtYd")
		)
		(fp_rect
			(start -0.508 0.9398)
			(end 0.508 -0.9398)
			(stroke
				(width 0)
				(type default)
			)
			(fill no)
			(layer "F.Fab")
		)
		(pad "1" smd custom
			(at 0 -0.4445)
			(size 0.1397 0.1397)
			(layers "F.Cu" "F.Mask" "F.Paste")
			(net "FM_TPM_PRSNT_RST_N_C")
			(options
				(clearance outline)
				(anchor circle)
			)
			(primitives
				(gr_poly
					(pts
						(arc
							(start -0.1778 -0.2794)
							(mid -0.249642 -0.249642)
							(end -0.2794 -0.1778)
						)
						(arc
							(start -0.2794 0.1778)
							(mid -0.249642 0.249642)
							(end -0.1778 0.2794)
						)
						(arc
							(start 0.1778 0.2794)
							(mid 0.249642 0.249642)
							(end 0.2794 0.1778)
						)
						(arc
							(start 0.2794 -0.1778)
							(mid 0.249642 -0.249642)
							(end 0.1778 -0.2794)
						)
					)
					(width 0)
					(fill yes)
				)
			)
		)
		(pad "2" smd custom
			(at 0 0.4445)
			(size 0.1397 0.1397)
			(layers "F.Cu" "F.Mask" "F.Paste")
			(net "FM_TPM_PRSNT_RST_N")
			(options
				(clearance outline)
				(anchor circle)
			)
			(primitives
				(gr_poly
					(pts
						(arc
							(start -0.1778 -0.2794)
							(mid -0.249642 -0.249642)
							(end -0.2794 -0.1778)
						)
						(arc
							(start -0.2794 0.1778)
							(mid -0.249642 0.249642)
							(end -0.1778 0.2794)
						)
						(arc
							(start 0.1778 0.2794)
							(mid 0.249642 0.249642)
							(end 0.2794 0.1778)
						)
						(arc
							(start 0.2794 -0.1778)
							(mid 0.249642 -0.249642)
							(end 0.1778 -0.2794)
						)
					)
					(width 0)
					(fill yes)
				)
			)
		)
	)
	(footprint ""
		(layer "F.Cu")
		(at 78.122018 -83.754468 90)
		(property "Reference" "VIA5"
			(at 0 0 90)
			(layer "F.SilkS")
			(hide yes)
			(effects
				(font
					(size 1.27 1.27)
				)
			)
		)
		(property "Value" "85OHM-8L-1D6MM-L16L18-GP"
			(at 4.064 0.6096 90)
			(unlocked yes)
			(layer "F.Fab")
			(hide yes)
			(effects
				(font
					(size 1.016 1.016)
					(thickness 0.1524)
				)
			)
		)
		(property "Device Type" "VIA-PCIE-4P-368076"
			(at 4.064 -0.9144 90)
			(unlocked yes)
			(layer "F.Fab")
			(hide yes)
			(effects
				(font
					(size 1.016 1.016)
					(thickness 0.1524)
				)
			)
		)
		(duplicate_pad_numbers_are_jumpers no)
		(fp_rect
			(start -1.8415 0.381)
			(end 1.8415 -0.381)
			(stroke
				(width 0)
				(type default)
			)
			(fill no)
			(layer "F.CrtYd")
		)
		(fp_rect
			(start -1.8415 0.381)
			(end 1.8415 -0.381)
			(stroke
				(width 0)
				(type default)
			)
			(fill no)
			(layer "F.Fab")
		)
		(pad "1" thru_hole circle
			(at -1.4605 0 90)
			(size 0.508 0.508)
			(drill 0.254)
			(layers "*.Cu" "*.Mask")
			(remove_unused_layers no)
			(net "GND")
			(clearance 0.127)
			(thermal_gap 0.127)
		)
		(pad "2" thru_hole circle
			(at -0.4445 0 90)
			(size 0.508 0.508)
			(drill 0.254)
			(layers "*.Cu" "*.Mask")
			(remove_unused_layers no)
			(net "PCIE_COMP_TO_IOM_20_DP")
			(clearance 0.127)
			(thermal_gap 0.127)
		)
		(pad "3" thru_hole circle
			(at 0.4445 0 90)
			(size 0.508 0.508)
			(drill 0.254)
			(layers "*.Cu" "*.Mask")
			(remove_unused_layers no)
			(net "PCIE_COMP_TO_IOM_20_DN")
			(clearance 0.127)
			(thermal_gap 0.127)
		)
		(pad "4" thru_hole circle
			(at 1.4605 0 90)
			(size 0.508 0.508)
			(drill 0.254)
			(layers "*.Cu" "*.Mask")
			(remove_unused_layers no)
			(net "GND")
			(clearance 0.127)
			(thermal_gap 0.127)
		)
	)
	(footprint ""
		(layer "F.Cu")
		(at 45.409104 -161.231072 180)
		(property "Reference" "R180"
			(at 0 0 180)
			(layer "F.SilkS")
			(hide yes)
			(effects
				(font
					(size 1.27 1.27)
				)
			)
		)
		(property "Value" "2K2R2F-GP"
			(at 0.064008 -3.993896 180)
			(unlocked yes)
			(layer "F.Fab")
			(hide yes)
			(effects
				(font
					(size 1.016 1.016)
					(thickness 0.1524)
				)
			)
		)
		(property "Device Type" "R402H16"
			(at 0.064008 -5.517896 180)
			(unlocked yes)
			(layer "F.Fab")
			(hide yes)
			(effects
				(font
					(size 1.016 1.016)
					(thickness 0.1524)
				)
			)
		)
		(duplicate_pad_numbers_are_jumpers no)
		(fp_line
			(start 0.508 -0.9398)
			(end -0.508 -0.9398)
			(stroke
				(width 0.1524)
				(type default)
			)
			(layer "F.SilkS")
		)
		(fp_line
			(start -0.508 -0.9398)
			(end -0.508 0.9398)
			(stroke
				(width 0.1524)
				(type default)
			)
			(layer "F.SilkS")
		)
		(fp_rect
			(start -0.508 0.9398)
			(end 0.508 -0.9398)
			(stroke
				(width 0)
				(type default)
			)
			(fill no)
			(layer "F.CrtYd")
		)
		(fp_rect
			(start -0.508 0.9398)
			(end 0.508 -0.9398)
			(stroke
				(width 0)
				(type default)
			)
			(fill no)
			(layer "F.Fab")
		)
		(pad "1" smd custom
			(at 0 -0.4445 180)
			(size 0.1397 0.1397)
			(layers "F.Cu" "F.Mask" "F.Paste")
			(net "I2C_DPB_SDA_OUT")
			(options
				(clearance outline)
				(anchor circle)
			)
			(primitives
				(gr_poly
					(pts
						(arc
							(start -0.1778 -0.2794)
							(mid -0.249642 -0.249642)
							(end -0.2794 -0.1778)
						)
						(arc
							(start -0.2794 0.1778)
							(mid -0.249642 0.249642)
							(end -0.1778 0.2794)
						)
						(arc
							(start 0.1778 0.2794)
							(mid 0.249642 0.249642)
							(end 0.2794 0.1778)
						)
						(arc
							(start 0.2794 -0.1778)
							(mid 0.249642 -0.249642)
							(end 0.1778 -0.2794)
						)
					)
					(width 0)
					(fill yes)
				)
			)
		)
		(pad "2" smd custom
			(at 0 0.4445 180)
			(size 0.1397 0.1397)
			(layers "F.Cu" "F.Mask" "F.Paste")
			(net "P3V3_STBY")
			(options
				(clearance outline)
				(anchor circle)
			)
			(primitives
				(gr_poly
					(pts
						(arc
							(start -0.1778 -0.2794)
							(mid -0.249642 -0.249642)
							(end -0.2794 -0.1778)
						)
						(arc
							(start -0.2794 0.1778)
							(mid -0.249642 0.249642)
							(end -0.1778 0.2794)
						)
						(arc
							(start 0.1778 0.2794)
							(mid 0.249642 0.249642)
							(end 0.2794 0.1778)
						)
						(arc
							(start 0.2794 -0.1778)
							(mid 0.249642 -0.249642)
							(end 0.1778 -0.2794)
						)
					)
					(width 0)
					(fill yes)
				)
			)
		)
	)
	(footprint ""
		(layer "F.Cu")
		(at 16.013684 -164.5539 90)
		(property "Reference" "R531"
			(at 0 0 90)
			(layer "F.SilkS")
			(hide yes)
			(effects
				(font
					(size 1.27 1.27)
				)
			)
		)
		(property "Value" "4K99R2F-L-GP"
			(at 0.064008 -3.993896 90)
			(unlocked yes)
			(layer "F.Fab")
			(hide yes)
			(effects
				(font
					(size 1.016 1.016)
					(thickness 0.1524)
				)
			)
		)
		(property "Device Type" "R402H16"
			(at 0.064008 -5.517896 90)
			(unlocked yes)
			(layer "F.Fab")
			(hide yes)
			(effects
				(font
					(size 1.016 1.016)
					(thickness 0.1524)
				)
			)
		)
		(duplicate_pad_numbers_are_jumpers no)
		(fp_line
			(start 0.508 -0.9398)
			(end -0.508 -0.9398)
			(stroke
				(width 0.1524)
				(type default)
			)
			(layer "F.SilkS")
		)
		(fp_line
			(start -0.508 -0.9398)
			(end -0.508 0.9398)
			(stroke
				(width 0.1524)
				(type default)
			)
			(layer "F.SilkS")
		)
		(fp_rect
			(start -0.508 0.9398)
			(end 0.508 -0.9398)
			(stroke
				(width 0)
				(type default)
			)
			(fill no)
			(layer "F.CrtYd")
		)
		(fp_rect
			(start -0.508 0.9398)
			(end 0.508 -0.9398)
			(stroke
				(width 0)
				(type default)
			)
			(fill no)
			(layer "F.Fab")
		)
		(pad "1" smd custom
			(at 0 -0.4445 90)
			(size 0.1397 0.1397)
			(layers "F.Cu" "F.Mask" "F.Paste")
			(net "TPS74801_P1V2_STBY_FB")
			(options
				(clearance outline)
				(anchor circle)
			)
			(primitives
				(gr_poly
					(pts
						(arc
							(start -0.1778 -0.2794)
							(mid -0.249642 -0.249642)
							(end -0.2794 -0.1778)
						)
						(arc
							(start -0.2794 0.1778)
							(mid -0.249642 0.249642)
							(end -0.1778 0.2794)
						)
						(arc
							(start 0.1778 0.2794)
							(mid 0.249642 0.249642)
							(end 0.2794 0.1778)
						)
						(arc
							(start 0.2794 -0.1778)
							(mid 0.249642 -0.249642)
							(end 0.1778 -0.2794)
						)
					)
					(width 0)
					(fill yes)
				)
			)
		)
		(pad "2" smd custom
			(at 0 0.4445 90)
			(size 0.1397 0.1397)
			(layers "F.Cu" "F.Mask" "F.Paste")
			(net "GND")
			(options
				(clearance outline)
				(anchor circle)
			)
			(primitives
				(gr_poly
					(pts
						(arc
							(start -0.1778 -0.2794)
							(mid -0.249642 -0.249642)
							(end -0.2794 -0.1778)
						)
						(arc
							(start -0.2794 0.1778)
							(mid -0.249642 0.249642)
							(end -0.1778 0.2794)
						)
						(arc
							(start 0.1778 0.2794)
							(mid 0.249642 0.249642)
							(end 0.2794 0.1778)
						)
						(arc
							(start 0.2794 -0.1778)
							(mid 0.249642 -0.249642)
							(end 0.1778 -0.2794)
						)
					)
					(width 0)
					(fill yes)
				)
			)
		)
	)
	(footprint ""
		(layer "F.Cu")
		(at 95.06458 -12.2428 90)
		(property "Reference" "D14"
			(at 0 0 90)
			(layer "F.SilkS")
			(hide yes)
			(effects
				(font
					(size 1.27 1.27)
				)
			)
		)
		(property "Value" "PESD5V0S1BL-1-GP"
			(at 1.8923 -1.5621 90)
			(unlocked yes)
			(layer "F.Fab")
			(hide yes)
			(effects
				(font
					(size 1.016 1.016)
					(thickness 0.1524)
				)
			)
		)
		(property "Device Type" "SOD882-10D6-1H20"
			(at 1.8923 -3.0861 90)
			(unlocked yes)
			(layer "F.Fab")
			(hide yes)
			(effects
				(font
					(size 1.016 1.016)
					(thickness 0.1524)
				)
			)
		)
		(duplicate_pad_numbers_are_jumpers no)
		(fp_line
			(start -0.3048 -0.9271)
			(end 0.3048 -0.9271)
			(stroke
				(width 0.254)
				(type default)
			)
			(layer "F.SilkS")
		)
		(fp_rect
			(start -0.2921 0.4953)
			(end 0.2921 -0.4953)
			(stroke
				(width 0)
				(type default)
			)
			(fill no)
			(layer "F.CrtYd")
		)
		(fp_poly
			(pts
				(xy -0.4318 0.8001) (xy -0.4318 -0.266192) (xy -0.2921 -0.266192) (xy -0.2921 0.4953) (xy 0.2921 0.4953)
				(xy 0.2921 -0.4953) (xy -0.2921 -0.4953) (xy -0.2921 -0.2667) (xy -0.4318 -0.2667) (xy -0.4318 -0.8001)
				(xy 0.4318 -0.8001) (xy 0.4318 0.8001)
			)
			(stroke
				(width 0)
				(type default)
			)
			(fill no)
			(layer "F.CrtYd")
		)
		(fp_rect
			(start -0.4318 0.8001)
			(end 0.4318 -0.8001)
			(stroke
				(width 0)
				(type default)
			)
			(fill no)
			(layer "F.Fab")
		)
		(pad "1" smd custom
			(at 0 -0.4445 90)
			(size 0.1143 0.1143)
			(layers "F.Cu" "F.Mask" "F.Paste")
			(net "I2C_DEBUG_SCL")
			(options
				(clearance outline)
				(anchor circle)
			)
			(primitives
				(gr_poly
					(pts
						(arc
							(start -0.2032 0.2286)
							(mid -0.275042 0.198842)
							(end -0.3048 0.127)
						)
						(arc
							(start -0.3048 -0.127)
							(mid -0.275042 -0.198842)
							(end -0.2032 -0.2286)
						)
						(arc
							(start 0.2032 -0.2286)
							(mid 0.275042 -0.198842)
							(end 0.3048 -0.127)
						)
						(arc
							(start 0.3048 0.127)
							(mid 0.275042 0.198842)
							(end 0.2032 0.2286)
						)
					)
					(width 0)
					(fill yes)
				)
			)
		)
		(pad "2" smd custom
			(at 0 0.4445 90)
			(size 0.1143 0.1143)
			(layers "F.Cu" "F.Mask" "F.Paste")
			(net "GND")
			(options
				(clearance outline)
				(anchor circle)
			)
			(primitives
				(gr_poly
					(pts
						(arc
							(start 0.2032 -0.2286)
							(mid 0.275042 -0.198842)
							(end 0.3048 -0.127)
						)
						(arc
							(start 0.3048 0.127)
							(mid 0.275042 0.198842)
							(end 0.2032 0.2286)
						)
						(arc
							(start -0.2032 0.2286)
							(mid -0.275042 0.198842)
							(end -0.3048 0.127)
						)
						(arc
							(start -0.3048 -0.127)
							(mid -0.275042 -0.198842)
							(end -0.2032 -0.2286)
						)
					)
					(width 0)
					(fill yes)
				)
			)
		)
	)
	(footprint ""
		(layer "F.Cu")
		(at 24.042116 -164.3507 90)
		(property "Reference" "C226"
			(at 0 0 90)
			(layer "F.SilkS")
			(hide yes)
			(effects
				(font
					(size 1.27 1.27)
				)
			)
		)
		(property "Value" "SC10U6D3V5KX-4GP"
			(at -0.0762 -6.1214 90)
			(unlocked yes)
			(layer "F.Fab")
			(hide yes)
			(effects
				(font
					(size 1.016 1.016)
					(thickness 0.1524)
				)
			)
		)
		(property "Device Type" "C805H58"
			(at -0.0762 -8.1534 90)
			(unlocked yes)
			(layer "F.Fab")
			(hide yes)
			(effects
				(font
					(size 1.016 1.016)
					(thickness 0.1524)
				)
			)
		)
		(duplicate_pad_numbers_are_jumpers no)
		(fp_line
			(start 0.635 0)
			(end -0.635 0)
			(stroke
				(width 0.508)
				(type default)
			)
			(layer "F.SilkS")
		)
		(fp_rect
			(start -0.9652 1.778)
			(end 0.9652 -1.778)
			(stroke
				(width 0)
				(type default)
			)
			(fill no)
			(layer "F.CrtYd")
		)
		(fp_poly
			(pts
				(xy -0.9652 -1.778) (xy 0.9652 -1.778) (xy 0.9652 1.778) (xy -0.9652 1.778)
			)
			(stroke
				(width 0)
				(type default)
			)
			(fill no)
			(layer "F.Fab")
		)
		(pad "1" smd rect
			(at 0 -0.9652 90)
			(size 1.397 1.143)
			(layers "F.Cu" "F.Mask" "F.Paste")
			(net "TPS74801_P1V2_STBY_OUT")
		)
		(pad "2" smd rect
			(at 0 0.9652 90)
			(size 1.397 1.143)
			(layers "F.Cu" "F.Mask" "F.Paste")
			(net "GND")
		)
	)
	(footprint ""
		(layer "F.Cu")
		(at 61.9506 -156.2354)
		(property "Reference" "R335"
			(at 0 0 0)
			(layer "F.SilkS")
			(hide yes)
			(effects
				(font
					(size 1.27 1.27)
				)
			)
		)
		(property "Value" "0R2J-2-GP"
			(at 0.064008 -3.993896 0)
			(unlocked yes)
			(layer "F.Fab")
			(hide yes)
			(effects
				(font
					(size 1.016 1.016)
					(thickness 0.1524)
				)
			)
		)
		(property "Device Type" "R402H16"
			(at 0.064008 -5.517896 0)
			(unlocked yes)
			(layer "F.Fab")
			(hide yes)
			(effects
				(font
					(size 1.016 1.016)
					(thickness 0.1524)
				)
			)
		)
		(duplicate_pad_numbers_are_jumpers no)
		(fp_line
			(start -0.508 -0.9398)
			(end -0.508 0.9398)
			(stroke
				(width 0.1524)
				(type default)
			)
			(layer "F.SilkS")
		)
		(fp_line
			(start 0.508 -0.9398)
			(end -0.508 -0.9398)
			(stroke
				(width 0.1524)
				(type default)
			)
			(layer "F.SilkS")
		)
		(fp_rect
			(start -0.508 0.9398)
			(end 0.508 -0.9398)
			(stroke
				(width 0)
				(type default)
			)
			(fill no)
			(layer "F.CrtYd")
		)
		(fp_rect
			(start -0.508 0.9398)
			(end 0.508 -0.9398)
			(stroke
				(width 0)
				(type default)
			)
			(fill no)
			(layer "F.Fab")
		)
		(pad "1" smd custom
			(at 0 -0.4445)
			(size 0.1397 0.1397)
			(layers "F.Cu" "F.Mask" "F.Paste")
			(net "NCSI_TXD1")
			(options
				(clearance outline)
				(anchor circle)
			)
			(primitives
				(gr_poly
					(pts
						(arc
							(start -0.1778 -0.2794)
							(mid -0.249642 -0.249642)
							(end -0.2794 -0.1778)
						)
						(arc
							(start -0.2794 0.1778)
							(mid -0.249642 0.249642)
							(end -0.1778 0.2794)
						)
						(arc
							(start 0.1778 0.2794)
							(mid 0.249642 0.249642)
							(end 0.2794 0.1778)
						)
						(arc
							(start 0.2794 -0.1778)
							(mid 0.249642 -0.249642)
							(end 0.1778 -0.2794)
						)
					)
					(width 0)
					(fill yes)
				)
			)
		)
		(pad "2" smd custom
			(at 0 0.4445)
			(size 0.1397 0.1397)
			(layers "F.Cu" "F.Mask" "F.Paste")
			(net "NCSI_TXD1_R")
			(options
				(clearance outline)
				(anchor circle)
			)
			(primitives
				(gr_poly
					(pts
						(arc
							(start -0.1778 -0.2794)
							(mid -0.249642 -0.249642)
							(end -0.2794 -0.1778)
						)
						(arc
							(start -0.2794 0.1778)
							(mid -0.249642 0.249642)
							(end -0.1778 0.2794)
						)
						(arc
							(start 0.1778 0.2794)
							(mid 0.249642 0.249642)
							(end 0.2794 0.1778)
						)
						(arc
							(start 0.2794 -0.1778)
							(mid 0.249642 -0.249642)
							(end 0.1778 -0.2794)
						)
					)
					(width 0)
					(fill yes)
				)
			)
		)
	)
	(footprint ""
		(layer "F.Cu")
		(at 70.5104 -149.733 -90)
		(property "Reference" "U30"
			(at 0 0 270)
			(layer "F.SilkS")
			(hide yes)
			(effects
				(font
					(size 1.27 1.27)
				)
			)
		)
		(property "Value" "ICS551MLFT-GP"
			(at -3.707384 -1.5367 270)
			(unlocked yes)
			(layer "F.Fab")
			(hide yes)
			(effects
				(font
					(size 1.016 1.016)
					(thickness 0.1524)
				)
			)
		)
		(property "Device Type" "SOIC8H69"
			(at -3.707384 -3.0607 270)
			(unlocked yes)
			(layer "F.Fab")
			(hide yes)
			(effects
				(font
					(size 1.016 1.016)
					(thickness 0.1524)
				)
			)
		)
		(duplicate_pad_numbers_are_jumpers no)
		(fp_line
			(start -2.6289 3.4417)
			(end -2.6289 1.4732)
			(stroke
				(width 0.381)
				(type default)
			)
			(layer "F.SilkS")
		)
		(fp_line
			(start -2.7432 1.4224)
			(end -2.6416 1.4224)
			(stroke
				(width 0.1524)
				(type default)
			)
			(layer "F.SilkS")
		)
		(fp_line
			(start -2.7432 1.4224)
			(end 2.1336 1.4224)
			(stroke
				(width 0.1524)
				(type default)
			)
			(layer "F.SilkS")
		)
		(fp_line
			(start 2.1336 1.4224)
			(end 2.1336 -1.4224)
			(stroke
				(width 0.1524)
				(type default)
			)
			(layer "F.SilkS")
		)
		(fp_line
			(start -2.1844 -0.0508)
			(end -2.7178 0.508)
			(stroke
				(width 0.1524)
				(type default)
			)
			(layer "F.SilkS")
		)
		(fp_line
			(start -2.7178 -0.508)
			(end -2.1844 -0.0508)
			(stroke
				(width 0.1524)
				(type default)
			)
			(layer "F.SilkS")
		)
		(fp_line
			(start -2.7432 -1.4224)
			(end -2.7432 1.4224)
			(stroke
				(width 0.1524)
				(type default)
			)
			(layer "F.SilkS")
		)
		(fp_line
			(start 2.1336 -1.4224)
			(end -2.7432 -1.4224)
			(stroke
				(width 0.1524)
				(type default)
			)
			(layer "F.SilkS")
		)
		(fp_poly
			(pts
				(xy -2.2098 -1.4224) (xy -2.2098 1.4224) (xy 2.2098 1.4224) (xy 2.2098 -1.4224)
			)
			(stroke
				(width 0)
				(type default)
			)
			(fill yes)
			(layer "F.SilkS")
		)
		(fp_rect
			(start -2.450084 2.999994)
			(end 2.450084 -2.999994)
			(stroke
				(width 0)
				(type default)
			)
			(fill no)
			(layer "F.CrtYd")
		)
		(fp_poly
			(pts
				(xy -2.8194 3.6322) (xy -2.8194 -3.6322) (xy 2.8194 -3.6322) (xy 2.8194 1.18364) (xy 2.450084 1.18364)
				(xy 2.450084 -2.999994) (xy -2.450084 -2.999994) (xy -2.450084 2.999994) (xy 2.450084 2.999994)
				(xy 2.450084 1.18618) (xy 2.8194 1.18618) (xy 2.8194 3.6322)
			)
			(stroke
				(width 0)
				(type default)
			)
			(fill no)
			(layer "F.CrtYd")
		)
		(fp_rect
			(start -2.8194 3.6322)
			(end 2.8194 -3.6322)
			(stroke
				(width 0)
				(type default)
			)
			(fill no)
			(layer "F.Fab")
		)
		(pad "1" smd rect
			(at -1.905 2.54 270)
			(size 0.635 1.651)
			(layers "F.Cu" "F.Mask" "F.Paste")
			(net "50M_CLK_OUT_R")
		)
		(pad "2" smd rect
			(at -0.635 2.54 270)
			(size 0.635 1.651)
			(layers "F.Cu" "F.Mask" "F.Paste")
			(net "U30_Q1")
		)
		(pad "3" smd rect
			(at 0.635 2.54 270)
			(size 0.635 1.651)
			(layers "F.Cu" "F.Mask" "F.Paste")
			(net "Net_533")
		)
		(pad "4" smd rect
			(at 1.905 2.54 270)
			(size 0.635 1.651)
			(layers "F.Cu" "F.Mask" "F.Paste")
			(net "NCSI_RCLK_R")
		)
		(pad "5" smd rect
			(at 1.905 -2.54 270)
			(size 0.635 1.651)
			(layers "F.Cu" "F.Mask" "F.Paste")
			(net "Net_534")
		)
		(pad "6" smd rect
			(at 0.635 -2.54 270)
			(size 0.635 1.651)
			(layers "F.Cu" "F.Mask" "F.Paste")
			(net "GND")
		)
		(pad "7" smd rect
			(at -0.635 -2.54 270)
			(size 0.635 1.651)
			(layers "F.Cu" "F.Mask" "F.Paste")
			(net "P3V3_STBY")
		)
		(pad "8" smd rect
			(at -1.905 -2.54 270)
			(size 0.635 1.651)
			(layers "F.Cu" "F.Mask" "F.Paste")
			(net "50M_CLK_OE")
		)
	)
	(footprint ""
		(layer "F.Cu")
		(at 78.5114 -172.466 180)
		(property "Reference" "R504"
			(at 0 0 180)
			(layer "F.SilkS")
			(hide yes)
			(effects
				(font
					(size 1.27 1.27)
				)
			)
		)
		(property "Value" "0R5J-5-GP"
			(at 0 -8.9535 180)
			(unlocked yes)
			(layer "F.Fab")
			(hide yes)
			(effects
				(font
					(size 1.27 1.016)
					(thickness 0.1524)
				)
			)
		)
		(property "Device Type" "R805H24"
			(at 0 -10.6299 180)
			(unlocked yes)
			(layer "F.Fab")
			(hide yes)
			(effects
				(font
					(size 1.27 1.016)
					(thickness 0.1524)
				)
			)
		)
		(duplicate_pad_numbers_are_jumpers no)
		(fp_line
			(start 0.889 1.7018)
			(end 0.889 -0.508)
			(stroke
				(width 0.1524)
				(type default)
			)
			(layer "F.SilkS")
		)
		(fp_line
			(start 0.889 -1.7018)
			(end 0.889 -0.381)
			(stroke
				(width 0.1524)
				(type default)
			)
			(layer "F.SilkS")
		)
		(fp_line
			(start 0.889 -1.7018)
			(end -0.889 -1.7018)
			(stroke
				(width 0.1524)
				(type default)
			)
			(layer "F.SilkS")
		)
		(fp_line
			(start -0.889 1.7018)
			(end 0.889 1.7018)
			(stroke
				(width 0.1524)
				(type default)
			)
			(layer "F.SilkS")
		)
		(fp_line
			(start -0.889 0.0762)
			(end -0.889 1.7018)
			(stroke
				(width 0.1524)
				(type default)
			)
			(layer "F.SilkS")
		)
		(fp_line
			(start -0.889 -1.7018)
			(end -0.889 0.2794)
			(stroke
				(width 0.1524)
				(type default)
			)
			(layer "F.SilkS")
		)
		(fp_poly
			(pts
				(xy 0.9652 -1.778) (xy 0.9652 1.778) (xy -0.9652 1.778) (xy -0.9652 -1.778)
			)
			(stroke
				(width 0)
				(type default)
			)
			(fill no)
			(layer "F.CrtYd")
		)
		(fp_rect
			(start -0.9652 1.778)
			(end 0.9652 -1.778)
			(stroke
				(width 0)
				(type default)
			)
			(fill no)
			(layer "F.Fab")
		)
		(pad "1" smd rect
			(at 0 -0.9652 180)
			(size 1.397 1.143)
			(layers "F.Cu" "F.Mask" "F.Paste")
			(net "P2V5_STBY")
		)
		(pad "2" smd rect
			(at 0 0.9652 180)
			(size 1.397 1.143)
			(layers "F.Cu" "F.Mask" "F.Paste")
			(net "TPS74801_P2V5_STBY_OUT")
		)
	)
	(footprint ""
		(layer "F.Cu")
		(at 27.419046 -153.381456 -90)
		(property "Reference" "R771"
			(at 0 0 270)
			(layer "F.SilkS")
			(hide yes)
			(effects
				(font
					(size 1.27 1.27)
				)
			)
		)
		(property "Value" "0R2J-2-GP"
			(at 0.064008 -3.993896 270)
			(unlocked yes)
			(layer "F.Fab")
			(hide yes)
			(effects
				(font
					(size 1.016 1.016)
					(thickness 0.1524)
				)
			)
		)
		(property "Device Type" "R402H16"
			(at 0.064008 -5.517896 270)
			(unlocked yes)
			(layer "F.Fab")
			(hide yes)
			(effects
				(font
					(size 1.016 1.016)
					(thickness 0.1524)
				)
			)
		)
		(duplicate_pad_numbers_are_jumpers no)
		(fp_line
			(start -0.508 -0.9398)
			(end -0.508 0.9398)
			(stroke
				(width 0.1524)
				(type default)
			)
			(layer "F.SilkS")
		)
		(fp_line
			(start 0.508 -0.9398)
			(end -0.508 -0.9398)
			(stroke
				(width 0.1524)
				(type default)
			)
			(layer "F.SilkS")
		)
		(fp_rect
			(start -0.508 0.9398)
			(end 0.508 -0.9398)
			(stroke
				(width 0)
				(type default)
			)
			(fill no)
			(layer "F.CrtYd")
		)
		(fp_rect
			(start -0.508 0.9398)
			(end 0.508 -0.9398)
			(stroke
				(width 0)
				(type default)
			)
			(fill no)
			(layer "F.Fab")
		)
		(pad "1" smd custom
			(at 0 -0.4445 270)
			(size 0.1397 0.1397)
			(layers "F.Cu" "F.Mask" "F.Paste")
			(net "DEBUG_GPIO_BMC_R_4")
			(options
				(clearance outline)
				(anchor circle)
			)
			(primitives
				(gr_poly
					(pts
						(arc
							(start -0.1778 -0.2794)
							(mid -0.249642 -0.249642)
							(end -0.2794 -0.1778)
						)
						(arc
							(start -0.2794 0.1778)
							(mid -0.249642 0.249642)
							(end -0.1778 0.2794)
						)
						(arc
							(start 0.1778 0.2794)
							(mid 0.249642 0.249642)
							(end 0.2794 0.1778)
						)
						(arc
							(start 0.2794 -0.1778)
							(mid 0.249642 -0.249642)
							(end 0.1778 -0.2794)
						)
					)
					(width 0)
					(fill yes)
				)
			)
		)
		(pad "2" smd custom
			(at 0 0.4445 270)
			(size 0.1397 0.1397)
			(layers "F.Cu" "F.Mask" "F.Paste")
			(net "DEBUG_GPIO_BMC_4")
			(options
				(clearance outline)
				(anchor circle)
			)
			(primitives
				(gr_poly
					(pts
						(arc
							(start -0.1778 -0.2794)
							(mid -0.249642 -0.249642)
							(end -0.2794 -0.1778)
						)
						(arc
							(start -0.2794 0.1778)
							(mid -0.249642 0.249642)
							(end -0.1778 0.2794)
						)
						(arc
							(start 0.1778 0.2794)
							(mid 0.249642 0.249642)
							(end 0.2794 0.1778)
						)
						(arc
							(start 0.2794 -0.1778)
							(mid 0.249642 -0.249642)
							(end 0.1778 -0.2794)
						)
					)
					(width 0)
					(fill yes)
				)
			)
		)
	)
	(footprint ""
		(layer "F.Cu")
		(at 146.660616 -14.672818 180)
		(property "Reference" "R514"
			(at 0 0 180)
			(layer "F.SilkS")
			(hide yes)
			(effects
				(font
					(size 1.27 1.27)
				)
			)
		)
		(property "Value" "10R3F-GP"
			(at -0.0254 -2.5146 180)
			(unlocked yes)
			(layer "F.Fab")
			(hide yes)
			(effects
				(font
					(size 1.016 1.016)
					(thickness 0.1524)
				)
			)
		)
		(property "Device Type" "R603H22"
			(at -0.0254 -4.0386 180)
			(unlocked yes)
			(layer "F.Fab")
			(hide yes)
			(effects
				(font
					(size 1.016 1.016)
					(thickness 0.1524)
				)
			)
		)
		(duplicate_pad_numbers_are_jumpers no)
		(fp_line
			(start 0.2032 0)
			(end 0.4826 0)
			(stroke
				(width 0.2032)
				(type default)
			)
			(layer "F.SilkS")
		)
		(fp_line
			(start -0.4826 0)
			(end -0.2032 0)
			(stroke
				(width 0.2032)
				(type default)
			)
			(layer "F.SilkS")
		)
		(fp_rect
			(start -0.5842 1.3335)
			(end 0.5842 -1.3335)
			(stroke
				(width 0)
				(type default)
			)
			(fill no)
			(layer "F.CrtYd")
		)
		(fp_rect
			(start -0.5842 1.3335)
			(end 0.5842 -1.3335)
			(stroke
				(width 0)
				(type default)
			)
			(fill no)
			(layer "F.Fab")
		)
		(pad "1" smd custom
			(at 0 -0.762 180)
			(size 0.2159 0.2159)
			(layers "F.Cu" "F.Mask" "F.Paste")
			(net "P1V8_STBY_CC")
			(options
				(clearance outline)
				(anchor circle)
			)
			(primitives
				(gr_poly
					(pts
						(arc
							(start -0.3302 -0.4318)
							(mid -0.402042 -0.402042)
							(end -0.4318 -0.3302)
						)
						(arc
							(start -0.4318 0.3302)
							(mid -0.402042 0.402042)
							(end -0.3302 0.4318)
						)
						(arc
							(start 0.3302 0.4318)
							(mid 0.402042 0.402042)
							(end 0.4318 0.3302)
						)
						(arc
							(start 0.4318 -0.3302)
							(mid 0.402042 -0.402042)
							(end 0.3302 -0.4318)
						)
					)
					(width 0)
					(fill yes)
				)
			)
		)
		(pad "2" smd custom
			(at 0 0.762 180)
			(size 0.2159 0.2159)
			(layers "F.Cu" "F.Mask" "F.Paste")
			(net "P1V8_STBY_CC_R")
			(options
				(clearance outline)
				(anchor circle)
			)
			(primitives
				(gr_poly
					(pts
						(arc
							(start -0.3302 -0.4318)
							(mid -0.402042 -0.402042)
							(end -0.4318 -0.3302)
						)
						(arc
							(start -0.4318 0.3302)
							(mid -0.402042 0.402042)
							(end -0.3302 0.4318)
						)
						(arc
							(start 0.3302 0.4318)
							(mid 0.402042 0.402042)
							(end 0.4318 0.3302)
						)
						(arc
							(start 0.4318 -0.3302)
							(mid 0.402042 -0.402042)
							(end 0.3302 -0.4318)
						)
					)
					(width 0)
					(fill yes)
				)
			)
		)
	)
	(footprint ""
		(layer "F.Cu")
		(at 57.2516 -181.5592)
		(property "Reference" "C169"
			(at 0 0 0)
			(layer "F.SilkS")
			(hide yes)
			(effects
				(font
					(size 1.27 1.27)
				)
			)
		)
		(property "Value" "SCD1U16V2KX-3GP"
			(at 1.1811 -2.7051 0)
			(unlocked yes)
			(layer "F.Fab")
			(hide yes)
			(effects
				(font
					(size 1.016 1.016)
					(thickness 0.1524)
				)
			)
		)
		(property "Device Type" "C402H22"
			(at 1.1811 -4.2291 0)
			(unlocked yes)
			(layer "F.Fab")
			(hide yes)
			(effects
				(font
					(size 1.016 1.016)
					(thickness 0.1524)
				)
			)
		)
		(duplicate_pad_numbers_are_jumpers no)
		(fp_rect
			(start -0.4318 0.9525)
			(end 0.4318 -0.9525)
			(stroke
				(width 0)
				(type default)
			)
			(fill no)
			(layer "F.CrtYd")
		)
		(fp_rect
			(start -0.4318 0.9525)
			(end 0.4318 -0.9525)
			(stroke
				(width 0)
				(type default)
			)
			(fill no)
			(layer "F.Fab")
		)
		(pad "1" smd custom
			(at 0 -0.4445)
			(size 0.1524 0.1524)
			(layers "F.Cu" "F.Mask" "F.Paste")
			(net "P3V3_STBY_OUT")
			(options
				(clearance outline)
				(anchor circle)
			)
			(primitives
				(gr_poly
					(pts
						(arc
							(start 0.3048 -0.2032)
							(mid 0.275042 -0.275042)
							(end 0.2032 -0.3048)
						)
						(arc
							(start -0.2032 -0.3048)
							(mid -0.275042 -0.275042)
							(end -0.3048 -0.2032)
						)
						(arc
							(start -0.3048 0.2032)
							(mid -0.275042 0.275042)
							(end -0.2032 0.3048)
						)
						(arc
							(start 0.2032 0.3048)
							(mid 0.275042 0.275042)
							(end 0.3048 0.2032)
						)
					)
					(width 0)
					(fill yes)
				)
			)
		)
		(pad "2" smd custom
			(at 0 0.4445)
			(size 0.1524 0.1524)
			(layers "F.Cu" "F.Mask" "F.Paste")
			(net "GND")
			(options
				(clearance outline)
				(anchor circle)
			)
			(primitives
				(gr_poly
					(pts
						(arc
							(start 0.3048 -0.2032)
							(mid 0.275042 -0.275042)
							(end 0.2032 -0.3048)
						)
						(arc
							(start -0.2032 -0.3048)
							(mid -0.275042 -0.275042)
							(end -0.3048 -0.2032)
						)
						(arc
							(start -0.3048 0.2032)
							(mid -0.275042 0.275042)
							(end -0.2032 0.3048)
						)
						(arc
							(start 0.2032 0.3048)
							(mid 0.275042 0.275042)
							(end 0.3048 0.2032)
						)
					)
					(width 0)
					(fill yes)
				)
			)
		)
	)
	(footprint ""
		(layer "F.Cu")
		(at 227.069396 -45.95749 180)
		(property "Reference" "C159"
			(at 0 0 180)
			(layer "F.SilkS")
			(hide yes)
			(effects
				(font
					(size 1.27 1.27)
				)
			)
		)
		(property "Value" "SC2200P50V2KX-2GP"
			(at 1.1811 -2.7051 180)
			(unlocked yes)
			(layer "F.Fab")
			(hide yes)
			(effects
				(font
					(size 1.016 1.016)
					(thickness 0.1524)
				)
			)
		)
		(property "Device Type" "C402H22"
			(at 1.1811 -4.2291 180)
			(unlocked yes)
			(layer "F.Fab")
			(hide yes)
			(effects
				(font
					(size 1.016 1.016)
					(thickness 0.1524)
				)
			)
		)
		(duplicate_pad_numbers_are_jumpers no)
		(fp_rect
			(start -0.4318 0.9525)
			(end 0.4318 -0.9525)
			(stroke
				(width 0)
				(type default)
			)
			(fill no)
			(layer "F.CrtYd")
		)
		(fp_rect
			(start -0.4318 0.9525)
			(end 0.4318 -0.9525)
			(stroke
				(width 0)
				(type default)
			)
			(fill no)
			(layer "F.Fab")
		)
		(pad "1" smd custom
			(at 0 -0.4445 180)
			(size 0.1524 0.1524)
			(layers "F.Cu" "F.Mask" "F.Paste")
			(net "P5V_LL")
			(options
				(clearance outline)
				(anchor circle)
			)
			(primitives
				(gr_poly
					(pts
						(arc
							(start 0.3048 -0.2032)
							(mid 0.275042 -0.275042)
							(end 0.2032 -0.3048)
						)
						(arc
							(start -0.2032 -0.3048)
							(mid -0.275042 -0.275042)
							(end -0.3048 -0.2032)
						)
						(arc
							(start -0.3048 0.2032)
							(mid -0.275042 0.275042)
							(end -0.2032 0.3048)
						)
						(arc
							(start 0.2032 0.3048)
							(mid 0.275042 0.275042)
							(end 0.3048 0.2032)
						)
					)
					(width 0)
					(fill yes)
				)
			)
		)
		(pad "2" smd custom
			(at 0 0.4445 180)
			(size 0.1524 0.1524)
			(layers "F.Cu" "F.Mask" "F.Paste")
			(net "P5V_SNB")
			(options
				(clearance outline)
				(anchor circle)
			)
			(primitives
				(gr_poly
					(pts
						(arc
							(start 0.3048 -0.2032)
							(mid 0.275042 -0.275042)
							(end 0.2032 -0.3048)
						)
						(arc
							(start -0.2032 -0.3048)
							(mid -0.275042 -0.275042)
							(end -0.3048 -0.2032)
						)
						(arc
							(start -0.3048 0.2032)
							(mid -0.275042 0.275042)
							(end -0.2032 0.3048)
						)
						(arc
							(start 0.2032 0.3048)
							(mid 0.275042 0.275042)
							(end 0.3048 0.2032)
						)
					)
					(width 0)
					(fill yes)
				)
			)
		)
	)
	(footprint ""
		(layer "F.Cu")
		(at 17.99971 -24.99995)
		(property "Reference" ""
			(at 0 0 0)
			(layer "F.SilkS")
			(hide yes)
			(effects
				(font
					(size 1.27 1.27)
				)
			)
		)
		(property "Value" "*"
			(at -6.38175 0.19685 0)
			(unlocked yes)
			(layer "F.Fab")
			(hide yes)
			(effects
				(font
					(size 1.016 1.016)
					(thickness 0.1524)
				)
			)
		)
		(duplicate_pad_numbers_are_jumpers no)
		(fp_poly
			(pts
				(arc
					(start 5.0673 0)
					(mid -5.0673 0)
					(end 5.0673 0)
				)
			)
			(stroke
				(width 0)
				(type default)
			)
			(fill no)
			(layer "B.CrtYd")
		)
		(fp_poly
			(pts
				(arc
					(start 5.0673 0)
					(mid -5.0673 0)
					(end 5.0673 0)
				)
			)
			(stroke
				(width 0)
				(type default)
			)
			(fill no)
			(layer "F.CrtYd")
		)
		(fp_poly
			(pts
				(arc
					(start 5.0673 0)
					(mid -5.0673 0)
					(end 5.0673 0)
				)
			)
			(stroke
				(width 0)
				(type default)
			)
			(fill no)
			(layer "B.Fab")
		)
		(fp_poly
			(pts
				(arc
					(start 5.0673 0)
					(mid -5.0673 0)
					(end 5.0673 0)
				)
			)
			(stroke
				(width 0)
				(type default)
			)
			(fill no)
			(layer "F.Fab")
		)
		(pad "1" thru_hole circle
			(at 0 0)
			(size 9.525 9.525)
			(drill 3.5052)
			(layers "*.Cu" "*.Mask")
			(remove_unused_layers no)
			(net "Net_36")
			(clearance -2.5019)
			(thermal_gap 0.3048)
			(padstack
				(mode front_inner_back)
				(layer "Inner"
					(shape circle)
					(size 3.9116 3.9116)
					(clearance 0.3048)
				)
				(layer "B.Cu"
					(shape circle)
					(size 9.525 9.525)
					(clearance -2.5019)
				)
			)
		)
	)
	(footprint ""
		(layer "F.Cu")
		(at 41.450006 -169.999914)
		(property "Reference" "NUT1"
			(at 0 0 0)
			(layer "F.SilkS")
			(hide yes)
			(effects
				(font
					(size 1.27 1.27)
				)
			)
		)
		(property "Value" "STF256R168H278-GP"
			(at -4.826 0.0508 0)
			(unlocked yes)
			(layer "F.Fab")
			(hide yes)
			(effects
				(font
					(size 1.016 1.016)
					(thickness 0.1524)
				)
			)
		)
		(property "Device Type" "STF256R168H278"
			(at -4.826 -1.4732 0)
			(unlocked yes)
			(layer "F.Fab")
			(hide yes)
			(effects
				(font
					(size 1.016 1.016)
					(thickness 0.1524)
				)
			)
		)
		(duplicate_pad_numbers_are_jumpers no)
		(fp_circle
			(center 0 0)
			(end 3.6068 0)
			(stroke
				(width 0.3048)
				(type default)
			)
			(fill no)
			(layer "F.SilkS")
		)
		(fp_poly
			(pts
				(arc
					(start 3.7592 0)
					(mid -3.7592 0)
					(end 3.7592 0)
				)
			)
			(stroke
				(width 0)
				(type default)
			)
			(fill no)
			(layer "B.CrtYd")
		)
		(fp_poly
			(pts
				(arc
					(start 2.5019 0)
					(mid -2.5019 0)
					(end 2.5019 0)
				)
			)
			(stroke
				(width 0)
				(type default)
			)
			(fill no)
			(layer "F.CrtYd")
		)
		(fp_poly
			(pts
				(arc
					(start 3.7592 0.00635)
					(mid -3.759205 0)
					(end 3.7592 -0.00635)
				)
				(arc
					(start 2.5019 -0.00635)
					(mid -2.501908 0)
					(end 2.5019 0.00635)
				)
			)
			(stroke
				(width 0)
				(type default)
			)
			(fill no)
			(layer "F.CrtYd")
		)
		(fp_poly
			(pts
				(arc
					(start 3.7592 0)
					(mid -3.7592 0)
					(end 3.7592 0)
				)
			)
			(stroke
				(width 0)
				(type default)
			)
			(fill no)
			(layer "B.Fab")
		)
		(fp_poly
			(pts
				(arc
					(start 3.7592 0)
					(mid -3.7592 0)
					(end 3.7592 0)
				)
			)
			(stroke
				(width 0)
				(type default)
			)
			(fill no)
			(layer "F.Fab")
		)
		(pad "1" thru_hole circle
			(at 0 0)
			(size 6.5024 6.5024)
			(drill 4.2672)
			(layers "*.Cu" "*.Mask")
			(remove_unused_layers no)
			(net "Net_89")
			(clearance -0.6096)
			(thermal_gap 0.3048)
			(padstack
				(mode front_inner_back)
				(layer "Inner"
					(shape circle)
					(size 4.6736 4.6736)
					(clearance 0.3048)
				)
				(layer "B.Cu"
					(shape circle)
					(size 6.5024 6.5024)
					(clearance -0.6096)
				)
			)
		)
	)
	(footprint ""
		(layer "F.Cu")
		(at 91.308174 -123.486164)
		(property "Reference" "R725"
			(at 0 0 0)
			(layer "F.SilkS")
			(hide yes)
			(effects
				(font
					(size 1.27 1.27)
				)
			)
		)
		(property "Value" "4K7R2F-GP"
			(at 0.064008 -3.993896 0)
			(unlocked yes)
			(layer "F.Fab")
			(hide yes)
			(effects
				(font
					(size 1.016 1.016)
					(thickness 0.1524)
				)
			)
		)
		(property "Device Type" "R402H16"
			(at 0.064008 -5.517896 0)
			(unlocked yes)
			(layer "F.Fab")
			(hide yes)
			(effects
				(font
					(size 1.016 1.016)
					(thickness 0.1524)
				)
			)
		)
		(duplicate_pad_numbers_are_jumpers no)
		(fp_line
			(start -0.508 -0.9398)
			(end -0.508 0.9398)
			(stroke
				(width 0.1524)
				(type default)
			)
			(layer "F.SilkS")
		)
		(fp_line
			(start 0.508 -0.9398)
			(end -0.508 -0.9398)
			(stroke
				(width 0.1524)
				(type default)
			)
			(layer "F.SilkS")
		)
		(fp_rect
			(start -0.508 0.9398)
			(end 0.508 -0.9398)
			(stroke
				(width 0)
				(type default)
			)
			(fill no)
			(layer "F.CrtYd")
		)
		(fp_rect
			(start -0.508 0.9398)
			(end 0.508 -0.9398)
			(stroke
				(width 0)
				(type default)
			)
			(fill no)
			(layer "F.Fab")
		)
		(pad "1" smd custom
			(at 0 -0.4445)
			(size 0.1397 0.1397)
			(layers "F.Cu" "F.Mask" "F.Paste")
			(net "P3V3_STBY")
			(options
				(clearance outline)
				(anchor circle)
			)
			(primitives
				(gr_poly
					(pts
						(arc
							(start -0.1778 -0.2794)
							(mid -0.249642 -0.249642)
							(end -0.2794 -0.1778)
						)
						(arc
							(start -0.2794 0.1778)
							(mid -0.249642 0.249642)
							(end -0.1778 0.2794)
						)
						(arc
							(start 0.1778 0.2794)
							(mid 0.249642 0.249642)
							(end 0.2794 0.1778)
						)
						(arc
							(start 0.2794 -0.1778)
							(mid 0.249642 -0.249642)
							(end 0.1778 -0.2794)
						)
					)
					(width 0)
					(fill yes)
				)
			)
		)
		(pad "2" smd custom
			(at 0 0.4445)
			(size 0.1397 0.1397)
			(layers "F.Cu" "F.Mask" "F.Paste")
			(net "UART_COMP_IN_RX")
			(options
				(clearance outline)
				(anchor circle)
			)
			(primitives
				(gr_poly
					(pts
						(arc
							(start -0.1778 -0.2794)
							(mid -0.249642 -0.249642)
							(end -0.2794 -0.1778)
						)
						(arc
							(start -0.2794 0.1778)
							(mid -0.249642 0.249642)
							(end -0.1778 0.2794)
						)
						(arc
							(start 0.1778 0.2794)
							(mid 0.249642 0.249642)
							(end 0.2794 0.1778)
						)
						(arc
							(start 0.2794 -0.1778)
							(mid 0.249642 -0.249642)
							(end 0.1778 -0.2794)
						)
					)
					(width 0)
					(fill yes)
				)
			)
		)
	)
	(footprint ""
		(layer "F.Cu")
		(at 156.729938 -19.661378 90)
		(property "Reference" "C204"
			(at 0 0 90)
			(layer "F.SilkS")
			(hide yes)
			(effects
				(font
					(size 1.27 1.27)
				)
			)
		)
		(property "Value" "SC10U16V5KX-7-GP-U"
			(at -0.0762 -6.1214 90)
			(unlocked yes)
			(layer "F.Fab")
			(hide yes)
			(effects
				(font
					(size 1.016 1.016)
					(thickness 0.1524)
				)
			)
		)
		(property "Device Type" "C805H58"
			(at -0.0762 -8.1534 90)
			(unlocked yes)
			(layer "F.Fab")
			(hide yes)
			(effects
				(font
					(size 1.016 1.016)
					(thickness 0.1524)
				)
			)
		)
		(duplicate_pad_numbers_are_jumpers no)
		(fp_line
			(start 0.635 0)
			(end -0.635 0)
			(stroke
				(width 0.508)
				(type default)
			)
			(layer "F.SilkS")
		)
		(fp_rect
			(start -0.9652 1.778)
			(end 0.9652 -1.778)
			(stroke
				(width 0)
				(type default)
			)
			(fill no)
			(layer "F.CrtYd")
		)
		(fp_poly
			(pts
				(xy -0.9652 -1.778) (xy 0.9652 -1.778) (xy 0.9652 1.778) (xy -0.9652 1.778)
			)
			(stroke
				(width 0)
				(type default)
			)
			(fill no)
			(layer "F.Fab")
		)
		(pad "1" smd rect
			(at 0 -0.9652 90)
			(size 1.397 1.143)
			(layers "F.Cu" "F.Mask" "F.Paste")
			(net "P12V_STBY_VIN_PU4")
		)
		(pad "2" smd rect
			(at 0 0.9652 90)
			(size 1.397 1.143)
			(layers "F.Cu" "F.Mask" "F.Paste")
			(net "GND")
		)
	)
	(footprint ""
		(layer "F.Cu")
		(at 88.773 -127.0508 -90)
		(property "Reference" "R715"
			(at 0 0 270)
			(layer "F.SilkS")
			(hide yes)
			(effects
				(font
					(size 1.27 1.27)
				)
			)
		)
		(property "Value" "0R2J-2-GP"
			(at 0.064008 -3.993896 270)
			(unlocked yes)
			(layer "F.Fab")
			(hide yes)
			(effects
				(font
					(size 1.016 1.016)
					(thickness 0.1524)
				)
			)
		)
		(property "Device Type" "R402H16"
			(at 0.064008 -5.517896 270)
			(unlocked yes)
			(layer "F.Fab")
			(hide yes)
			(effects
				(font
					(size 1.016 1.016)
					(thickness 0.1524)
				)
			)
		)
		(duplicate_pad_numbers_are_jumpers no)
		(fp_line
			(start -0.508 -0.9398)
			(end -0.508 0.9398)
			(stroke
				(width 0.1524)
				(type default)
			)
			(layer "F.SilkS")
		)
		(fp_line
			(start 0.508 -0.9398)
			(end -0.508 -0.9398)
			(stroke
				(width 0.1524)
				(type default)
			)
			(layer "F.SilkS")
		)
		(fp_rect
			(start -0.508 0.9398)
			(end 0.508 -0.9398)
			(stroke
				(width 0)
				(type default)
			)
			(fill no)
			(layer "F.CrtYd")
		)
		(fp_rect
			(start -0.508 0.9398)
			(end 0.508 -0.9398)
			(stroke
				(width 0)
				(type default)
			)
			(fill no)
			(layer "F.Fab")
		)
		(pad "1" smd custom
			(at 0 -0.4445 270)
			(size 0.1397 0.1397)
			(layers "F.Cu" "F.Mask" "F.Paste")
			(net "UART_SEL_MUX")
			(options
				(clearance outline)
				(anchor circle)
			)
			(primitives
				(gr_poly
					(pts
						(arc
							(start -0.1778 -0.2794)
							(mid -0.249642 -0.249642)
							(end -0.2794 -0.1778)
						)
						(arc
							(start -0.2794 0.1778)
							(mid -0.249642 0.249642)
							(end -0.1778 0.2794)
						)
						(arc
							(start 0.1778 0.2794)
							(mid 0.249642 0.249642)
							(end 0.2794 0.1778)
						)
						(arc
							(start 0.2794 -0.1778)
							(mid 0.249642 -0.249642)
							(end 0.1778 -0.2794)
						)
					)
					(width 0)
					(fill yes)
				)
			)
		)
		(pad "2" smd custom
			(at 0 0.4445 270)
			(size 0.1397 0.1397)
			(layers "F.Cu" "F.Mask" "F.Paste")
			(net "BMC_UART_SEL_OUT")
			(options
				(clearance outline)
				(anchor circle)
			)
			(primitives
				(gr_poly
					(pts
						(arc
							(start -0.1778 -0.2794)
							(mid -0.249642 -0.249642)
							(end -0.2794 -0.1778)
						)
						(arc
							(start -0.2794 0.1778)
							(mid -0.249642 0.249642)
							(end -0.1778 0.2794)
						)
						(arc
							(start 0.1778 0.2794)
							(mid 0.249642 0.249642)
							(end 0.2794 0.1778)
						)
						(arc
							(start 0.2794 -0.1778)
							(mid 0.249642 -0.249642)
							(end 0.1778 -0.2794)
						)
					)
					(width 0)
					(fill yes)
				)
			)
		)
	)
	(footprint ""
		(layer "F.Cu")
		(at 134.897622 -8.034782 -90)
		(property "Reference" "Q5"
			(at 0 0 270)
			(layer "F.SilkS")
			(hide yes)
			(effects
				(font
					(size 1.27 1.27)
				)
			)
		)
		(property "Value" "PH0925CL-1-GP"
			(at -4.2799 -0.4572 270)
			(unlocked yes)
			(layer "F.Fab")
			(hide yes)
			(effects
				(font
					(size 1.016 1.016)
					(thickness 0.1524)
				)
			)
		)
		(property "Device Type" "LFPAK-5PH48-U"
			(at -4.2799 -1.9812 270)
			(unlocked yes)
			(layer "F.Fab")
			(hide yes)
			(effects
				(font
					(size 1.016 1.016)
					(thickness 0.1524)
				)
			)
		)
		(duplicate_pad_numbers_are_jumpers no)
		(fp_line
			(start -1.7272 1.1684)
			(end -2.1082 1.1684)
			(stroke
				(width 0.3302)
				(type default)
			)
			(layer "F.SilkS")
		)
		(fp_line
			(start -2.7559 1.0668)
			(end 2.7559 1.0668)
			(stroke
				(width 0.1524)
				(type default)
			)
			(layer "F.SilkS")
		)
		(fp_line
			(start 2.7559 1.0668)
			(end 2.7559 -6.5532)
			(stroke
				(width 0.1524)
				(type default)
			)
			(layer "F.SilkS")
		)
		(fp_line
			(start -2.7559 -6.5532)
			(end -2.7559 1.0668)
			(stroke
				(width 0.1524)
				(type default)
			)
			(layer "F.SilkS")
		)
		(fp_line
			(start 2.7559 -6.5532)
			(end -2.7559 -6.5532)
			(stroke
				(width 0.1524)
				(type default)
			)
			(layer "F.SilkS")
		)
		(fp_poly
			(pts
				(xy -2.34061 2.195322) (xy -1.90881 1.763522) (xy -1.47701 2.195322)
			)
			(stroke
				(width 0)
				(type default)
			)
			(fill yes)
			(layer "F.SilkS")
		)
		(fp_poly
			(pts
				(xy -2.5019 -1.09601) (xy -0.3302 -1.09601) (xy -0.3302 -3.36931) (xy -2.5019 -3.36931)
			)
			(stroke
				(width 0)
				(type default)
			)
			(fill yes)
			(layer "F.Paste")
		)
		(fp_poly
			(pts
				(xy 0.3302 -1.09601) (xy 2.5019 -1.09601) (xy 2.5019 -3.36931) (xy 0.3302 -3.36931)
			)
			(stroke
				(width 0)
				(type default)
			)
			(fill yes)
			(layer "F.Paste")
		)
		(fp_poly
			(pts
				(xy -2.5019 -4.02971) (xy -0.3302 -4.02971) (xy -0.3302 -6.30301) (xy -2.5019 -6.30301)
			)
			(stroke
				(width 0)
				(type default)
			)
			(fill yes)
			(layer "F.Paste")
		)
		(fp_poly
			(pts
				(xy 0.3302 -4.02971) (xy 2.5019 -4.02971) (xy 2.5019 -6.30301) (xy 0.3302 -6.30301)
			)
			(stroke
				(width 0)
				(type default)
			)
			(fill yes)
			(layer "F.Paste")
		)
		(fp_rect
			(start -2.4511 0.3048)
			(end 2.4511 -5.6896)
			(stroke
				(width 0)
				(type default)
			)
			(fill no)
			(layer "F.CrtYd")
		)
		(fp_poly
			(pts
				(xy -3.0099 1.3208) (xy -3.0099 -6.8072) (xy 3.0099 -6.8072) (xy 3.0099 -1.016) (xy 2.4511 -1.016)
				(xy 2.4511 -5.6896) (xy -2.4511 -5.6896) (xy -2.4511 0.3048) (xy 2.4511 0.3048) (xy 2.4511 -1.0033)
				(xy 3.0099 -1.0033) (xy 3.0099 1.3208)
			)
			(stroke
				(width 0)
				(type default)
			)
			(fill no)
			(layer "F.CrtYd")
		)
		(fp_rect
			(start -3.0099 1.3208)
			(end 3.0099 -6.8072)
			(stroke
				(width 0)
				(type default)
			)
			(fill no)
			(layer "F.Fab")
		)
		(pad "1" smd rect
			(at -1.905 0 270)
			(size 0.762 1.6256)
			(layers "F.Cu" "F.Mask" "F.Paste")
			(net "P12V_STBY")
		)
		(pad "2" smd rect
			(at -0.635 0 270)
			(size 0.762 1.6256)
			(layers "F.Cu" "F.Mask" "F.Paste")
			(net "P12V_STBY")
		)
		(pad "3" smd rect
			(at 0.635 0 270)
			(size 0.762 1.6256)
			(layers "F.Cu" "F.Mask" "F.Paste")
			(net "P12V_STBY")
		)
		(pad "4" smd rect
			(at 1.905 0 270)
			(size 0.762 1.6256)
			(layers "F.Cu" "F.Mask" "F.Paste")
			(net "MB0_12V_CTRL_GATE1")
		)
		(pad "5" smd rect
			(at 0 -3.69951 270)
			(size 5.0038 5.207)
			(layers "F.Cu" "F.Mask" "F.Paste")
			(net "MB0_P12V_MAIN_R")
		)
	)
	(footprint ""
		(layer "F.Cu")
		(at 63.126874 -175.139096)
		(property "Reference" "U9"
			(at 0 0 0)
			(layer "F.SilkS")
			(hide yes)
			(effects
				(font
					(size 1.27 1.27)
				)
			)
		)
		(property "Value" "SN74LVC1G07DCKRG4-2-GP"
			(at -2.3368 -8.6868 0)
			(unlocked yes)
			(layer "F.Fab")
			(hide yes)
			(effects
				(font
					(size 1.016 1.016)
					(thickness 0.1524)
				)
			)
		)
		(property "Device Type" "SC70-5H44"
			(at -2.3114 -10.414 0)
			(unlocked yes)
			(layer "F.Fab")
			(hide yes)
			(effects
				(font
					(size 1.016 1.016)
					(thickness 0.1524)
				)
			)
		)
		(duplicate_pad_numbers_are_jumpers no)
		(fp_line
			(start -1.27 -1.7018)
			(end 1.27 -1.7018)
			(stroke
				(width 0.1524)
				(type default)
			)
			(layer "F.SilkS")
		)
		(fp_line
			(start -1.27 1.7018)
			(end -1.27 -1.7018)
			(stroke
				(width 0.1524)
				(type default)
			)
			(layer "F.SilkS")
		)
		(fp_line
			(start 0.6604 -1.8034)
			(end 1.3843 -1.8034)
			(stroke
				(width 0.3302)
				(type default)
			)
			(layer "F.SilkS")
		)
		(fp_line
			(start 1.27 -1.7018)
			(end 1.27 1.7018)
			(stroke
				(width 0.1524)
				(type default)
			)
			(layer "F.SilkS")
		)
		(fp_line
			(start 1.27 1.7018)
			(end -1.27 1.7018)
			(stroke
				(width 0.1524)
				(type default)
			)
			(layer "F.SilkS")
		)
		(fp_line
			(start 1.3843 -1.8034)
			(end 1.3843 -1.1176)
			(stroke
				(width 0.3302)
				(type default)
			)
			(layer "F.SilkS")
		)
		(fp_rect
			(start -1.524 1.9558)
			(end 1.524 -1.9558)
			(stroke
				(width 0)
				(type default)
			)
			(fill no)
			(layer "F.CrtYd")
		)
		(fp_poly
			(pts
				(xy -1.524 -1.9558) (xy 1.524 -1.9558) (xy 1.524 1.9558) (xy -1.524 1.9558)
			)
			(stroke
				(width 0)
				(type default)
			)
			(fill no)
			(layer "F.Fab")
		)
		(pad "1" smd rect
			(at 0.65024 -0.8255)
			(size 0.4064 1.2192)
			(layers "F.Cu" "F.Mask" "F.Paste")
			(net "Net_526")
		)
		(pad "2" smd rect
			(at 0 -0.8255)
			(size 0.4064 1.2192)
			(layers "F.Cu" "F.Mask" "F.Paste")
			(net "FM_BMC_RESET_N")
		)
		(pad "3" smd rect
			(at -0.65024 -0.8255)
			(size 0.4064 1.2192)
			(layers "F.Cu" "F.Mask" "F.Paste")
			(net "GND")
		)
		(pad "4" smd rect
			(at -0.65024 0.8255)
			(size 0.4064 1.2192)
			(layers "F.Cu" "F.Mask" "F.Paste")
			(net "FM_TPM_PRSNT_RST_N_C")
		)
		(pad "5" smd rect
			(at 0.65024 0.8255)
			(size 0.4064 1.2192)
			(layers "F.Cu" "F.Mask" "F.Paste")
			(net "P3V3_STBY")
		)
	)
	(footprint ""
		(layer "F.Cu")
		(at 52.8574 -130.8608)
		(property "Reference" "TP12"
			(at 0 0 0)
			(layer "F.SilkS")
			(hide yes)
			(effects
				(font
					(size 1.27 1.27)
				)
			)
		)
		(property "Value" "TPAD28-2-GP"
			(at -0.0127 -1.6637 0)
			(unlocked yes)
			(layer "F.Fab")
			(hide yes)
			(effects
				(font
					(size 1.016 1.016)
					(thickness 0.1524)
				)
			)
		)
		(property "Device Type" "TPAD28"
			(at -0.0127 -3.1877 0)
			(unlocked yes)
			(layer "F.Fab")
			(hide yes)
			(effects
				(font
					(size 1.016 1.016)
					(thickness 0.1524)
				)
			)
		)
		(duplicate_pad_numbers_are_jumpers no)
		(fp_poly
			(pts
				(arc
					(start 0.3556 0)
					(mid -0.3556 0)
					(end 0.3556 0)
				)
			)
			(stroke
				(width 0)
				(type default)
			)
			(fill no)
			(layer "F.CrtYd")
		)
		(fp_poly
			(pts
				(arc
					(start 0.6096 0)
					(mid -0.6096 0)
					(end 0.6096 0)
				)
			)
			(stroke
				(width 0)
				(type default)
			)
			(fill no)
			(layer "F.Fab")
		)
		(pad "1" smd circle
			(at 0 0)
			(size 0.7112 0.7112)
			(layers "F.Cu" "F.Mask" "F.Paste")
			(net "TP_BMC0_LPC_LAD3")
		)
	)
	(footprint ""
		(layer "F.Cu")
		(at 213.910672 -47.476156 180)
		(property "Reference" "R478"
			(at 0 0 180)
			(layer "F.SilkS")
			(hide yes)
			(effects
				(font
					(size 1.27 1.27)
				)
			)
		)
		(property "Value" "10KR2F-2-GP"
			(at 0.064008 -3.993896 180)
			(unlocked yes)
			(layer "F.Fab")
			(hide yes)
			(effects
				(font
					(size 1.016 1.016)
					(thickness 0.1524)
				)
			)
		)
		(property "Device Type" "R402H16"
			(at 0.064008 -5.517896 180)
			(unlocked yes)
			(layer "F.Fab")
			(hide yes)
			(effects
				(font
					(size 1.016 1.016)
					(thickness 0.1524)
				)
			)
		)
		(duplicate_pad_numbers_are_jumpers no)
		(fp_line
			(start 0.508 -0.9398)
			(end -0.508 -0.9398)
			(stroke
				(width 0.1524)
				(type default)
			)
			(layer "F.SilkS")
		)
		(fp_line
			(start -0.508 -0.9398)
			(end -0.508 0.9398)
			(stroke
				(width 0.1524)
				(type default)
			)
			(layer "F.SilkS")
		)
		(fp_rect
			(start -0.508 0.9398)
			(end 0.508 -0.9398)
			(stroke
				(width 0)
				(type default)
			)
			(fill no)
			(layer "F.CrtYd")
		)
		(fp_rect
			(start -0.508 0.9398)
			(end 0.508 -0.9398)
			(stroke
				(width 0)
				(type default)
			)
			(fill no)
			(layer "F.Fab")
		)
		(pad "1" smd custom
			(at 0 -0.4445 180)
			(size 0.1397 0.1397)
			(layers "F.Cu" "F.Mask" "F.Paste")
			(net "P5V_VFB")
			(options
				(clearance outline)
				(anchor circle)
			)
			(primitives
				(gr_poly
					(pts
						(arc
							(start -0.1778 -0.2794)
							(mid -0.249642 -0.249642)
							(end -0.2794 -0.1778)
						)
						(arc
							(start -0.2794 0.1778)
							(mid -0.249642 0.249642)
							(end -0.1778 0.2794)
						)
						(arc
							(start 0.1778 0.2794)
							(mid 0.249642 0.249642)
							(end 0.2794 0.1778)
						)
						(arc
							(start 0.2794 -0.1778)
							(mid 0.249642 -0.249642)
							(end 0.1778 -0.2794)
						)
					)
					(width 0)
					(fill yes)
				)
			)
		)
		(pad "2" smd custom
			(at 0 0.4445 180)
			(size 0.1397 0.1397)
			(layers "F.Cu" "F.Mask" "F.Paste")
			(net "AGND_P5V")
			(options
				(clearance outline)
				(anchor circle)
			)
			(primitives
				(gr_poly
					(pts
						(arc
							(start -0.1778 -0.2794)
							(mid -0.249642 -0.249642)
							(end -0.2794 -0.1778)
						)
						(arc
							(start -0.2794 0.1778)
							(mid -0.249642 0.249642)
							(end -0.1778 0.2794)
						)
						(arc
							(start 0.1778 0.2794)
							(mid 0.249642 0.249642)
							(end 0.2794 0.1778)
						)
						(arc
							(start 0.2794 -0.1778)
							(mid 0.249642 -0.249642)
							(end 0.1778 -0.2794)
						)
					)
					(width 0)
					(fill yes)
				)
			)
		)
	)
	(footprint ""
		(layer "F.Cu")
		(at 79.93888 -172.72508)
		(property "Reference" "C195"
			(at 0 0 0)
			(layer "F.SilkS")
			(hide yes)
			(effects
				(font
					(size 1.27 1.27)
				)
			)
		)
		(property "Value" "SCD1U16V2KX-3GP"
			(at 1.1811 -2.7051 0)
			(unlocked yes)
			(layer "F.Fab")
			(hide yes)
			(effects
				(font
					(size 1.016 1.016)
					(thickness 0.1524)
				)
			)
		)
		(property "Device Type" "C402H22"
			(at 1.1811 -4.2291 0)
			(unlocked yes)
			(layer "F.Fab")
			(hide yes)
			(effects
				(font
					(size 1.016 1.016)
					(thickness 0.1524)
				)
			)
		)
		(duplicate_pad_numbers_are_jumpers no)
		(fp_rect
			(start -0.4318 0.9525)
			(end 0.4318 -0.9525)
			(stroke
				(width 0)
				(type default)
			)
			(fill no)
			(layer "F.CrtYd")
		)
		(fp_rect
			(start -0.4318 0.9525)
			(end 0.4318 -0.9525)
			(stroke
				(width 0)
				(type default)
			)
			(fill no)
			(layer "F.Fab")
		)
		(pad "1" smd custom
			(at 0 -0.4445)
			(size 0.1524 0.1524)
			(layers "F.Cu" "F.Mask" "F.Paste")
			(net "TPS74801_P2V5_STBY_OUT")
			(options
				(clearance outline)
				(anchor circle)
			)
			(primitives
				(gr_poly
					(pts
						(arc
							(start 0.3048 -0.2032)
							(mid 0.275042 -0.275042)
							(end 0.2032 -0.3048)
						)
						(arc
							(start -0.2032 -0.3048)
							(mid -0.275042 -0.275042)
							(end -0.3048 -0.2032)
						)
						(arc
							(start -0.3048 0.2032)
							(mid -0.275042 0.275042)
							(end -0.2032 0.3048)
						)
						(arc
							(start 0.2032 0.3048)
							(mid 0.275042 0.275042)
							(end 0.3048 0.2032)
						)
					)
					(width 0)
					(fill yes)
				)
			)
		)
		(pad "2" smd custom
			(at 0 0.4445)
			(size 0.1524 0.1524)
			(layers "F.Cu" "F.Mask" "F.Paste")
			(net "GND")
			(options
				(clearance outline)
				(anchor circle)
			)
			(primitives
				(gr_poly
					(pts
						(arc
							(start 0.3048 -0.2032)
							(mid 0.275042 -0.275042)
							(end 0.2032 -0.3048)
						)
						(arc
							(start -0.2032 -0.3048)
							(mid -0.275042 -0.275042)
							(end -0.3048 -0.2032)
						)
						(arc
							(start -0.3048 0.2032)
							(mid -0.275042 0.275042)
							(end -0.2032 0.3048)
						)
						(arc
							(start 0.2032 0.3048)
							(mid 0.275042 0.275042)
							(end 0.3048 0.2032)
						)
					)
					(width 0)
					(fill yes)
				)
			)
		)
	)
	(footprint ""
		(layer "F.Cu")
		(at 224.968054 -77.141832 90)
		(property "Reference" "C657"
			(at 0 0 90)
			(layer "F.SilkS")
			(hide yes)
			(effects
				(font
					(size 1.27 1.27)
				)
			)
		)
		(property "Value" "ST100U6D3VDM-8-GP"
			(at 0 -9.6012 90)
			(unlocked yes)
			(layer "F.Fab")
			(hide yes)
			(effects
				(font
					(size 1.016 1.016)
					(thickness 0.1524)
				)
			)
		)
		(property "Device Type" "CT7343H83"
			(at 0 -11.1252 90)
			(unlocked yes)
			(layer "F.Fab")
			(hide yes)
			(effects
				(font
					(size 1.016 1.016)
					(thickness 0.1524)
				)
			)
		)
		(duplicate_pad_numbers_are_jumpers no)
		(fp_line
			(start 2.286 -4.8768)
			(end -2.286 -4.8768)
			(stroke
				(width 0.1524)
				(type default)
			)
			(layer "F.SilkS")
		)
		(fp_line
			(start -2.286 -4.8768)
			(end -2.286 -2.032)
			(stroke
				(width 0.1524)
				(type default)
			)
			(layer "F.SilkS")
		)
		(fp_line
			(start 2.1082 -4.699)
			(end -2.1082 -4.699)
			(stroke
				(width 0.508)
				(type default)
			)
			(layer "F.SilkS")
		)
		(fp_line
			(start 2.286 -2.032)
			(end 2.286 -4.8768)
			(stroke
				(width 0.1524)
				(type default)
			)
			(layer "F.SilkS")
		)
		(fp_line
			(start 2.286 2.032)
			(end 2.286 4.8768)
			(stroke
				(width 0.1524)
				(type default)
			)
			(layer "F.SilkS")
		)
		(fp_line
			(start 2.286 4.8768)
			(end -2.286 4.8768)
			(stroke
				(width 0.1524)
				(type default)
			)
			(layer "F.SilkS")
		)
		(fp_line
			(start -2.286 4.8768)
			(end -2.286 2.032)
			(stroke
				(width 0.1524)
				(type default)
			)
			(layer "F.SilkS")
		)
		(fp_rect
			(start -2.1463 3.6449)
			(end 2.1463 -3.6449)
			(stroke
				(width 0)
				(type default)
			)
			(fill no)
			(layer "F.CrtYd")
		)
		(fp_poly
			(pts
				(xy -2.54 4.953) (xy -2.54 4.2926) (xy -3.81 4.2926) (xy -3.81 -4.2926) (xy -2.54 -4.2926) (xy -2.54 -4.953)
				(xy 2.54 -4.953) (xy 2.54 -4.2926) (xy 3.81 -4.2926) (xy 3.81 -1.6256) (xy 2.1463 -1.6256) (xy 2.1463 -3.6449)
				(xy -2.1463 -3.6449) (xy -2.1463 3.6449) (xy 2.1463 3.6449) (xy 2.1463 -1.6129) (xy 3.81 -1.6129)
				(xy 3.81 4.2926) (xy 2.54 4.2926) (xy 2.54 4.953)
			)
			(stroke
				(width 0)
				(type default)
			)
			(fill no)
			(layer "F.CrtYd")
		)
		(fp_rect
			(start 2.54 4.2926)
			(end 3.81 -4.2926)
			(stroke
				(width 0)
				(type default)
			)
			(fill no)
			(layer "F.Fab")
		)
		(fp_rect
			(start -3.81 4.2926)
			(end -2.54 -4.2926)
			(stroke
				(width 0)
				(type default)
			)
			(fill no)
			(layer "F.Fab")
		)
		(fp_rect
			(start -2.54 4.953)
			(end 2.54 -4.953)
			(stroke
				(width 0)
				(type default)
			)
			(fill no)
			(layer "F.Fab")
		)
		(pad "1" smd rect
			(at 0 -3.1496 90)
			(size 2.413 2.286)
			(layers "F.Cu" "F.Mask" "F.Paste")
			(net "P3V3_M2")
		)
		(pad "2" smd rect
			(at 0 3.1496 90)
			(size 2.413 2.286)
			(layers "F.Cu" "F.Mask" "F.Paste")
			(net "GND")
		)
		(zone
			(layer "F.Cu")
			(hatch none 0.5)
			(connect_pads
				(clearance 0)
			)
			(min_thickness 0.25)
			(keepout
				(tracks allowed)
				(vias not_allowed)
				(pads allowed)
				(copperpour not_allowed)
				(footprints allowed)
			)
			(placement
				(enabled no)
				(sheetname "")
			)
			(fill
				(thermal_gap 0.5)
				(thermal_bridge_width 0.5)
				(island_removal_mode 0)
			)
			(polygon
				(pts
					(xy 223.278954 -78.653132) (xy 220.370654 -78.653132) (xy 220.370654 -75.630532) (xy 223.266254 -75.630532)
					(xy 223.596454 -75.630532) (xy 223.596454 -78.653132)
				)
			)
		)
		(zone
			(layer "F.Cu")
			(hatch none 0.5)
			(connect_pads
				(clearance 0)
			)
			(min_thickness 0.25)
			(keepout
				(tracks allowed)
				(vias not_allowed)
				(pads allowed)
				(copperpour not_allowed)
				(footprints allowed)
			)
			(placement
				(enabled no)
				(sheetname "")
			)
			(fill
				(thermal_gap 0.5)
				(thermal_bridge_width 0.5)
				(island_removal_mode 0)
			)
			(polygon
				(pts
					(xy 229.565454 -75.630532) (xy 229.565454 -78.653132) (xy 226.669854 -78.653132) (xy 226.339654 -78.653132)
					(xy 226.339654 -75.630532) (xy 226.669854 -75.630532)
				)
			)
		)
	)
	(footprint ""
		(layer "F.Cu")
		(at 91.059 -29.464 -90)
		(property "Reference" "U98"
			(at 0 0 270)
			(layer "F.SilkS")
			(hide yes)
			(effects
				(font
					(size 1.27 1.27)
				)
			)
		)
		(property "Value" "TPS2065DBVT-GP"
			(at 0 -5.1308 270)
			(unlocked yes)
			(layer "F.Fab")
			(hide yes)
			(effects
				(font
					(size 1.016 1.016)
					(thickness 0.1524)
				)
			)
		)
		(property "Device Type" "SOT-23-5H58"
			(at 0 -6.7564 270)
			(unlocked yes)
			(layer "F.Fab")
			(hide yes)
			(effects
				(font
					(size 1.016 1.016)
					(thickness 0.1524)
				)
			)
		)
		(duplicate_pad_numbers_are_jumpers no)
		(fp_line
			(start -1.778 2.286)
			(end -0.254 2.286)
			(stroke
				(width 0.1524)
				(type default)
			)
			(layer "F.SilkS")
		)
		(fp_line
			(start -1.778 2.286)
			(end 1.778 2.286)
			(stroke
				(width 0.1524)
				(type default)
			)
			(layer "F.SilkS")
		)
		(fp_line
			(start -0.254 2.286)
			(end 1.778 2.286)
			(stroke
				(width 0.1524)
				(type default)
			)
			(layer "F.SilkS")
		)
		(fp_line
			(start 1.778 2.286)
			(end 1.778 -2.286)
			(stroke
				(width 0.1524)
				(type default)
			)
			(layer "F.SilkS")
		)
		(fp_line
			(start -1.7272 2.2352)
			(end -1.7272 0.762)
			(stroke
				(width 0.3302)
				(type default)
			)
			(layer "F.SilkS")
		)
		(fp_line
			(start -0.7112 2.2352)
			(end -1.7272 2.2352)
			(stroke
				(width 0.3302)
				(type default)
			)
			(layer "F.SilkS")
		)
		(fp_line
			(start -1.778 -2.286)
			(end -1.778 2.286)
			(stroke
				(width 0.1524)
				(type default)
			)
			(layer "F.SilkS")
		)
		(fp_line
			(start 1.778 -2.286)
			(end -1.778 -2.286)
			(stroke
				(width 0.1524)
				(type default)
			)
			(layer "F.SilkS")
		)
		(fp_poly
			(pts
				(xy -2.03708 1.279144) (xy -2.39268 0.923544) (xy -2.39268 1.634744)
			)
			(stroke
				(width 0)
				(type default)
			)
			(fill yes)
			(layer "F.SilkS")
		)
		(fp_rect
			(start -1.778 2.286)
			(end 1.778 -2.286)
			(stroke
				(width 0)
				(type default)
			)
			(fill no)
			(layer "F.CrtYd")
		)
		(fp_rect
			(start -1.778 2.286)
			(end 1.778 -2.286)
			(stroke
				(width 0)
				(type default)
			)
			(fill no)
			(layer "F.Fab")
		)
		(pad "1" smd rect
			(at -0.94996 1.143 270)
			(size 0.508 1.524)
			(layers "F.Cu" "F.Mask" "F.Paste")
			(net "P5V_USB")
		)
		(pad "2" smd rect
			(at 0 1.143 270)
			(size 0.508 1.524)
			(layers "F.Cu" "F.Mask" "F.Paste")
			(net "GND")
		)
		(pad "3" smd rect
			(at 0.94996 1.143 270)
			(size 0.508 1.524)
			(layers "F.Cu" "F.Mask" "F.Paste")
			(net "USB_OCS_N1")
		)
		(pad "4" smd rect
			(at 0.94996 -1.143 270)
			(size 0.508 1.524)
			(layers "F.Cu" "F.Mask" "F.Paste")
			(net "USB_EN_1")
		)
		(pad "5" smd rect
			(at -0.94996 -1.143 270)
			(size 0.508 1.524)
			(layers "F.Cu" "F.Mask" "F.Paste")
			(net "P5V_STBY")
		)
	)
	(footprint ""
		(layer "F.Cu")
		(at 216.08542 -90.367612 180)
		(property "Reference" "R831"
			(at 0 0 180)
			(layer "F.SilkS")
			(hide yes)
			(effects
				(font
					(size 1.27 1.27)
				)
			)
		)
		(property "Value" "20KR2F-L-GP"
			(at 0.064008 -3.993896 180)
			(unlocked yes)
			(layer "F.Fab")
			(hide yes)
			(effects
				(font
					(size 1.016 1.016)
					(thickness 0.1524)
				)
			)
		)
		(property "Device Type" "R402H16"
			(at 0.064008 -5.517896 180)
			(unlocked yes)
			(layer "F.Fab")
			(hide yes)
			(effects
				(font
					(size 1.016 1.016)
					(thickness 0.1524)
				)
			)
		)
		(duplicate_pad_numbers_are_jumpers no)
		(fp_line
			(start 0.508 -0.9398)
			(end -0.508 -0.9398)
			(stroke
				(width 0.1524)
				(type default)
			)
			(layer "F.SilkS")
		)
		(fp_line
			(start -0.508 -0.9398)
			(end -0.508 0.9398)
			(stroke
				(width 0.1524)
				(type default)
			)
			(layer "F.SilkS")
		)
		(fp_rect
			(start -0.508 0.9398)
			(end 0.508 -0.9398)
			(stroke
				(width 0)
				(type default)
			)
			(fill no)
			(layer "F.CrtYd")
		)
		(fp_rect
			(start -0.508 0.9398)
			(end 0.508 -0.9398)
			(stroke
				(width 0)
				(type default)
			)
			(fill no)
			(layer "F.Fab")
		)
		(pad "1" smd custom
			(at 0 -0.4445 180)
			(size 0.1397 0.1397)
			(layers "F.Cu" "F.Mask" "F.Paste")
			(net "GND")
			(options
				(clearance outline)
				(anchor circle)
			)
			(primitives
				(gr_poly
					(pts
						(arc
							(start -0.1778 -0.2794)
							(mid -0.249642 -0.249642)
							(end -0.2794 -0.1778)
						)
						(arc
							(start -0.2794 0.1778)
							(mid -0.249642 0.249642)
							(end -0.1778 0.2794)
						)
						(arc
							(start 0.1778 0.2794)
							(mid 0.249642 0.249642)
							(end 0.2794 0.1778)
						)
						(arc
							(start 0.2794 -0.1778)
							(mid 0.249642 -0.249642)
							(end 0.1778 -0.2794)
						)
					)
					(width 0)
					(fill yes)
				)
			)
		)
		(pad "2" smd custom
			(at 0 0.4445 180)
			(size 0.1397 0.1397)
			(layers "F.Cu" "F.Mask" "F.Paste")
			(net "IOM_FULL_PGOOD")
			(options
				(clearance outline)
				(anchor circle)
			)
			(primitives
				(gr_poly
					(pts
						(arc
							(start -0.1778 -0.2794)
							(mid -0.249642 -0.249642)
							(end -0.2794 -0.1778)
						)
						(arc
							(start -0.2794 0.1778)
							(mid -0.249642 0.249642)
							(end -0.1778 0.2794)
						)
						(arc
							(start 0.1778 0.2794)
							(mid 0.249642 0.249642)
							(end 0.2794 0.1778)
						)
						(arc
							(start 0.2794 -0.1778)
							(mid 0.249642 -0.249642)
							(end 0.1778 -0.2794)
						)
					)
					(width 0)
					(fill yes)
				)
			)
		)
	)
	(footprint ""
		(layer "F.Cu")
		(at 35.2044 -134.5438 90)
		(property "Reference" "R280"
			(at 0 0 90)
			(layer "F.SilkS")
			(hide yes)
			(effects
				(font
					(size 1.27 1.27)
				)
			)
		)
		(property "Value" "33R2F-3-GP"
			(at 0.064008 -3.993896 90)
			(unlocked yes)
			(layer "F.Fab")
			(hide yes)
			(effects
				(font
					(size 1.016 1.016)
					(thickness 0.1524)
				)
			)
		)
		(property "Device Type" "R402H16"
			(at 0.064008 -5.517896 90)
			(unlocked yes)
			(layer "F.Fab")
			(hide yes)
			(effects
				(font
					(size 1.016 1.016)
					(thickness 0.1524)
				)
			)
		)
		(duplicate_pad_numbers_are_jumpers no)
		(fp_line
			(start 0.508 -0.9398)
			(end -0.508 -0.9398)
			(stroke
				(width 0.1524)
				(type default)
			)
			(layer "F.SilkS")
		)
		(fp_line
			(start -0.508 -0.9398)
			(end -0.508 0.9398)
			(stroke
				(width 0.1524)
				(type default)
			)
			(layer "F.SilkS")
		)
		(fp_rect
			(start -0.508 0.9398)
			(end 0.508 -0.9398)
			(stroke
				(width 0)
				(type default)
			)
			(fill no)
			(layer "F.CrtYd")
		)
		(fp_rect
			(start -0.508 0.9398)
			(end 0.508 -0.9398)
			(stroke
				(width 0)
				(type default)
			)
			(fill no)
			(layer "F.Fab")
		)
		(pad "1" smd custom
			(at 0 -0.4445 90)
			(size 0.1397 0.1397)
			(layers "F.Cu" "F.Mask" "F.Paste")
			(net "FLA_CS_0_R")
			(options
				(clearance outline)
				(anchor circle)
			)
			(primitives
				(gr_poly
					(pts
						(arc
							(start -0.1778 -0.2794)
							(mid -0.249642 -0.249642)
							(end -0.2794 -0.1778)
						)
						(arc
							(start -0.2794 0.1778)
							(mid -0.249642 0.249642)
							(end -0.1778 0.2794)
						)
						(arc
							(start 0.1778 0.2794)
							(mid 0.249642 0.249642)
							(end 0.2794 0.1778)
						)
						(arc
							(start 0.2794 -0.1778)
							(mid 0.249642 -0.249642)
							(end 0.1778 -0.2794)
						)
					)
					(width 0)
					(fill yes)
				)
			)
		)
		(pad "2" smd custom
			(at 0 0.4445 90)
			(size 0.1397 0.1397)
			(layers "F.Cu" "F.Mask" "F.Paste")
			(net "FLA_CS_0")
			(options
				(clearance outline)
				(anchor circle)
			)
			(primitives
				(gr_poly
					(pts
						(arc
							(start -0.1778 -0.2794)
							(mid -0.249642 -0.249642)
							(end -0.2794 -0.1778)
						)
						(arc
							(start -0.2794 0.1778)
							(mid -0.249642 0.249642)
							(end -0.1778 0.2794)
						)
						(arc
							(start 0.1778 0.2794)
							(mid 0.249642 0.249642)
							(end 0.2794 0.1778)
						)
						(arc
							(start 0.2794 -0.1778)
							(mid 0.249642 -0.249642)
							(end 0.1778 -0.2794)
						)
					)
					(width 0)
					(fill yes)
				)
			)
		)
	)
	(footprint ""
		(layer "F.Cu")
		(at 88.674194 -53.331872)
		(property "Reference" "PQ3"
			(at 0 0 0)
			(layer "F.SilkS")
			(hide yes)
			(effects
				(font
					(size 1.27 1.27)
				)
			)
		)
		(property "Value" "FDS8878-G-GP"
			(at -3.707384 -1.5367 0)
			(unlocked yes)
			(layer "F.Fab")
			(hide yes)
			(effects
				(font
					(size 1.016 1.016)
					(thickness 0.1524)
				)
			)
		)
		(property "Device Type" "SOIC8H69"
			(at -3.707384 -3.0607 0)
			(unlocked yes)
			(layer "F.Fab")
			(hide yes)
			(effects
				(font
					(size 1.016 1.016)
					(thickness 0.1524)
				)
			)
		)
		(duplicate_pad_numbers_are_jumpers no)
		(fp_line
			(start -2.7432 -1.4224)
			(end -2.7432 1.4224)
			(stroke
				(width 0.1524)
				(type default)
			)
			(layer "F.SilkS")
		)
		(fp_line
			(start -2.7432 1.4224)
			(end -2.6416 1.4224)
			(stroke
				(width 0.1524)
				(type default)
			)
			(layer "F.SilkS")
		)
		(fp_line
			(start -2.7432 1.4224)
			(end 2.1336 1.4224)
			(stroke
				(width 0.1524)
				(type default)
			)
			(layer "F.SilkS")
		)
		(fp_line
			(start -2.7178 -0.508)
			(end -2.1844 -0.0508)
			(stroke
				(width 0.1524)
				(type default)
			)
			(layer "F.SilkS")
		)
		(fp_line
			(start -2.6289 3.4417)
			(end -2.6289 1.4732)
			(stroke
				(width 0.381)
				(type default)
			)
			(layer "F.SilkS")
		)
		(fp_line
			(start -2.1844 -0.0508)
			(end -2.7178 0.508)
			(stroke
				(width 0.1524)
				(type default)
			)
			(layer "F.SilkS")
		)
		(fp_line
			(start 2.1336 -1.4224)
			(end -2.7432 -1.4224)
			(stroke
				(width 0.1524)
				(type default)
			)
			(layer "F.SilkS")
		)
		(fp_line
			(start 2.1336 1.4224)
			(end 2.1336 -1.4224)
			(stroke
				(width 0.1524)
				(type default)
			)
			(layer "F.SilkS")
		)
		(fp_poly
			(pts
				(xy -2.2098 -1.4224) (xy -2.2098 1.4224) (xy 2.2098 1.4224) (xy 2.2098 -1.4224)
			)
			(stroke
				(width 0)
				(type default)
			)
			(fill yes)
			(layer "F.SilkS")
		)
		(fp_rect
			(start -2.450084 2.999994)
			(end 2.450084 -2.999994)
			(stroke
				(width 0)
				(type default)
			)
			(fill no)
			(layer "F.CrtYd")
		)
		(fp_poly
			(pts
				(xy -2.8194 3.6322) (xy -2.8194 -3.6322) (xy 2.8194 -3.6322) (xy 2.8194 1.18364) (xy 2.450084 1.18364)
				(xy 2.450084 -2.999994) (xy -2.450084 -2.999994) (xy -2.450084 2.999994) (xy 2.450084 2.999994)
				(xy 2.450084 1.18618) (xy 2.8194 1.18618) (xy 2.8194 3.6322)
			)
			(stroke
				(width 0)
				(type default)
			)
			(fill no)
			(layer "F.CrtYd")
		)
		(fp_rect
			(start -2.8194 3.6322)
			(end 2.8194 -3.6322)
			(stroke
				(width 0)
				(type default)
			)
			(fill no)
			(layer "F.Fab")
		)
		(pad "1" smd rect
			(at -1.905 2.54)
			(size 0.635 1.651)
			(layers "F.Cu" "F.Mask" "F.Paste")
			(net "P3V3")
		)
		(pad "2" smd rect
			(at -0.635 2.54)
			(size 0.635 1.651)
			(layers "F.Cu" "F.Mask" "F.Paste")
			(net "P3V3")
		)
		(pad "3" smd rect
			(at 0.635 2.54)
			(size 0.635 1.651)
			(layers "F.Cu" "F.Mask" "F.Paste")
			(net "P3V3")
		)
		(pad "4" smd rect
			(at 1.905 2.54)
			(size 0.635 1.651)
			(layers "F.Cu" "F.Mask" "F.Paste")
			(net "PQ2_D")
		)
		(pad "5" smd rect
			(at 1.905 -2.54)
			(size 0.635 1.651)
			(layers "F.Cu" "F.Mask" "F.Paste")
			(net "P3V3_STBY")
		)
		(pad "6" smd rect
			(at 0.635 -2.54)
			(size 0.635 1.651)
			(layers "F.Cu" "F.Mask" "F.Paste")
			(net "P3V3_STBY")
		)
		(pad "7" smd rect
			(at -0.635 -2.54)
			(size 0.635 1.651)
			(layers "F.Cu" "F.Mask" "F.Paste")
			(net "P3V3_STBY")
		)
		(pad "8" smd rect
			(at -1.905 -2.54)
			(size 0.635 1.651)
			(layers "F.Cu" "F.Mask" "F.Paste")
			(net "P3V3_STBY")
		)
	)
	(footprint ""
		(layer "F.Cu")
		(at 10.796524 -138.144504 90)
		(property "Reference" "R230"
			(at 0 0 90)
			(layer "F.SilkS")
			(hide yes)
			(effects
				(font
					(size 1.27 1.27)
				)
			)
		)
		(property "Value" "120R2F-GP"
			(at 0.064008 -3.993896 90)
			(unlocked yes)
			(layer "F.Fab")
			(hide yes)
			(effects
				(font
					(size 1.016 1.016)
					(thickness 0.1524)
				)
			)
		)
		(property "Device Type" "R402H16"
			(at 0.064008 -5.517896 90)
			(unlocked yes)
			(layer "F.Fab")
			(hide yes)
			(effects
				(font
					(size 1.016 1.016)
					(thickness 0.1524)
				)
			)
		)
		(duplicate_pad_numbers_are_jumpers no)
		(fp_line
			(start 0.508 -0.9398)
			(end -0.508 -0.9398)
			(stroke
				(width 0.1524)
				(type default)
			)
			(layer "F.SilkS")
		)
		(fp_line
			(start -0.508 -0.9398)
			(end -0.508 0.9398)
			(stroke
				(width 0.1524)
				(type default)
			)
			(layer "F.SilkS")
		)
		(fp_rect
			(start -0.508 0.9398)
			(end 0.508 -0.9398)
			(stroke
				(width 0)
				(type default)
			)
			(fill no)
			(layer "F.CrtYd")
		)
		(fp_rect
			(start -0.508 0.9398)
			(end 0.508 -0.9398)
			(stroke
				(width 0)
				(type default)
			)
			(fill no)
			(layer "F.Fab")
		)
		(pad "1" smd custom
			(at 0 -0.4445 90)
			(size 0.1397 0.1397)
			(layers "F.Cu" "F.Mask" "F.Paste")
			(net "MEMBA_0")
			(options
				(clearance outline)
				(anchor circle)
			)
			(primitives
				(gr_poly
					(pts
						(arc
							(start -0.1778 -0.2794)
							(mid -0.249642 -0.249642)
							(end -0.2794 -0.1778)
						)
						(arc
							(start -0.2794 0.1778)
							(mid -0.249642 0.249642)
							(end -0.1778 0.2794)
						)
						(arc
							(start 0.1778 0.2794)
							(mid 0.249642 0.249642)
							(end 0.2794 0.1778)
						)
						(arc
							(start 0.2794 -0.1778)
							(mid 0.249642 -0.249642)
							(end 0.1778 -0.2794)
						)
					)
					(width 0)
					(fill yes)
				)
			)
		)
		(pad "2" smd custom
			(at 0 0.4445 90)
			(size 0.1397 0.1397)
			(layers "F.Cu" "F.Mask" "F.Paste")
			(net "P1V2_STBY")
			(options
				(clearance outline)
				(anchor circle)
			)
			(primitives
				(gr_poly
					(pts
						(arc
							(start -0.1778 -0.2794)
							(mid -0.249642 -0.249642)
							(end -0.2794 -0.1778)
						)
						(arc
							(start -0.2794 0.1778)
							(mid -0.249642 0.249642)
							(end -0.1778 0.2794)
						)
						(arc
							(start 0.1778 0.2794)
							(mid 0.249642 0.249642)
							(end 0.2794 0.1778)
						)
						(arc
							(start 0.2794 -0.1778)
							(mid 0.249642 -0.249642)
							(end 0.1778 -0.2794)
						)
					)
					(width 0)
					(fill yes)
				)
			)
		)
	)
	(footprint ""
		(layer "F.Cu")
		(at 33.9344 -162.941)
		(property "Reference" "L5"
			(at 0 0 0)
			(layer "F.SilkS")
			(hide yes)
			(effects
				(font
					(size 1.27 1.27)
				)
			)
		)
		(property "Value" "MMZ2012S601ATA1N-GP"
			(at 0 -4.2418 0)
			(unlocked yes)
			(layer "F.Fab")
			(hide yes)
			(effects
				(font
					(size 1.016 1.016)
					(thickness 0.1524)
				)
			)
		)
		(property "Device Type" "L805H42"
			(at 0 -5.7912 0)
			(unlocked yes)
			(layer "F.Fab")
			(hide yes)
			(effects
				(font
					(size 1.016 1.016)
					(thickness 0.1524)
				)
			)
		)
		(duplicate_pad_numbers_are_jumpers no)
		(fp_line
			(start -0.889 -1.7018)
			(end 0.889 -1.7018)
			(stroke
				(width 0.1524)
				(type default)
			)
			(layer "F.SilkS")
		)
		(fp_line
			(start -0.889 1.7018)
			(end -0.889 -1.7018)
			(stroke
				(width 0.1524)
				(type default)
			)
			(layer "F.SilkS")
		)
		(fp_line
			(start 0.889 -1.7018)
			(end 0.889 1.7018)
			(stroke
				(width 0.1524)
				(type default)
			)
			(layer "F.SilkS")
		)
		(fp_line
			(start 0.889 1.7018)
			(end -0.889 1.7018)
			(stroke
				(width 0.1524)
				(type default)
			)
			(layer "F.SilkS")
		)
		(fp_rect
			(start -0.9652 1.778)
			(end 0.9652 -1.778)
			(stroke
				(width 0)
				(type default)
			)
			(fill no)
			(layer "F.CrtYd")
		)
		(fp_rect
			(start -0.9652 1.778)
			(end 0.9652 -1.778)
			(stroke
				(width 0)
				(type default)
			)
			(fill no)
			(layer "F.Fab")
		)
		(pad "1" smd rect
			(at 0 -0.9652)
			(size 1.397 1.143)
			(layers "F.Cu" "F.Mask" "F.Paste")
			(net "P1V15_STBY")
		)
		(pad "2" smd rect
			(at 0 0.9652)
			(size 1.397 1.143)
			(layers "F.Cu" "F.Mask" "F.Paste")
			(net "V1PLLAV11")
		)
	)
	(footprint ""
		(layer "F.Cu")
		(at 183.9468 -101.18852)
		(property "Reference" "TP215"
			(at 0 0 0)
			(layer "F.SilkS")
			(hide yes)
			(effects
				(font
					(size 1.27 1.27)
				)
			)
		)
		(property "Value" "TPAD32-GP"
			(at -0.0508 -1.6764 0)
			(unlocked yes)
			(layer "F.Fab")
			(hide yes)
			(effects
				(font
					(size 1.016 1.016)
					(thickness 0.1524)
				)
			)
		)
		(property "Device Type" "TPAD32"
			(at -0.0508 -3.2004 0)
			(unlocked yes)
			(layer "F.Fab")
			(hide yes)
			(effects
				(font
					(size 1.016 1.016)
					(thickness 0.1524)
				)
			)
		)
		(duplicate_pad_numbers_are_jumpers no)
		(fp_poly
			(pts
				(arc
					(start 0.4064 0)
					(mid -0.4064 0)
					(end 0.4064 0)
				)
			)
			(stroke
				(width 0)
				(type default)
			)
			(fill no)
			(layer "F.CrtYd")
		)
		(fp_poly
			(pts
				(arc
					(start 0.7112 0)
					(mid -0.7112 0)
					(end 0.7112 0)
				)
			)
			(stroke
				(width 0)
				(type default)
			)
			(fill no)
			(layer "F.Fab")
		)
		(pad "1" smd circle
			(at 0 0)
			(size 0.8128 0.8128)
			(layers "F.Cu" "F.Mask" "F.Paste")
			(net "TEMP_1_ALERT")
		)
	)
	(footprint ""
		(layer "F.Cu")
		(at 66.364104 -170.111674 90)
		(property "Reference" "R80"
			(at 0 0 90)
			(layer "F.SilkS")
			(hide yes)
			(effects
				(font
					(size 1.27 1.27)
				)
			)
		)
		(property "Value" "100KR2F-L1-GP"
			(at 0.064008 -3.993896 90)
			(unlocked yes)
			(layer "F.Fab")
			(hide yes)
			(effects
				(font
					(size 1.016 1.016)
					(thickness 0.1524)
				)
			)
		)
		(property "Device Type" "R402H16"
			(at 0.064008 -5.517896 90)
			(unlocked yes)
			(layer "F.Fab")
			(hide yes)
			(effects
				(font
					(size 1.016 1.016)
					(thickness 0.1524)
				)
			)
		)
		(duplicate_pad_numbers_are_jumpers no)
		(fp_line
			(start 0.508 -0.9398)
			(end -0.508 -0.9398)
			(stroke
				(width 0.1524)
				(type default)
			)
			(layer "F.SilkS")
		)
		(fp_line
			(start -0.508 -0.9398)
			(end -0.508 0.9398)
			(stroke
				(width 0.1524)
				(type default)
			)
			(layer "F.SilkS")
		)
		(fp_rect
			(start -0.508 0.9398)
			(end 0.508 -0.9398)
			(stroke
				(width 0)
				(type default)
			)
			(fill no)
			(layer "F.CrtYd")
		)
		(fp_rect
			(start -0.508 0.9398)
			(end 0.508 -0.9398)
			(stroke
				(width 0)
				(type default)
			)
			(fill no)
			(layer "F.Fab")
		)
		(pad "1" smd custom
			(at 0 -0.4445 90)
			(size 0.1397 0.1397)
			(layers "F.Cu" "F.Mask" "F.Paste")
			(net "Q4_G")
			(options
				(clearance outline)
				(anchor circle)
			)
			(primitives
				(gr_poly
					(pts
						(arc
							(start -0.1778 -0.2794)
							(mid -0.249642 -0.249642)
							(end -0.2794 -0.1778)
						)
						(arc
							(start -0.2794 0.1778)
							(mid -0.249642 0.249642)
							(end -0.1778 0.2794)
						)
						(arc
							(start 0.1778 0.2794)
							(mid 0.249642 0.249642)
							(end 0.2794 0.1778)
						)
						(arc
							(start 0.2794 -0.1778)
							(mid 0.249642 -0.249642)
							(end 0.1778 -0.2794)
						)
					)
					(width 0)
					(fill yes)
				)
			)
		)
		(pad "2" smd custom
			(at 0 0.4445 90)
			(size 0.1397 0.1397)
			(layers "F.Cu" "F.Mask" "F.Paste")
			(net "GND")
			(options
				(clearance outline)
				(anchor circle)
			)
			(primitives
				(gr_poly
					(pts
						(arc
							(start -0.1778 -0.2794)
							(mid -0.249642 -0.249642)
							(end -0.2794 -0.1778)
						)
						(arc
							(start -0.2794 0.1778)
							(mid -0.249642 0.249642)
							(end -0.1778 0.2794)
						)
						(arc
							(start 0.1778 0.2794)
							(mid 0.249642 0.249642)
							(end 0.2794 0.1778)
						)
						(arc
							(start 0.2794 -0.1778)
							(mid 0.249642 -0.249642)
							(end 0.1778 -0.2794)
						)
					)
					(width 0)
					(fill yes)
				)
			)
		)
	)
	(footprint ""
		(layer "F.Cu")
		(at 216.642188 -37.976556 -90)
		(property "Reference" "R468"
			(at 0 0 270)
			(layer "F.SilkS")
			(hide yes)
			(effects
				(font
					(size 1.27 1.27)
				)
			)
		)
		(property "Value" "3K3R2J-3-GP"
			(at 0.064008 -3.993896 270)
			(unlocked yes)
			(layer "F.Fab")
			(hide yes)
			(effects
				(font
					(size 1.016 1.016)
					(thickness 0.1524)
				)
			)
		)
		(property "Device Type" "R402H16"
			(at 0.064008 -5.517896 270)
			(unlocked yes)
			(layer "F.Fab")
			(hide yes)
			(effects
				(font
					(size 1.016 1.016)
					(thickness 0.1524)
				)
			)
		)
		(duplicate_pad_numbers_are_jumpers no)
		(fp_line
			(start -0.508 -0.9398)
			(end -0.508 0.9398)
			(stroke
				(width 0.1524)
				(type default)
			)
			(layer "F.SilkS")
		)
		(fp_line
			(start 0.508 -0.9398)
			(end -0.508 -0.9398)
			(stroke
				(width 0.1524)
				(type default)
			)
			(layer "F.SilkS")
		)
		(fp_rect
			(start -0.508 0.9398)
			(end 0.508 -0.9398)
			(stroke
				(width 0)
				(type default)
			)
			(fill no)
			(layer "F.CrtYd")
		)
		(fp_rect
			(start -0.508 0.9398)
			(end 0.508 -0.9398)
			(stroke
				(width 0)
				(type default)
			)
			(fill no)
			(layer "F.Fab")
		)
		(pad "1" smd custom
			(at 0 -0.4445 270)
			(size 0.1397 0.1397)
			(layers "F.Cu" "F.Mask" "F.Paste")
			(net "P5V_LL")
			(options
				(clearance outline)
				(anchor circle)
			)
			(primitives
				(gr_poly
					(pts
						(arc
							(start -0.1778 -0.2794)
							(mid -0.249642 -0.249642)
							(end -0.2794 -0.1778)
						)
						(arc
							(start -0.2794 0.1778)
							(mid -0.249642 0.249642)
							(end -0.1778 0.2794)
						)
						(arc
							(start 0.1778 0.2794)
							(mid 0.249642 0.249642)
							(end 0.2794 0.1778)
						)
						(arc
							(start 0.2794 -0.1778)
							(mid 0.249642 -0.249642)
							(end 0.1778 -0.2794)
						)
					)
					(width 0)
					(fill yes)
				)
			)
		)
		(pad "2" smd custom
			(at 0 0.4445 270)
			(size 0.1397 0.1397)
			(layers "F.Cu" "F.Mask" "F.Paste")
			(net "P5V_LL_R")
			(options
				(clearance outline)
				(anchor circle)
			)
			(primitives
				(gr_poly
					(pts
						(arc
							(start -0.1778 -0.2794)
							(mid -0.249642 -0.249642)
							(end -0.2794 -0.1778)
						)
						(arc
							(start -0.2794 0.1778)
							(mid -0.249642 0.249642)
							(end -0.1778 0.2794)
						)
						(arc
							(start 0.1778 0.2794)
							(mid 0.249642 0.249642)
							(end 0.2794 0.1778)
						)
						(arc
							(start 0.2794 -0.1778)
							(mid 0.249642 -0.249642)
							(end 0.1778 -0.2794)
						)
					)
					(width 0)
					(fill yes)
				)
			)
		)
	)
	(footprint ""
		(layer "F.Cu")
		(at 33.693354 -186.99861)
		(property "Reference" "R490"
			(at 0 0 0)
			(layer "F.SilkS")
			(hide yes)
			(effects
				(font
					(size 1.27 1.27)
				)
			)
		)
		(property "Value" "3D01R5F-GP"
			(at 0 -8.9535 0)
			(unlocked yes)
			(layer "F.Fab")
			(hide yes)
			(effects
				(font
					(size 1.27 1.016)
					(thickness 0.1524)
				)
			)
		)
		(property "Device Type" "R805H24"
			(at 0 -10.6299 0)
			(unlocked yes)
			(layer "F.Fab")
			(hide yes)
			(effects
				(font
					(size 1.27 1.016)
					(thickness 0.1524)
				)
			)
		)
		(duplicate_pad_numbers_are_jumpers no)
		(fp_line
			(start -0.889 -1.7018)
			(end -0.889 0.2794)
			(stroke
				(width 0.1524)
				(type default)
			)
			(layer "F.SilkS")
		)
		(fp_line
			(start -0.889 0.0762)
			(end -0.889 1.7018)
			(stroke
				(width 0.1524)
				(type default)
			)
			(layer "F.SilkS")
		)
		(fp_line
			(start -0.889 1.7018)
			(end 0.889 1.7018)
			(stroke
				(width 0.1524)
				(type default)
			)
			(layer "F.SilkS")
		)
		(fp_line
			(start 0.889 -1.7018)
			(end -0.889 -1.7018)
			(stroke
				(width 0.1524)
				(type default)
			)
			(layer "F.SilkS")
		)
		(fp_line
			(start 0.889 -1.7018)
			(end 0.889 -0.381)
			(stroke
				(width 0.1524)
				(type default)
			)
			(layer "F.SilkS")
		)
		(fp_line
			(start 0.889 1.7018)
			(end 0.889 -0.508)
			(stroke
				(width 0.1524)
				(type default)
			)
			(layer "F.SilkS")
		)
		(fp_poly
			(pts
				(xy 0.9652 -1.778) (xy 0.9652 1.778) (xy -0.9652 1.778) (xy -0.9652 -1.778)
			)
			(stroke
				(width 0)
				(type default)
			)
			(fill no)
			(layer "F.CrtYd")
		)
		(fp_rect
			(start -0.9652 1.778)
			(end 0.9652 -1.778)
			(stroke
				(width 0)
				(type default)
			)
			(fill no)
			(layer "F.Fab")
		)
		(pad "1" smd rect
			(at 0 -0.9652)
			(size 1.397 1.143)
			(layers "F.Cu" "F.Mask" "F.Paste")
			(net "P3V3_SNB")
		)
		(pad "2" smd rect
			(at 0 0.9652)
			(size 1.397 1.143)
			(layers "F.Cu" "F.Mask" "F.Paste")
			(net "GND")
		)
	)
	(footprint ""
		(layer "F.Cu")
		(at 153.986738 -7.697978 -90)
		(property "Reference" "C213"
			(at 0 0 270)
			(layer "F.SilkS")
			(hide yes)
			(effects
				(font
					(size 1.27 1.27)
				)
			)
		)
		(property "Value" "SC1U16V3KX-5GP"
			(at 0 -2.8194 270)
			(unlocked yes)
			(layer "F.Fab")
			(hide yes)
			(effects
				(font
					(size 1.016 1.016)
					(thickness 0.1524)
				)
			)
		)
		(property "Device Type" "C603H36"
			(at 0 -4.3434 270)
			(unlocked yes)
			(layer "F.Fab")
			(hide yes)
			(effects
				(font
					(size 1.016 1.016)
					(thickness 0.1524)
				)
			)
		)
		(duplicate_pad_numbers_are_jumpers no)
		(fp_line
			(start 0.508 0)
			(end -0.508 0)
			(stroke
				(width 0.2032)
				(type default)
			)
			(layer "F.SilkS")
		)
		(fp_rect
			(start -0.5842 1.3335)
			(end 0.5842 -1.3335)
			(stroke
				(width 0)
				(type default)
			)
			(fill no)
			(layer "F.CrtYd")
		)
		(fp_rect
			(start -0.5842 1.3335)
			(end 0.5842 -1.3335)
			(stroke
				(width 0)
				(type default)
			)
			(fill no)
			(layer "F.Fab")
		)
		(pad "1" smd custom
			(at 0 -0.762 270)
			(size 0.2159 0.2159)
			(layers "F.Cu" "F.Mask" "F.Paste")
			(net "GND")
			(options
				(clearance outline)
				(anchor circle)
			)
			(primitives
				(gr_poly
					(pts
						(arc
							(start -0.3302 -0.4318)
							(mid -0.402042 -0.402042)
							(end -0.4318 -0.3302)
						)
						(arc
							(start -0.4318 0.3302)
							(mid -0.402042 0.402042)
							(end -0.3302 0.4318)
						)
						(arc
							(start 0.3302 0.4318)
							(mid 0.402042 0.402042)
							(end 0.4318 0.3302)
						)
						(arc
							(start 0.4318 -0.3302)
							(mid 0.402042 -0.402042)
							(end 0.3302 -0.4318)
						)
					)
					(width 0)
					(fill yes)
				)
			)
		)
		(pad "2" smd custom
			(at 0 0.762 270)
			(size 0.2159 0.2159)
			(layers "F.Cu" "F.Mask" "F.Paste")
			(net "P1V8_STBY_EN_R")
			(options
				(clearance outline)
				(anchor circle)
			)
			(primitives
				(gr_poly
					(pts
						(arc
							(start -0.3302 -0.4318)
							(mid -0.402042 -0.402042)
							(end -0.4318 -0.3302)
						)
						(arc
							(start -0.4318 0.3302)
							(mid -0.402042 0.402042)
							(end -0.3302 0.4318)
						)
						(arc
							(start 0.3302 0.4318)
							(mid 0.402042 0.402042)
							(end 0.4318 0.3302)
						)
						(arc
							(start 0.4318 -0.3302)
							(mid 0.402042 -0.402042)
							(end 0.3302 -0.4318)
						)
					)
					(width 0)
					(fill yes)
				)
			)
		)
	)
	(footprint ""
		(layer "F.Cu")
		(at 215.17864 -102.615492 90)
		(property "Reference" "R824"
			(at 0 0 90)
			(layer "F.SilkS")
			(hide yes)
			(effects
				(font
					(size 1.27 1.27)
				)
			)
		)
		(property "Value" "39K2R2F-L-GP"
			(at 0.064008 -3.993896 90)
			(unlocked yes)
			(layer "F.Fab")
			(hide yes)
			(effects
				(font
					(size 1.016 1.016)
					(thickness 0.1524)
				)
			)
		)
		(property "Device Type" "R402H16"
			(at 0.064008 -5.517896 90)
			(unlocked yes)
			(layer "F.Fab")
			(hide yes)
			(effects
				(font
					(size 1.016 1.016)
					(thickness 0.1524)
				)
			)
		)
		(duplicate_pad_numbers_are_jumpers no)
		(fp_line
			(start 0.508 -0.9398)
			(end -0.508 -0.9398)
			(stroke
				(width 0.1524)
				(type default)
			)
			(layer "F.SilkS")
		)
		(fp_line
			(start -0.508 -0.9398)
			(end -0.508 0.9398)
			(stroke
				(width 0.1524)
				(type default)
			)
			(layer "F.SilkS")
		)
		(fp_rect
			(start -0.508 0.9398)
			(end 0.508 -0.9398)
			(stroke
				(width 0)
				(type default)
			)
			(fill no)
			(layer "F.CrtYd")
		)
		(fp_rect
			(start -0.508 0.9398)
			(end 0.508 -0.9398)
			(stroke
				(width 0)
				(type default)
			)
			(fill no)
			(layer "F.Fab")
		)
		(pad "1" smd custom
			(at 0 -0.4445 90)
			(size 0.1397 0.1397)
			(layers "F.Cu" "F.Mask" "F.Paste")
			(net "AGND_P3V3_M2")
			(options
				(clearance outline)
				(anchor circle)
			)
			(primitives
				(gr_poly
					(pts
						(arc
							(start -0.1778 -0.2794)
							(mid -0.249642 -0.249642)
							(end -0.2794 -0.1778)
						)
						(arc
							(start -0.2794 0.1778)
							(mid -0.249642 0.249642)
							(end -0.1778 0.2794)
						)
						(arc
							(start 0.1778 0.2794)
							(mid 0.249642 0.249642)
							(end 0.2794 0.1778)
						)
						(arc
							(start 0.2794 -0.1778)
							(mid 0.249642 -0.249642)
							(end 0.1778 -0.2794)
						)
					)
					(width 0)
					(fill yes)
				)
			)
		)
		(pad "2" smd custom
			(at 0 0.4445 90)
			(size 0.1397 0.1397)
			(layers "F.Cu" "F.Mask" "F.Paste")
			(net "P3V3_M2_MODE")
			(options
				(clearance outline)
				(anchor circle)
			)
			(primitives
				(gr_poly
					(pts
						(arc
							(start -0.1778 -0.2794)
							(mid -0.249642 -0.249642)
							(end -0.2794 -0.1778)
						)
						(arc
							(start -0.2794 0.1778)
							(mid -0.249642 0.249642)
							(end -0.1778 0.2794)
						)
						(arc
							(start 0.1778 0.2794)
							(mid 0.249642 0.249642)
							(end 0.2794 0.1778)
						)
						(arc
							(start 0.2794 -0.1778)
							(mid 0.249642 -0.249642)
							(end 0.1778 -0.2794)
						)
					)
					(width 0)
					(fill yes)
				)
			)
		)
	)
	(footprint ""
		(layer "F.Cu")
		(at 78.122018 -77.353668 90)
		(property "Reference" "VIA3"
			(at 0 0 90)
			(layer "F.SilkS")
			(hide yes)
			(effects
				(font
					(size 1.27 1.27)
				)
			)
		)
		(property "Value" "85OHM-8L-1D6MM-L16L18-GP"
			(at 4.064 0.6096 90)
			(unlocked yes)
			(layer "F.Fab")
			(hide yes)
			(effects
				(font
					(size 1.016 1.016)
					(thickness 0.1524)
				)
			)
		)
		(property "Device Type" "VIA-PCIE-4P-368076"
			(at 4.064 -0.9144 90)
			(unlocked yes)
			(layer "F.Fab")
			(hide yes)
			(effects
				(font
					(size 1.016 1.016)
					(thickness 0.1524)
				)
			)
		)
		(duplicate_pad_numbers_are_jumpers no)
		(fp_rect
			(start -1.8415 0.381)
			(end 1.8415 -0.381)
			(stroke
				(width 0)
				(type default)
			)
			(fill no)
			(layer "F.CrtYd")
		)
		(fp_rect
			(start -1.8415 0.381)
			(end 1.8415 -0.381)
			(stroke
				(width 0)
				(type default)
			)
			(fill no)
			(layer "F.Fab")
		)
		(pad "1" thru_hole circle
			(at -1.4605 0 90)
			(size 0.508 0.508)
			(drill 0.254)
			(layers "*.Cu" "*.Mask")
			(remove_unused_layers no)
			(net "GND")
			(clearance 0.127)
			(thermal_gap 0.127)
		)
		(pad "2" thru_hole circle
			(at -0.4445 0 90)
			(size 0.508 0.508)
			(drill 0.254)
			(layers "*.Cu" "*.Mask")
			(remove_unused_layers no)
			(net "PCIE_COMP_TO_IOM_18_DP")
			(clearance 0.127)
			(thermal_gap 0.127)
		)
		(pad "3" thru_hole circle
			(at 0.4445 0 90)
			(size 0.508 0.508)
			(drill 0.254)
			(layers "*.Cu" "*.Mask")
			(remove_unused_layers no)
			(net "PCIE_COMP_TO_IOM_18_DN")
			(clearance 0.127)
			(thermal_gap 0.127)
		)
		(pad "4" thru_hole circle
			(at 1.4605 0 90)
			(size 0.508 0.508)
			(drill 0.254)
			(layers "*.Cu" "*.Mask")
			(remove_unused_layers no)
			(net "GND")
			(clearance 0.127)
			(thermal_gap 0.127)
		)
	)
	(footprint ""
		(layer "F.Cu")
		(at 205.232 -141.224 -135)
		(property "Reference" "VIA52"
			(at 0 0 225)
			(layer "F.SilkS")
			(hide yes)
			(effects
				(font
					(size 1.27 1.27)
				)
			)
		)
		(property "Value" "85OHM-8L-1D6MM-L16L18-GP"
			(at 4.064105 0.609655 225)
			(unlocked yes)
			(layer "F.Fab")
			(hide yes)
			(effects
				(font
					(size 1.016 1.016)
					(thickness 0.1524)
				)
			)
		)
		(property "Device Type" "VIA-PCIE-4P-368076"
			(at 4.064105 -0.914474 225)
			(unlocked yes)
			(layer "F.Fab")
			(hide yes)
			(effects
				(font
					(size 1.016 1.016)
					(thickness 0.1524)
				)
			)
		)
		(duplicate_pad_numbers_are_jumpers no)
		(fp_poly
			(pts
				(xy -1.841491 -0.381057) (xy 1.841509 -0.381058) (xy 1.841508 0.380942) (xy -1.841491 0.380942)
			)
			(stroke
				(width 0)
				(type default)
			)
			(fill no)
			(layer "F.CrtYd")
		)
		(fp_poly
			(pts
				(xy -1.841491 -0.381057) (xy 1.841509 -0.381058) (xy 1.841508 0.380942) (xy -1.841491 0.380942)
			)
			(stroke
				(width 0)
				(type default)
			)
			(fill no)
			(layer "F.Fab")
		)
		(pad "1" thru_hole circle
			(at -1.460499 0 225)
			(size 0.508 0.508)
			(drill 0.254)
			(layers "*.Cu" "*.Mask")
			(remove_unused_layers no)
			(net "GND")
			(clearance 0.127)
			(thermal_gap 0.127)
		)
		(pad "2" thru_hole circle
			(at -0.4445 0 225)
			(size 0.508 0.508)
			(drill 0.254)
			(layers "*.Cu" "*.Mask")
			(remove_unused_layers no)
			(net "PCIE_COMP_TO_IOM_9_DP")
			(clearance 0.127)
			(thermal_gap 0.127)
		)
		(pad "3" thru_hole circle
			(at 0.4445 0 225)
			(size 0.508 0.508)
			(drill 0.254)
			(layers "*.Cu" "*.Mask")
			(remove_unused_layers no)
			(net "PCIE_COMP_TO_IOM_9_DN")
			(clearance 0.127)
			(thermal_gap 0.127)
		)
		(pad "4" thru_hole circle
			(at 1.460499 0 225)
			(size 0.508 0.508)
			(drill 0.254)
			(layers "*.Cu" "*.Mask")
			(remove_unused_layers no)
			(net "GND")
			(clearance 0.127)
			(thermal_gap 0.127)
		)
	)
	(footprint ""
		(layer "F.Cu")
		(at 37.3126 -175.6664 -90)
		(property "Reference" "C183"
			(at 0 0 270)
			(layer "F.SilkS")
			(hide yes)
			(effects
				(font
					(size 1.27 1.27)
				)
			)
		)
		(property "Value" "SC1KP50V2KX-1GP"
			(at 1.1811 -2.7051 270)
			(unlocked yes)
			(layer "F.Fab")
			(hide yes)
			(effects
				(font
					(size 1.016 1.016)
					(thickness 0.1524)
				)
			)
		)
		(property "Device Type" "C402H22"
			(at 1.1811 -4.2291 270)
			(unlocked yes)
			(layer "F.Fab")
			(hide yes)
			(effects
				(font
					(size 1.016 1.016)
					(thickness 0.1524)
				)
			)
		)
		(duplicate_pad_numbers_are_jumpers no)
		(fp_rect
			(start -0.4318 0.9525)
			(end 0.4318 -0.9525)
			(stroke
				(width 0)
				(type default)
			)
			(fill no)
			(layer "F.CrtYd")
		)
		(fp_rect
			(start -0.4318 0.9525)
			(end 0.4318 -0.9525)
			(stroke
				(width 0)
				(type default)
			)
			(fill no)
			(layer "F.Fab")
		)
		(pad "1" smd custom
			(at 0 -0.4445 270)
			(size 0.1524 0.1524)
			(layers "F.Cu" "F.Mask" "F.Paste")
			(net "P3V3_STBY_LL_R")
			(options
				(clearance outline)
				(anchor circle)
			)
			(primitives
				(gr_poly
					(pts
						(arc
							(start 0.3048 -0.2032)
							(mid 0.275042 -0.275042)
							(end 0.2032 -0.3048)
						)
						(arc
							(start -0.2032 -0.3048)
							(mid -0.275042 -0.275042)
							(end -0.3048 -0.2032)
						)
						(arc
							(start -0.3048 0.2032)
							(mid -0.275042 0.275042)
							(end -0.2032 0.3048)
						)
						(arc
							(start 0.2032 0.3048)
							(mid 0.275042 0.275042)
							(end 0.3048 0.2032)
						)
					)
					(width 0)
					(fill yes)
				)
			)
		)
		(pad "2" smd custom
			(at 0 0.4445 270)
			(size 0.1524 0.1524)
			(layers "F.Cu" "F.Mask" "F.Paste")
			(net "P3V3_STBY_VFB")
			(options
				(clearance outline)
				(anchor circle)
			)
			(primitives
				(gr_poly
					(pts
						(arc
							(start 0.3048 -0.2032)
							(mid 0.275042 -0.275042)
							(end 0.2032 -0.3048)
						)
						(arc
							(start -0.2032 -0.3048)
							(mid -0.275042 -0.275042)
							(end -0.3048 -0.2032)
						)
						(arc
							(start -0.3048 0.2032)
							(mid -0.275042 0.275042)
							(end -0.2032 0.3048)
						)
						(arc
							(start 0.2032 0.3048)
							(mid 0.275042 0.275042)
							(end 0.3048 0.2032)
						)
					)
					(width 0)
					(fill yes)
				)
			)
		)
	)
	(footprint ""
		(layer "F.Cu")
		(at 12.499848 -187.999878)
		(property "Reference" ""
			(at 0 0 0)
			(layer "F.SilkS")
			(hide yes)
			(effects
				(font
					(size 1.27 1.27)
				)
			)
		)
		(property "Value" "*"
			(at 6.2484 0.3429 0)
			(unlocked yes)
			(layer "F.Fab")
			(hide yes)
			(effects
				(font
					(size 1.016 1.016)
					(thickness 0.1524)
				)
			)
		)
		(duplicate_pad_numbers_are_jumpers no)
		(fp_poly
			(pts
				(arc
					(start 5.0673 0)
					(mid -5.0673 0)
					(end 5.0673 0)
				)
			)
			(stroke
				(width 0)
				(type default)
			)
			(fill no)
			(layer "B.CrtYd")
		)
		(fp_poly
			(pts
				(arc
					(start 5.0673 0)
					(mid -5.0673 0)
					(end 5.0673 0)
				)
			)
			(stroke
				(width 0)
				(type default)
			)
			(fill no)
			(layer "F.CrtYd")
		)
		(fp_poly
			(pts
				(arc
					(start 5.0673 0)
					(mid -5.0673 0)
					(end 5.0673 0)
				)
			)
			(stroke
				(width 0)
				(type default)
			)
			(fill no)
			(layer "B.Fab")
		)
		(fp_poly
			(pts
				(arc
					(start 5.0673 0)
					(mid -5.0673 0)
					(end 5.0673 0)
				)
			)
			(stroke
				(width 0)
				(type default)
			)
			(fill no)
			(layer "F.Fab")
		)
		(pad "1" thru_hole circle
			(at 0 0)
			(size 9.525 9.525)
			(drill 4.0132)
			(layers "*.Cu" "*.Mask")
			(remove_unused_layers no)
			(net "Net_85")
			(clearance -2.2479)
			(thermal_gap 0.3048)
			(padstack
				(mode front_inner_back)
				(layer "Inner"
					(shape circle)
					(size 4.4196 4.4196)
					(clearance 0.3048)
				)
				(layer "B.Cu"
					(shape circle)
					(size 9.525 9.525)
					(clearance -2.2479)
				)
			)
		)
	)
	(footprint ""
		(layer "F.Cu")
		(at 47.540418 -128.189736)
		(property "Reference" "R200"
			(at 0 0 0)
			(layer "F.SilkS")
			(hide yes)
			(effects
				(font
					(size 1.27 1.27)
				)
			)
		)
		(property "Value" "2K2R2F-GP"
			(at 0.064008 -3.993896 0)
			(unlocked yes)
			(layer "F.Fab")
			(hide yes)
			(effects
				(font
					(size 1.016 1.016)
					(thickness 0.1524)
				)
			)
		)
		(property "Device Type" "R402H16"
			(at 0.064008 -5.517896 0)
			(unlocked yes)
			(layer "F.Fab")
			(hide yes)
			(effects
				(font
					(size 1.016 1.016)
					(thickness 0.1524)
				)
			)
		)
		(duplicate_pad_numbers_are_jumpers no)
		(fp_line
			(start -0.508 -0.9398)
			(end -0.508 0.9398)
			(stroke
				(width 0.1524)
				(type default)
			)
			(layer "F.SilkS")
		)
		(fp_line
			(start 0.508 -0.9398)
			(end -0.508 -0.9398)
			(stroke
				(width 0.1524)
				(type default)
			)
			(layer "F.SilkS")
		)
		(fp_rect
			(start -0.508 0.9398)
			(end 0.508 -0.9398)
			(stroke
				(width 0)
				(type default)
			)
			(fill no)
			(layer "F.CrtYd")
		)
		(fp_rect
			(start -0.508 0.9398)
			(end 0.508 -0.9398)
			(stroke
				(width 0)
				(type default)
			)
			(fill no)
			(layer "F.Fab")
		)
		(pad "1" smd custom
			(at 0 -0.4445)
			(size 0.1397 0.1397)
			(layers "F.Cu" "F.Mask" "F.Paste")
			(net "I2C_TPM_SCL")
			(options
				(clearance outline)
				(anchor circle)
			)
			(primitives
				(gr_poly
					(pts
						(arc
							(start -0.1778 -0.2794)
							(mid -0.249642 -0.249642)
							(end -0.2794 -0.1778)
						)
						(arc
							(start -0.2794 0.1778)
							(mid -0.249642 0.249642)
							(end -0.1778 0.2794)
						)
						(arc
							(start 0.1778 0.2794)
							(mid 0.249642 0.249642)
							(end 0.2794 0.1778)
						)
						(arc
							(start 0.2794 -0.1778)
							(mid 0.249642 -0.249642)
							(end 0.1778 -0.2794)
						)
					)
					(width 0)
					(fill yes)
				)
			)
		)
		(pad "2" smd custom
			(at 0 0.4445)
			(size 0.1397 0.1397)
			(layers "F.Cu" "F.Mask" "F.Paste")
			(net "P3V3_STBY")
			(options
				(clearance outline)
				(anchor circle)
			)
			(primitives
				(gr_poly
					(pts
						(arc
							(start -0.1778 -0.2794)
							(mid -0.249642 -0.249642)
							(end -0.2794 -0.1778)
						)
						(arc
							(start -0.2794 0.1778)
							(mid -0.249642 0.249642)
							(end -0.1778 0.2794)
						)
						(arc
							(start 0.1778 0.2794)
							(mid 0.249642 0.249642)
							(end 0.2794 0.1778)
						)
						(arc
							(start 0.2794 -0.1778)
							(mid 0.249642 -0.249642)
							(end 0.1778 -0.2794)
						)
					)
					(width 0)
					(fill yes)
				)
			)
		)
	)
	(footprint ""
		(layer "F.Cu")
		(at 180.319426 -140.483082 -135)
		(property "Reference" "VIA60"
			(at 0 0 225)
			(layer "F.SilkS")
			(hide yes)
			(effects
				(font
					(size 1.27 1.27)
				)
			)
		)
		(property "Value" "85OHM-8L-1D6MM-L16L18-GP"
			(at 4.064105 0.609655 225)
			(unlocked yes)
			(layer "F.Fab")
			(hide yes)
			(effects
				(font
					(size 1.016 1.016)
					(thickness 0.1524)
				)
			)
		)
		(property "Device Type" "VIA-PCIE-4P-368076"
			(at 4.064105 -0.914474 225)
			(unlocked yes)
			(layer "F.Fab")
			(hide yes)
			(effects
				(font
					(size 1.016 1.016)
					(thickness 0.1524)
				)
			)
		)
		(duplicate_pad_numbers_are_jumpers no)
		(fp_poly
			(pts
				(xy -1.841491 -0.381057) (xy 1.841509 -0.381058) (xy 1.841508 0.380942) (xy -1.841491 0.380942)
			)
			(stroke
				(width 0)
				(type default)
			)
			(fill no)
			(layer "F.CrtYd")
		)
		(fp_poly
			(pts
				(xy -1.841491 -0.381057) (xy 1.841509 -0.381058) (xy 1.841508 0.380942) (xy -1.841491 0.380942)
			)
			(stroke
				(width 0)
				(type default)
			)
			(fill no)
			(layer "F.Fab")
		)
		(pad "1" thru_hole circle
			(at -1.460499 0 225)
			(size 0.508 0.508)
			(drill 0.254)
			(layers "*.Cu" "*.Mask")
			(remove_unused_layers no)
			(net "GND")
			(clearance 0.127)
			(thermal_gap 0.127)
		)
		(pad "2" thru_hole circle
			(at -0.4445 0 225)
			(size 0.508 0.508)
			(drill 0.254)
			(layers "*.Cu" "*.Mask")
			(remove_unused_layers no)
			(net "PCIE_COMP_TO_IOM_13_DP")
			(clearance 0.127)
			(thermal_gap 0.127)
		)
		(pad "3" thru_hole circle
			(at 0.4445 0 225)
			(size 0.508 0.508)
			(drill 0.254)
			(layers "*.Cu" "*.Mask")
			(remove_unused_layers no)
			(net "PCIE_COMP_TO_IOM_13_DN")
			(clearance 0.127)
			(thermal_gap 0.127)
		)
		(pad "4" thru_hole circle
			(at 1.460499 0 225)
			(size 0.508 0.508)
			(drill 0.254)
			(layers "*.Cu" "*.Mask")
			(remove_unused_layers no)
			(net "GND")
			(clearance 0.127)
			(thermal_gap 0.127)
		)
	)
	(footprint ""
		(layer "F.Cu")
		(at 152.488138 -19.559778 -90)
		(property "Reference" "R512"
			(at 0 0 270)
			(layer "F.SilkS")
			(hide yes)
			(effects
				(font
					(size 1.27 1.27)
				)
			)
		)
		(property "Value" "0R6J-3-GP"
			(at -0.0508 -4.8514 270)
			(unlocked yes)
			(layer "F.Fab")
			(hide yes)
			(effects
				(font
					(size 1.016 1.016)
					(thickness 0.1524)
				)
			)
		)
		(property "Device Type" "R1206H28"
			(at 0 -6.3754 270)
			(unlocked yes)
			(layer "F.Fab")
			(hide yes)
			(effects
				(font
					(size 1.016 1.016)
					(thickness 0.1524)
				)
			)
		)
		(duplicate_pad_numbers_are_jumpers no)
		(fp_line
			(start -1.016 2.2352)
			(end -1.016 -2.2352)
			(stroke
				(width 0.1524)
				(type default)
			)
			(layer "F.SilkS")
		)
		(fp_line
			(start 1.016 2.2352)
			(end -1.016 2.2352)
			(stroke
				(width 0.1524)
				(type default)
			)
			(layer "F.SilkS")
		)
		(fp_line
			(start -1.016 -2.2352)
			(end 1.016 -2.2352)
			(stroke
				(width 0.1524)
				(type default)
			)
			(layer "F.SilkS")
		)
		(fp_line
			(start 1.016 -2.2352)
			(end 1.016 2.2352)
			(stroke
				(width 0.1524)
				(type default)
			)
			(layer "F.SilkS")
		)
		(fp_rect
			(start -1.0922 2.3114)
			(end 1.0922 -2.3114)
			(stroke
				(width 0)
				(type default)
			)
			(fill no)
			(layer "F.CrtYd")
		)
		(fp_poly
			(pts
				(xy -1.0922 -2.3114) (xy 1.0922 -2.3114) (xy 1.0922 2.3114) (xy -1.0922 2.3114)
			)
			(stroke
				(width 0)
				(type default)
			)
			(fill no)
			(layer "F.Fab")
		)
		(pad "1" smd rect
			(at 0 -1.397 270)
			(size 1.651 1.27)
			(layers "F.Cu" "F.Mask" "F.Paste")
			(net "P12V_STBY_VIN_PU4")
		)
		(pad "2" smd rect
			(at 0 1.397 270)
			(size 1.651 1.27)
			(layers "F.Cu" "F.Mask" "F.Paste")
			(net "P12V_STBY")
		)
	)
	(footprint ""
		(layer "F.Cu")
		(at 33.772348 -153.240994 -90)
		(property "Reference" "R319"
			(at 0 0 270)
			(layer "F.SilkS")
			(hide yes)
			(effects
				(font
					(size 1.27 1.27)
				)
			)
		)
		(property "Value" "0R2J-2-GP"
			(at 0.064008 -3.993896 270)
			(unlocked yes)
			(layer "F.Fab")
			(hide yes)
			(effects
				(font
					(size 1.016 1.016)
					(thickness 0.1524)
				)
			)
		)
		(property "Device Type" "R402H16"
			(at 0.064008 -5.517896 270)
			(unlocked yes)
			(layer "F.Fab")
			(hide yes)
			(effects
				(font
					(size 1.016 1.016)
					(thickness 0.1524)
				)
			)
		)
		(duplicate_pad_numbers_are_jumpers no)
		(fp_line
			(start -0.508 -0.9398)
			(end -0.508 0.9398)
			(stroke
				(width 0.1524)
				(type default)
			)
			(layer "F.SilkS")
		)
		(fp_line
			(start 0.508 -0.9398)
			(end -0.508 -0.9398)
			(stroke
				(width 0.1524)
				(type default)
			)
			(layer "F.SilkS")
		)
		(fp_rect
			(start -0.508 0.9398)
			(end 0.508 -0.9398)
			(stroke
				(width 0)
				(type default)
			)
			(fill no)
			(layer "F.CrtYd")
		)
		(fp_rect
			(start -0.508 0.9398)
			(end 0.508 -0.9398)
			(stroke
				(width 0)
				(type default)
			)
			(fill no)
			(layer "F.Fab")
		)
		(pad "1" smd custom
			(at 0 -0.4445 270)
			(size 0.1397 0.1397)
			(layers "F.Cu" "F.Mask" "F.Paste")
			(net "ENCL_FAULT_LED_R")
			(options
				(clearance outline)
				(anchor circle)
			)
			(primitives
				(gr_poly
					(pts
						(arc
							(start -0.1778 -0.2794)
							(mid -0.249642 -0.249642)
							(end -0.2794 -0.1778)
						)
						(arc
							(start -0.2794 0.1778)
							(mid -0.249642 0.249642)
							(end -0.1778 0.2794)
						)
						(arc
							(start 0.1778 0.2794)
							(mid 0.249642 0.249642)
							(end 0.2794 0.1778)
						)
						(arc
							(start 0.2794 -0.1778)
							(mid 0.249642 -0.249642)
							(end 0.1778 -0.2794)
						)
					)
					(width 0)
					(fill yes)
				)
			)
		)
		(pad "2" smd custom
			(at 0 0.4445 270)
			(size 0.1397 0.1397)
			(layers "F.Cu" "F.Mask" "F.Paste")
			(net "ENCL_FAULT_LED")
			(options
				(clearance outline)
				(anchor circle)
			)
			(primitives
				(gr_poly
					(pts
						(arc
							(start -0.1778 -0.2794)
							(mid -0.249642 -0.249642)
							(end -0.2794 -0.1778)
						)
						(arc
							(start -0.2794 0.1778)
							(mid -0.249642 0.249642)
							(end -0.1778 0.2794)
						)
						(arc
							(start 0.1778 0.2794)
							(mid 0.249642 0.249642)
							(end 0.2794 0.1778)
						)
						(arc
							(start 0.2794 -0.1778)
							(mid 0.249642 -0.249642)
							(end 0.1778 -0.2794)
						)
					)
					(width 0)
					(fill yes)
				)
			)
		)
	)
	(footprint ""
		(layer "F.Cu")
		(at 214.903558 -39.096696)
		(property "Reference" "R713"
			(at 0 0 0)
			(layer "F.SilkS")
			(hide yes)
			(effects
				(font
					(size 1.27 1.27)
				)
			)
		)
		(property "Value" "0R2J-2-GP"
			(at 0.064008 -3.993896 0)
			(unlocked yes)
			(layer "F.Fab")
			(hide yes)
			(effects
				(font
					(size 1.016 1.016)
					(thickness 0.1524)
				)
			)
		)
		(property "Device Type" "R402H16"
			(at 0.064008 -5.517896 0)
			(unlocked yes)
			(layer "F.Fab")
			(hide yes)
			(effects
				(font
					(size 1.016 1.016)
					(thickness 0.1524)
				)
			)
		)
		(duplicate_pad_numbers_are_jumpers no)
		(fp_line
			(start -0.508 -0.9398)
			(end -0.508 0.9398)
			(stroke
				(width 0.1524)
				(type default)
			)
			(layer "F.SilkS")
		)
		(fp_line
			(start 0.508 -0.9398)
			(end -0.508 -0.9398)
			(stroke
				(width 0.1524)
				(type default)
			)
			(layer "F.SilkS")
		)
		(fp_rect
			(start -0.508 0.9398)
			(end 0.508 -0.9398)
			(stroke
				(width 0)
				(type default)
			)
			(fill no)
			(layer "F.CrtYd")
		)
		(fp_rect
			(start -0.508 0.9398)
			(end 0.508 -0.9398)
			(stroke
				(width 0)
				(type default)
			)
			(fill no)
			(layer "F.Fab")
		)
		(pad "1" smd custom
			(at 0 -0.4445)
			(size 0.1397 0.1397)
			(layers "F.Cu" "F.Mask" "F.Paste")
			(net "P5V_EN_R")
			(options
				(clearance outline)
				(anchor circle)
			)
			(primitives
				(gr_poly
					(pts
						(arc
							(start -0.1778 -0.2794)
							(mid -0.249642 -0.249642)
							(end -0.2794 -0.1778)
						)
						(arc
							(start -0.2794 0.1778)
							(mid -0.249642 0.249642)
							(end -0.1778 0.2794)
						)
						(arc
							(start 0.1778 0.2794)
							(mid 0.249642 0.249642)
							(end 0.2794 0.1778)
						)
						(arc
							(start 0.2794 -0.1778)
							(mid 0.249642 -0.249642)
							(end 0.1778 -0.2794)
						)
					)
					(width 0)
					(fill yes)
				)
			)
		)
		(pad "2" smd custom
			(at 0 0.4445)
			(size 0.1397 0.1397)
			(layers "F.Cu" "F.Mask" "F.Paste")
			(net "P12V_IOM_PGOOD")
			(options
				(clearance outline)
				(anchor circle)
			)
			(primitives
				(gr_poly
					(pts
						(arc
							(start -0.1778 -0.2794)
							(mid -0.249642 -0.249642)
							(end -0.2794 -0.1778)
						)
						(arc
							(start -0.2794 0.1778)
							(mid -0.249642 0.249642)
							(end -0.1778 0.2794)
						)
						(arc
							(start 0.1778 0.2794)
							(mid 0.249642 0.249642)
							(end 0.2794 0.1778)
						)
						(arc
							(start 0.2794 -0.1778)
							(mid 0.249642 -0.249642)
							(end 0.1778 -0.2794)
						)
					)
					(width 0)
					(fill yes)
				)
			)
		)
	)
	(footprint ""
		(layer "F.Cu")
		(at 98.298 -171.6024 -90)
		(property "Reference" "R724"
			(at 0 0 270)
			(layer "F.SilkS")
			(hide yes)
			(effects
				(font
					(size 1.27 1.27)
				)
			)
		)
		(property "Value" "0R2J-2-GP"
			(at 0.064008 -3.993896 270)
			(unlocked yes)
			(layer "F.Fab")
			(hide yes)
			(effects
				(font
					(size 1.016 1.016)
					(thickness 0.1524)
				)
			)
		)
		(property "Device Type" "R402H16"
			(at 0.064008 -5.517896 270)
			(unlocked yes)
			(layer "F.Fab")
			(hide yes)
			(effects
				(font
					(size 1.016 1.016)
					(thickness 0.1524)
				)
			)
		)
		(duplicate_pad_numbers_are_jumpers no)
		(fp_line
			(start -0.508 -0.9398)
			(end -0.508 0.9398)
			(stroke
				(width 0.1524)
				(type default)
			)
			(layer "F.SilkS")
		)
		(fp_line
			(start 0.508 -0.9398)
			(end -0.508 -0.9398)
			(stroke
				(width 0.1524)
				(type default)
			)
			(layer "F.SilkS")
		)
		(fp_rect
			(start -0.508 0.9398)
			(end 0.508 -0.9398)
			(stroke
				(width 0)
				(type default)
			)
			(fill no)
			(layer "F.CrtYd")
		)
		(fp_rect
			(start -0.508 0.9398)
			(end 0.508 -0.9398)
			(stroke
				(width 0)
				(type default)
			)
			(fill no)
			(layer "F.Fab")
		)
		(pad "1" smd custom
			(at 0 -0.4445 270)
			(size 0.1397 0.1397)
			(layers "F.Cu" "F.Mask" "F.Paste")
			(net "DPB_MISC_ALERT_OUT")
			(options
				(clearance outline)
				(anchor circle)
			)
			(primitives
				(gr_poly
					(pts
						(arc
							(start -0.1778 -0.2794)
							(mid -0.249642 -0.249642)
							(end -0.2794 -0.1778)
						)
						(arc
							(start -0.2794 0.1778)
							(mid -0.249642 0.249642)
							(end -0.1778 0.2794)
						)
						(arc
							(start 0.1778 0.2794)
							(mid 0.249642 0.249642)
							(end 0.2794 0.1778)
						)
						(arc
							(start 0.2794 -0.1778)
							(mid 0.249642 -0.249642)
							(end 0.1778 -0.2794)
						)
					)
					(width 0)
					(fill yes)
				)
			)
		)
		(pad "2" smd custom
			(at 0 0.4445 270)
			(size 0.1397 0.1397)
			(layers "F.Cu" "F.Mask" "F.Paste")
			(net "DPB_MISC_ALERT_OUT_R")
			(options
				(clearance outline)
				(anchor circle)
			)
			(primitives
				(gr_poly
					(pts
						(arc
							(start -0.1778 -0.2794)
							(mid -0.249642 -0.249642)
							(end -0.2794 -0.1778)
						)
						(arc
							(start -0.2794 0.1778)
							(mid -0.249642 0.249642)
							(end -0.1778 0.2794)
						)
						(arc
							(start 0.1778 0.2794)
							(mid 0.249642 0.249642)
							(end 0.2794 0.1778)
						)
						(arc
							(start 0.2794 -0.1778)
							(mid 0.249642 -0.249642)
							(end 0.1778 -0.2794)
						)
					)
					(width 0)
					(fill yes)
				)
			)
		)
	)
	(footprint ""
		(layer "F.Cu")
		(at 44.345352 -124.818902)
		(property "Reference" "R89"
			(at 0 0 0)
			(layer "F.SilkS")
			(hide yes)
			(effects
				(font
					(size 1.27 1.27)
				)
			)
		)
		(property "Value" "33D2R2F-GP"
			(at 0.064008 -3.993896 0)
			(unlocked yes)
			(layer "F.Fab")
			(hide yes)
			(effects
				(font
					(size 1.016 1.016)
					(thickness 0.1524)
				)
			)
		)
		(property "Device Type" "R402H16"
			(at 0.064008 -5.517896 0)
			(unlocked yes)
			(layer "F.Fab")
			(hide yes)
			(effects
				(font
					(size 1.016 1.016)
					(thickness 0.1524)
				)
			)
		)
		(duplicate_pad_numbers_are_jumpers no)
		(fp_line
			(start -0.508 -0.9398)
			(end -0.508 0.9398)
			(stroke
				(width 0.1524)
				(type default)
			)
			(layer "F.SilkS")
		)
		(fp_line
			(start 0.508 -0.9398)
			(end -0.508 -0.9398)
			(stroke
				(width 0.1524)
				(type default)
			)
			(layer "F.SilkS")
		)
		(fp_rect
			(start -0.508 0.9398)
			(end 0.508 -0.9398)
			(stroke
				(width 0)
				(type default)
			)
			(fill no)
			(layer "F.CrtYd")
		)
		(fp_rect
			(start -0.508 0.9398)
			(end 0.508 -0.9398)
			(stroke
				(width 0)
				(type default)
			)
			(fill no)
			(layer "F.Fab")
		)
		(pad "1" smd custom
			(at 0 -0.4445)
			(size 0.1397 0.1397)
			(layers "F.Cu" "F.Mask" "F.Paste")
			(net "BMC_SPI_MISO")
			(options
				(clearance outline)
				(anchor circle)
			)
			(primitives
				(gr_poly
					(pts
						(arc
							(start -0.1778 -0.2794)
							(mid -0.249642 -0.249642)
							(end -0.2794 -0.1778)
						)
						(arc
							(start -0.2794 0.1778)
							(mid -0.249642 0.249642)
							(end -0.1778 0.2794)
						)
						(arc
							(start 0.1778 0.2794)
							(mid 0.249642 0.249642)
							(end 0.2794 0.1778)
						)
						(arc
							(start 0.2794 -0.1778)
							(mid 0.249642 -0.249642)
							(end 0.1778 -0.2794)
						)
					)
					(width 0)
					(fill yes)
				)
			)
		)
		(pad "2" smd custom
			(at 0 0.4445)
			(size 0.1397 0.1397)
			(layers "F.Cu" "F.Mask" "F.Paste")
			(net "BMC_SPI_MISO_TPM")
			(options
				(clearance outline)
				(anchor circle)
			)
			(primitives
				(gr_poly
					(pts
						(arc
							(start -0.1778 -0.2794)
							(mid -0.249642 -0.249642)
							(end -0.2794 -0.1778)
						)
						(arc
							(start -0.2794 0.1778)
							(mid -0.249642 0.249642)
							(end -0.1778 0.2794)
						)
						(arc
							(start 0.1778 0.2794)
							(mid 0.249642 0.249642)
							(end 0.2794 0.1778)
						)
						(arc
							(start 0.2794 -0.1778)
							(mid 0.249642 -0.249642)
							(end 0.1778 -0.2794)
						)
					)
					(width 0)
					(fill yes)
				)
			)
		)
	)
	(footprint ""
		(layer "F.Cu")
		(at 55.530242 -166.076884)
		(property "Reference" "C520"
			(at 0 0 0)
			(layer "F.SilkS")
			(hide yes)
			(effects
				(font
					(size 1.27 1.27)
				)
			)
		)
		(property "Value" "SCD1U25V2KX-2-GP"
			(at 1.1811 -2.7051 0)
			(unlocked yes)
			(layer "F.Fab")
			(hide yes)
			(effects
				(font
					(size 1.016 1.016)
					(thickness 0.1524)
				)
			)
		)
		(property "Device Type" "C402H22"
			(at 1.1811 -4.2291 0)
			(unlocked yes)
			(layer "F.Fab")
			(hide yes)
			(effects
				(font
					(size 1.016 1.016)
					(thickness 0.1524)
				)
			)
		)
		(duplicate_pad_numbers_are_jumpers no)
		(fp_rect
			(start -0.4318 0.9525)
			(end 0.4318 -0.9525)
			(stroke
				(width 0)
				(type default)
			)
			(fill no)
			(layer "F.CrtYd")
		)
		(fp_rect
			(start -0.4318 0.9525)
			(end 0.4318 -0.9525)
			(stroke
				(width 0)
				(type default)
			)
			(fill no)
			(layer "F.Fab")
		)
		(pad "1" smd custom
			(at 0 -0.4445)
			(size 0.1524 0.1524)
			(layers "F.Cu" "F.Mask" "F.Paste")
			(net "ADC_P2V5_STBY")
			(options
				(clearance outline)
				(anchor circle)
			)
			(primitives
				(gr_poly
					(pts
						(arc
							(start 0.3048 -0.2032)
							(mid 0.275042 -0.275042)
							(end 0.2032 -0.3048)
						)
						(arc
							(start -0.2032 -0.3048)
							(mid -0.275042 -0.275042)
							(end -0.3048 -0.2032)
						)
						(arc
							(start -0.3048 0.2032)
							(mid -0.275042 0.275042)
							(end -0.2032 0.3048)
						)
						(arc
							(start 0.2032 0.3048)
							(mid 0.275042 0.275042)
							(end 0.3048 0.2032)
						)
					)
					(width 0)
					(fill yes)
				)
			)
		)
		(pad "2" smd custom
			(at 0 0.4445)
			(size 0.1524 0.1524)
			(layers "F.Cu" "F.Mask" "F.Paste")
			(net "GND")
			(options
				(clearance outline)
				(anchor circle)
			)
			(primitives
				(gr_poly
					(pts
						(arc
							(start 0.3048 -0.2032)
							(mid 0.275042 -0.275042)
							(end 0.2032 -0.3048)
						)
						(arc
							(start -0.2032 -0.3048)
							(mid -0.275042 -0.275042)
							(end -0.3048 -0.2032)
						)
						(arc
							(start -0.3048 0.2032)
							(mid -0.275042 0.275042)
							(end -0.2032 0.3048)
						)
						(arc
							(start 0.2032 0.3048)
							(mid 0.275042 0.275042)
							(end 0.3048 0.2032)
						)
					)
					(width 0)
					(fill yes)
				)
			)
		)
	)
	(footprint ""
		(layer "F.Cu")
		(at 20.034504 -142.561564)
		(property "Reference" "U28"
			(at 0 0 0)
			(layer "F.SilkS")
			(hide yes)
			(effects
				(font
					(size 1.27 1.27)
				)
			)
		)
		(property "Value" "H5AN4G6NAFR-TFC-GP"
			(at -8.423656 -15.9766 0)
			(unlocked yes)
			(layer "F.Fab")
			(hide yes)
			(effects
				(font
					(size 1.016 1.016)
					(thickness 0.1524)
				)
			)
		)
		(property "Device Type" "BGA96D075130H48"
			(at -8.423656 -17.5006 0)
			(unlocked yes)
			(layer "F.Fab")
			(hide yes)
			(effects
				(font
					(size 1.016 1.016)
					(thickness 0.1524)
				)
			)
		)
		(duplicate_pad_numbers_are_jumpers no)
		(fp_line
			(start -4.080256 -6.830314)
			(end -2.480056 -6.830314)
			(stroke
				(width 0.508)
				(type default)
			)
			(layer "F.SilkS")
		)
		(fp_line
			(start -4.080256 -5.230114)
			(end -4.080256 -6.830314)
			(stroke
				(width 0.508)
				(type default)
			)
			(layer "F.SilkS")
		)
		(fp_line
			(start -3.750056 -6.500114)
			(end -3.750056 6.500114)
			(stroke
				(width 0.1524)
				(type default)
			)
			(layer "F.SilkS")
		)
		(fp_line
			(start -3.750056 6.500114)
			(end 3.750056 6.500114)
			(stroke
				(width 0.1524)
				(type default)
			)
			(layer "F.SilkS")
		)
		(fp_line
			(start 3.750056 -6.500114)
			(end -3.750056 -6.500114)
			(stroke
				(width 0.1524)
				(type default)
			)
			(layer "F.SilkS")
		)
		(fp_line
			(start 3.750056 6.500114)
			(end 3.750056 -6.500114)
			(stroke
				(width 0.1524)
				(type default)
			)
			(layer "F.SilkS")
		)
		(fp_rect
			(start -3.750056 6.500114)
			(end 3.750056 -6.500114)
			(stroke
				(width 0)
				(type default)
			)
			(fill no)
			(layer "F.CrtYd")
		)
		(fp_poly
			(pts
				(xy -4.7498 7.5057) (xy -4.7498 -7.5057) (xy 4.7498 -7.5057) (xy 4.7498 -0.54864) (xy 3.750056 -0.54864)
				(xy 3.750056 -6.500114) (xy -3.750056 -6.500114) (xy -3.750056 6.500114) (xy 3.750056 6.500114)
				(xy 3.750056 -0.54356) (xy 4.7498 -0.54356) (xy 4.7498 7.5057)
			)
			(stroke
				(width 0)
				(type default)
			)
			(fill no)
			(layer "F.CrtYd")
		)
		(fp_rect
			(start -5.750052 8.50011)
			(end 5.750052 -8.50011)
			(stroke
				(width 0)
				(type default)
			)
			(fill no)
			(layer "F.Fab")
		)
		(pad "A1" smd circle
			(at -3.199892 -5.999988)
			(size 0.3556 0.3556)
			(layers "F.Cu" "F.Mask" "F.Paste")
			(net "P1V2_STBY")
		)
		(pad "A2" smd circle
			(at -2.400046 -5.999988)
			(size 0.3556 0.3556)
			(layers "F.Cu" "F.Mask" "F.Paste")
			(net "GND")
		)
		(pad "A3" smd circle
			(at -1.599946 -5.999988)
			(size 0.3556 0.3556)
			(layers "F.Cu" "F.Mask" "F.Paste")
			(net "MEMDQ_8")
		)
		(pad "A7" smd circle
			(at 1.599946 -5.999988)
			(size 0.3556 0.3556)
			(layers "F.Cu" "F.Mask" "F.Paste")
			(net "MEMDQS_N1")
		)
		(pad "A8" smd circle
			(at 2.400046 -5.999988)
			(size 0.3556 0.3556)
			(layers "F.Cu" "F.Mask" "F.Paste")
			(net "GND")
		)
		(pad "A9" smd circle
			(at 3.199892 -5.999988)
			(size 0.3556 0.3556)
			(layers "F.Cu" "F.Mask" "F.Paste")
			(net "P1V2_STBY")
		)
		(pad "B1" smd circle
			(at -3.199892 -5.199888)
			(size 0.3556 0.3556)
			(layers "F.Cu" "F.Mask" "F.Paste")
			(net "P2V5_STBY")
		)
		(pad "B2" smd circle
			(at -2.400046 -5.199888)
			(size 0.3556 0.3556)
			(layers "F.Cu" "F.Mask" "F.Paste")
			(net "GND")
		)
		(pad "B3" smd circle
			(at -1.599946 -5.199888)
			(size 0.3556 0.3556)
			(layers "F.Cu" "F.Mask" "F.Paste")
			(net "P1V2_STBY")
		)
		(pad "B7" smd circle
			(at 1.599946 -5.199888)
			(size 0.3556 0.3556)
			(layers "F.Cu" "F.Mask" "F.Paste")
			(net "MEMDQS_P1")
		)
		(pad "B8" smd circle
			(at 2.400046 -5.199888)
			(size 0.3556 0.3556)
			(layers "F.Cu" "F.Mask" "F.Paste")
			(net "MEMDQ_9")
		)
		(pad "B9" smd circle
			(at 3.199892 -5.199888)
			(size 0.3556 0.3556)
			(layers "F.Cu" "F.Mask" "F.Paste")
			(net "P1V2_STBY")
		)
		(pad "C1" smd circle
			(at -3.199892 -4.400042)
			(size 0.3556 0.3556)
			(layers "F.Cu" "F.Mask" "F.Paste")
			(net "P1V2_STBY")
		)
		(pad "C2" smd circle
			(at -2.400046 -4.400042)
			(size 0.3556 0.3556)
			(layers "F.Cu" "F.Mask" "F.Paste")
			(net "MEMDQ_12")
		)
		(pad "C3" smd circle
			(at -1.599946 -4.400042)
			(size 0.3556 0.3556)
			(layers "F.Cu" "F.Mask" "F.Paste")
			(net "MEMDQ_10")
		)
		(pad "C7" smd circle
			(at 1.599946 -4.400042)
			(size 0.3556 0.3556)
			(layers "F.Cu" "F.Mask" "F.Paste")
			(net "MEMDQ_11")
		)
		(pad "C8" smd circle
			(at 2.400046 -4.400042)
			(size 0.3556 0.3556)
			(layers "F.Cu" "F.Mask" "F.Paste")
			(net "MEMDQ_13")
		)
		(pad "C9" smd circle
			(at 3.199892 -4.400042)
			(size 0.3556 0.3556)
			(layers "F.Cu" "F.Mask" "F.Paste")
			(net "GND")
		)
		(pad "D1" smd circle
			(at -3.199892 -3.599942)
			(size 0.3556 0.3556)
			(layers "F.Cu" "F.Mask" "F.Paste")
			(net "P1V2_STBY")
		)
		(pad "D2" smd circle
			(at -2.400046 -3.599942)
			(size 0.3556 0.3556)
			(layers "F.Cu" "F.Mask" "F.Paste")
			(net "GND")
		)
		(pad "D3" smd circle
			(at -1.599946 -3.599942)
			(size 0.3556 0.3556)
			(layers "F.Cu" "F.Mask" "F.Paste")
			(net "MEMDQ_14")
		)
		(pad "D7" smd circle
			(at 1.599946 -3.599942)
			(size 0.3556 0.3556)
			(layers "F.Cu" "F.Mask" "F.Paste")
			(net "MEMDQ_15")
		)
		(pad "D8" smd circle
			(at 2.400046 -3.599942)
			(size 0.3556 0.3556)
			(layers "F.Cu" "F.Mask" "F.Paste")
			(net "GND")
		)
		(pad "D9" smd circle
			(at 3.199892 -3.599942)
			(size 0.3556 0.3556)
			(layers "F.Cu" "F.Mask" "F.Paste")
			(net "P1V2_STBY")
		)
		(pad "E1" smd circle
			(at -3.199892 -2.800096)
			(size 0.3556 0.3556)
			(layers "F.Cu" "F.Mask" "F.Paste")
			(net "GND")
		)
		(pad "E2" smd circle
			(at -2.400046 -2.800096)
			(size 0.3556 0.3556)
			(layers "F.Cu" "F.Mask" "F.Paste")
			(net "MEMDM_1")
		)
		(pad "E3" smd circle
			(at -1.599946 -2.800096)
			(size 0.3556 0.3556)
			(layers "F.Cu" "F.Mask" "F.Paste")
			(net "GND")
		)
		(pad "E7" smd circle
			(at 1.599946 -2.800096)
			(size 0.3556 0.3556)
			(layers "F.Cu" "F.Mask" "F.Paste")
			(net "MEMDM_0")
		)
		(pad "E8" smd circle
			(at 2.400046 -2.800096)
			(size 0.3556 0.3556)
			(layers "F.Cu" "F.Mask" "F.Paste")
			(net "GND")
		)
		(pad "E9" smd circle
			(at 3.199892 -2.800096)
			(size 0.3556 0.3556)
			(layers "F.Cu" "F.Mask" "F.Paste")
			(net "GND")
		)
		(pad "F1" smd circle
			(at -3.199892 -1.999996)
			(size 0.3556 0.3556)
			(layers "F.Cu" "F.Mask" "F.Paste")
			(net "GND")
		)
		(pad "F2" smd circle
			(at -2.400046 -1.999996)
			(size 0.3556 0.3556)
			(layers "F.Cu" "F.Mask" "F.Paste")
			(net "P1V2_STBY")
		)
		(pad "F3" smd circle
			(at -1.599946 -1.999996)
			(size 0.3556 0.3556)
			(layers "F.Cu" "F.Mask" "F.Paste")
			(net "MEMDQS_N0")
		)
		(pad "F7" smd circle
			(at 1.599946 -1.999996)
			(size 0.3556 0.3556)
			(layers "F.Cu" "F.Mask" "F.Paste")
			(net "MEMDQ_1")
		)
		(pad "F8" smd circle
			(at 2.400046 -1.999996)
			(size 0.3556 0.3556)
			(layers "F.Cu" "F.Mask" "F.Paste")
			(net "P1V2_STBY")
		)
		(pad "F9" smd circle
			(at 3.199892 -1.999996)
			(size 0.3556 0.3556)
			(layers "F.Cu" "F.Mask" "F.Paste")
			(net "PD_ZQ")
		)
		(pad "G1" smd circle
			(at -3.199892 -1.199896)
			(size 0.3556 0.3556)
			(layers "F.Cu" "F.Mask" "F.Paste")
			(net "P1V2_STBY")
		)
		(pad "G2" smd circle
			(at -2.400046 -1.199896)
			(size 0.3556 0.3556)
			(layers "F.Cu" "F.Mask" "F.Paste")
			(net "MEMDQ_0")
		)
		(pad "G3" smd circle
			(at -1.599946 -1.199896)
			(size 0.3556 0.3556)
			(layers "F.Cu" "F.Mask" "F.Paste")
			(net "MEMDQS_P0")
		)
		(pad "G7" smd circle
			(at 1.599946 -1.199896)
			(size 0.3556 0.3556)
			(layers "F.Cu" "F.Mask" "F.Paste")
			(net "P1V2_STBY")
		)
		(pad "G8" smd circle
			(at 2.400046 -1.199896)
			(size 0.3556 0.3556)
			(layers "F.Cu" "F.Mask" "F.Paste")
			(net "GND")
		)
		(pad "G9" smd circle
			(at 3.199892 -1.199896)
			(size 0.3556 0.3556)
			(layers "F.Cu" "F.Mask" "F.Paste")
			(net "P1V2_STBY")
		)
		(pad "H1" smd circle
			(at -3.199892 -0.40005)
			(size 0.3556 0.3556)
			(layers "F.Cu" "F.Mask" "F.Paste")
			(net "GND")
		)
		(pad "H2" smd circle
			(at -2.400046 -0.40005)
			(size 0.3556 0.3556)
			(layers "F.Cu" "F.Mask" "F.Paste")
			(net "MEMDQ_4")
		)
		(pad "H3" smd circle
			(at -1.599946 -0.40005)
			(size 0.3556 0.3556)
			(layers "F.Cu" "F.Mask" "F.Paste")
			(net "MEMDQ_2")
		)
		(pad "H7" smd circle
			(at 1.599946 -0.40005)
			(size 0.3556 0.3556)
			(layers "F.Cu" "F.Mask" "F.Paste")
			(net "MEMDQ_3")
		)
		(pad "H8" smd circle
			(at 2.400046 -0.40005)
			(size 0.3556 0.3556)
			(layers "F.Cu" "F.Mask" "F.Paste")
			(net "MEMDQ_5")
		)
		(pad "H9" smd circle
			(at 3.199892 -0.40005)
			(size 0.3556 0.3556)
			(layers "F.Cu" "F.Mask" "F.Paste")
			(net "GND")
		)
		(pad "J1" smd circle
			(at -3.199892 0.40005)
			(size 0.3556 0.3556)
			(layers "F.Cu" "F.Mask" "F.Paste")
			(net "P1V2_STBY")
		)
		(pad "J2" smd circle
			(at -2.400046 0.40005)
			(size 0.3556 0.3556)
			(layers "F.Cu" "F.Mask" "F.Paste")
			(net "P1V2_STBY")
		)
		(pad "J3" smd circle
			(at -1.599946 0.40005)
			(size 0.3556 0.3556)
			(layers "F.Cu" "F.Mask" "F.Paste")
			(net "MEMDQ_6")
		)
		(pad "J7" smd circle
			(at 1.599946 0.40005)
			(size 0.3556 0.3556)
			(layers "F.Cu" "F.Mask" "F.Paste")
			(net "MEMDQ_7")
		)
		(pad "J8" smd circle
			(at 2.400046 0.40005)
			(size 0.3556 0.3556)
			(layers "F.Cu" "F.Mask" "F.Paste")
			(net "P1V2_STBY")
		)
		(pad "J9" smd circle
			(at 3.199892 0.40005)
			(size 0.3556 0.3556)
			(layers "F.Cu" "F.Mask" "F.Paste")
			(net "P1V2_STBY")
		)
		(pad "K1" smd circle
			(at -3.199892 1.199896)
			(size 0.3556 0.3556)
			(layers "F.Cu" "F.Mask" "F.Paste")
			(net "GND")
		)
		(pad "K2" smd circle
			(at -2.400046 1.199896)
			(size 0.3556 0.3556)
			(layers "F.Cu" "F.Mask" "F.Paste")
			(net "MEMCKE")
		)
		(pad "K3" smd circle
			(at -1.599946 1.199896)
			(size 0.3556 0.3556)
			(layers "F.Cu" "F.Mask" "F.Paste")
			(net "MEMODT")
		)
		(pad "K7" smd circle
			(at 1.599946 1.199896)
			(size 0.3556 0.3556)
			(layers "F.Cu" "F.Mask" "F.Paste")
			(net "MEMCK_P")
		)
		(pad "K8" smd circle
			(at 2.400046 1.199896)
			(size 0.3556 0.3556)
			(layers "F.Cu" "F.Mask" "F.Paste")
			(net "MEMCK_N")
		)
		(pad "K9" smd circle
			(at 3.199892 1.199896)
			(size 0.3556 0.3556)
			(layers "F.Cu" "F.Mask" "F.Paste")
			(net "GND")
		)
		(pad "L1" smd circle
			(at -3.199892 1.999996)
			(size 0.3556 0.3556)
			(layers "F.Cu" "F.Mask" "F.Paste")
			(net "P1V2_STBY")
		)
		(pad "L2" smd circle
			(at -2.400046 1.999996)
			(size 0.3556 0.3556)
			(layers "F.Cu" "F.Mask" "F.Paste")
			(net "MEMWEN")
		)
		(pad "L3" smd circle
			(at -1.599946 1.999996)
			(size 0.3556 0.3556)
			(layers "F.Cu" "F.Mask" "F.Paste")
			(net "DDR4_ACT")
		)
		(pad "L7" smd circle
			(at 1.599946 1.999996)
			(size 0.3556 0.3556)
			(layers "F.Cu" "F.Mask" "F.Paste")
			(net "MEMCSN")
		)
		(pad "L8" smd circle
			(at 2.400046 1.999996)
			(size 0.3556 0.3556)
			(layers "F.Cu" "F.Mask" "F.Paste")
			(net "MEMRASN")
		)
		(pad "L9" smd circle
			(at 3.199892 1.999996)
			(size 0.3556 0.3556)
			(layers "F.Cu" "F.Mask" "F.Paste")
			(net "P1V2_STBY")
		)
		(pad "M1" smd circle
			(at -3.199892 2.800096)
			(size 0.3556 0.3556)
			(layers "F.Cu" "F.Mask" "F.Paste")
			(net "DDR_VREF")
		)
		(pad "M2" smd circle
			(at -2.400046 2.800096)
			(size 0.3556 0.3556)
			(layers "F.Cu" "F.Mask" "F.Paste")
			(net "MEMBG_0")
		)
		(pad "M3" smd circle
			(at -1.599946 2.800096)
			(size 0.3556 0.3556)
			(layers "F.Cu" "F.Mask" "F.Paste")
			(net "MEMA_10")
		)
		(pad "M7" smd circle
			(at 1.599946 2.800096)
			(size 0.3556 0.3556)
			(layers "F.Cu" "F.Mask" "F.Paste")
			(net "MEMA_12")
		)
		(pad "M8" smd circle
			(at 2.400046 2.800096)
			(size 0.3556 0.3556)
			(layers "F.Cu" "F.Mask" "F.Paste")
			(net "MEMCASN")
		)
		(pad "M9" smd circle
			(at 3.199892 2.800096)
			(size 0.3556 0.3556)
			(layers "F.Cu" "F.Mask" "F.Paste")
			(net "GND")
		)
		(pad "N1" smd circle
			(at -3.199892 3.599942)
			(size 0.3556 0.3556)
			(layers "F.Cu" "F.Mask" "F.Paste")
			(net "GND")
		)
		(pad "N2" smd circle
			(at -2.400046 3.599942)
			(size 0.3556 0.3556)
			(layers "F.Cu" "F.Mask" "F.Paste")
			(net "MEMBA_0")
		)
		(pad "N3" smd circle
			(at -1.599946 3.599942)
			(size 0.3556 0.3556)
			(layers "F.Cu" "F.Mask" "F.Paste")
			(net "MEMA_4")
		)
		(pad "N7" smd circle
			(at 1.599946 3.599942)
			(size 0.3556 0.3556)
			(layers "F.Cu" "F.Mask" "F.Paste")
			(net "MEMA_3")
		)
		(pad "N8" smd circle
			(at 2.400046 3.599942)
			(size 0.3556 0.3556)
			(layers "F.Cu" "F.Mask" "F.Paste")
			(net "MEMBA_1")
		)
		(pad "N9" smd circle
			(at 3.199892 3.599942)
			(size 0.3556 0.3556)
			(layers "F.Cu" "F.Mask" "F.Paste")
			(net "GND")
		)
		(pad "P1" smd circle
			(at -3.199892 4.400042)
			(size 0.3556 0.3556)
			(layers "F.Cu" "F.Mask" "F.Paste")
			(net "DDR4_RST_N")
		)
		(pad "P2" smd circle
			(at -2.400046 4.400042)
			(size 0.3556 0.3556)
			(layers "F.Cu" "F.Mask" "F.Paste")
			(net "MEMA_6")
		)
		(pad "P3" smd circle
			(at -1.599946 4.400042)
			(size 0.3556 0.3556)
			(layers "F.Cu" "F.Mask" "F.Paste")
			(net "MEMA_0")
		)
		(pad "P7" smd circle
			(at 1.599946 4.400042)
			(size 0.3556 0.3556)
			(layers "F.Cu" "F.Mask" "F.Paste")
			(net "MEMA_1")
		)
		(pad "P8" smd circle
			(at 2.400046 4.400042)
			(size 0.3556 0.3556)
			(layers "F.Cu" "F.Mask" "F.Paste")
			(net "MEMA_5")
		)
		(pad "P9" smd circle
			(at 3.199892 4.400042)
			(size 0.3556 0.3556)
			(layers "F.Cu" "F.Mask" "F.Paste")
			(net "DDR4_ALERT")
		)
		(pad "R1" smd circle
			(at -3.199892 5.199888)
			(size 0.3556 0.3556)
			(layers "F.Cu" "F.Mask" "F.Paste")
			(net "P1V2_STBY")
		)
		(pad "R2" smd circle
			(at -2.400046 5.199888)
			(size 0.3556 0.3556)
			(layers "F.Cu" "F.Mask" "F.Paste")
			(net "MEMA_8")
		)
		(pad "R3" smd circle
			(at -1.599946 5.199888)
			(size 0.3556 0.3556)
			(layers "F.Cu" "F.Mask" "F.Paste")
			(net "MEMA_2")
		)
		(pad "R7" smd circle
			(at 1.599946 5.199888)
			(size 0.3556 0.3556)
			(layers "F.Cu" "F.Mask" "F.Paste")
			(net "MEMA_9")
		)
		(pad "R8" smd circle
			(at 2.400046 5.199888)
			(size 0.3556 0.3556)
			(layers "F.Cu" "F.Mask" "F.Paste")
			(net "MEMA_7")
		)
		(pad "R9" smd circle
			(at 3.199892 5.199888)
			(size 0.3556 0.3556)
			(layers "F.Cu" "F.Mask" "F.Paste")
			(net "P2V5_STBY")
		)
		(pad "T1" smd circle
			(at -3.199892 5.999988)
			(size 0.3556 0.3556)
			(layers "F.Cu" "F.Mask" "F.Paste")
			(net "GND")
		)
		(pad "T2" smd circle
			(at -2.400046 5.999988)
			(size 0.3556 0.3556)
			(layers "F.Cu" "F.Mask" "F.Paste")
			(net "MEMA_11")
		)
		(pad "T3" smd circle
			(at -1.599946 5.999988)
			(size 0.3556 0.3556)
			(layers "F.Cu" "F.Mask" "F.Paste")
			(net "MEM_PAR")
		)
		(pad "T7" smd circle
			(at 1.599946 5.999988)
			(size 0.3556 0.3556)
			(layers "F.Cu" "F.Mask" "F.Paste")
			(net "Net_542")
		)
		(pad "T8" smd circle
			(at 2.400046 5.999988)
			(size 0.3556 0.3556)
			(layers "F.Cu" "F.Mask" "F.Paste")
			(net "MEMA_13")
		)
		(pad "T9" smd circle
			(at 3.199892 5.999988)
			(size 0.3556 0.3556)
			(layers "F.Cu" "F.Mask" "F.Paste")
			(net "P1V2_STBY")
		)
	)
	(footprint ""
		(layer "F.Cu")
		(at 43.623738 -179.49545)
		(property "Reference" "C181"
			(at 0 0 0)
			(layer "F.SilkS")
			(hide yes)
			(effects
				(font
					(size 1.27 1.27)
				)
			)
		)
		(property "Value" "SCD1U25V2KX-2-GP"
			(at 1.1811 -2.7051 0)
			(unlocked yes)
			(layer "F.Fab")
			(hide yes)
			(effects
				(font
					(size 1.016 1.016)
					(thickness 0.1524)
				)
			)
		)
		(property "Device Type" "C402H22"
			(at 1.1811 -4.2291 0)
			(unlocked yes)
			(layer "F.Fab")
			(hide yes)
			(effects
				(font
					(size 1.016 1.016)
					(thickness 0.1524)
				)
			)
		)
		(duplicate_pad_numbers_are_jumpers no)
		(fp_rect
			(start -0.4318 0.9525)
			(end 0.4318 -0.9525)
			(stroke
				(width 0)
				(type default)
			)
			(fill no)
			(layer "F.CrtYd")
		)
		(fp_rect
			(start -0.4318 0.9525)
			(end 0.4318 -0.9525)
			(stroke
				(width 0)
				(type default)
			)
			(fill no)
			(layer "F.Fab")
		)
		(pad "1" smd custom
			(at 0 -0.4445)
			(size 0.1524 0.1524)
			(layers "F.Cu" "F.Mask" "F.Paste")
			(net "P3V3_STBY_OUT")
			(options
				(clearance outline)
				(anchor circle)
			)
			(primitives
				(gr_poly
					(pts
						(arc
							(start 0.3048 -0.2032)
							(mid 0.275042 -0.275042)
							(end 0.2032 -0.3048)
						)
						(arc
							(start -0.2032 -0.3048)
							(mid -0.275042 -0.275042)
							(end -0.3048 -0.2032)
						)
						(arc
							(start -0.3048 0.2032)
							(mid -0.275042 0.275042)
							(end -0.2032 0.3048)
						)
						(arc
							(start 0.2032 0.3048)
							(mid 0.275042 0.275042)
							(end 0.3048 0.2032)
						)
					)
					(width 0)
					(fill yes)
				)
			)
		)
		(pad "2" smd custom
			(at 0 0.4445)
			(size 0.1524 0.1524)
			(layers "F.Cu" "F.Mask" "F.Paste")
			(net "P3V3_STBY_LL_R")
			(options
				(clearance outline)
				(anchor circle)
			)
			(primitives
				(gr_poly
					(pts
						(arc
							(start 0.3048 -0.2032)
							(mid 0.275042 -0.275042)
							(end 0.2032 -0.3048)
						)
						(arc
							(start -0.2032 -0.3048)
							(mid -0.275042 -0.275042)
							(end -0.3048 -0.2032)
						)
						(arc
							(start -0.3048 0.2032)
							(mid -0.275042 0.275042)
							(end -0.2032 0.3048)
						)
						(arc
							(start 0.2032 0.3048)
							(mid 0.275042 0.275042)
							(end 0.3048 0.2032)
						)
					)
					(width 0)
					(fill yes)
				)
			)
		)
	)
	(footprint ""
		(layer "F.Cu")
		(at 32.6898 -135.7884 90)
		(property "Reference" "R283"
			(at 0 0 90)
			(layer "F.SilkS")
			(hide yes)
			(effects
				(font
					(size 1.27 1.27)
				)
			)
		)
		(property "Value" "33R2F-3-GP"
			(at 0.064008 -3.993896 90)
			(unlocked yes)
			(layer "F.Fab")
			(hide yes)
			(effects
				(font
					(size 1.016 1.016)
					(thickness 0.1524)
				)
			)
		)
		(property "Device Type" "R402H16"
			(at 0.064008 -5.517896 90)
			(unlocked yes)
			(layer "F.Fab")
			(hide yes)
			(effects
				(font
					(size 1.016 1.016)
					(thickness 0.1524)
				)
			)
		)
		(duplicate_pad_numbers_are_jumpers no)
		(fp_line
			(start 0.508 -0.9398)
			(end -0.508 -0.9398)
			(stroke
				(width 0.1524)
				(type default)
			)
			(layer "F.SilkS")
		)
		(fp_line
			(start -0.508 -0.9398)
			(end -0.508 0.9398)
			(stroke
				(width 0.1524)
				(type default)
			)
			(layer "F.SilkS")
		)
		(fp_rect
			(start -0.508 0.9398)
			(end 0.508 -0.9398)
			(stroke
				(width 0)
				(type default)
			)
			(fill no)
			(layer "F.CrtYd")
		)
		(fp_rect
			(start -0.508 0.9398)
			(end 0.508 -0.9398)
			(stroke
				(width 0)
				(type default)
			)
			(fill no)
			(layer "F.Fab")
		)
		(pad "1" smd custom
			(at 0 -0.4445 90)
			(size 0.1397 0.1397)
			(layers "F.Cu" "F.Mask" "F.Paste")
			(net "BMC_SPI_CLK_R")
			(options
				(clearance outline)
				(anchor circle)
			)
			(primitives
				(gr_poly
					(pts
						(arc
							(start -0.1778 -0.2794)
							(mid -0.249642 -0.249642)
							(end -0.2794 -0.1778)
						)
						(arc
							(start -0.2794 0.1778)
							(mid -0.249642 0.249642)
							(end -0.1778 0.2794)
						)
						(arc
							(start 0.1778 0.2794)
							(mid 0.249642 0.249642)
							(end 0.2794 0.1778)
						)
						(arc
							(start 0.2794 -0.1778)
							(mid 0.249642 -0.249642)
							(end 0.1778 -0.2794)
						)
					)
					(width 0)
					(fill yes)
				)
			)
		)
		(pad "2" smd custom
			(at 0 0.4445 90)
			(size 0.1397 0.1397)
			(layers "F.Cu" "F.Mask" "F.Paste")
			(net "BMC_SPI_CLK")
			(options
				(clearance outline)
				(anchor circle)
			)
			(primitives
				(gr_poly
					(pts
						(arc
							(start -0.1778 -0.2794)
							(mid -0.249642 -0.249642)
							(end -0.2794 -0.1778)
						)
						(arc
							(start -0.2794 0.1778)
							(mid -0.249642 0.249642)
							(end -0.1778 0.2794)
						)
						(arc
							(start 0.1778 0.2794)
							(mid 0.249642 0.249642)
							(end 0.2794 0.1778)
						)
						(arc
							(start 0.2794 -0.1778)
							(mid 0.249642 -0.249642)
							(end 0.1778 -0.2794)
						)
					)
					(width 0)
					(fill yes)
				)
			)
		)
	)
	(footprint ""
		(layer "F.Cu")
		(at 66.71183 -179.45989 180)
		(property "Reference" "R82"
			(at 0 0 180)
			(layer "F.SilkS")
			(hide yes)
			(effects
				(font
					(size 1.27 1.27)
				)
			)
		)
		(property "Value" "10KR2F-2-GP"
			(at 0.064008 -3.993896 180)
			(unlocked yes)
			(layer "F.Fab")
			(hide yes)
			(effects
				(font
					(size 1.016 1.016)
					(thickness 0.1524)
				)
			)
		)
		(property "Device Type" "R402H16"
			(at 0.064008 -5.517896 180)
			(unlocked yes)
			(layer "F.Fab")
			(hide yes)
			(effects
				(font
					(size 1.016 1.016)
					(thickness 0.1524)
				)
			)
		)
		(duplicate_pad_numbers_are_jumpers no)
		(fp_line
			(start 0.508 -0.9398)
			(end -0.508 -0.9398)
			(stroke
				(width 0.1524)
				(type default)
			)
			(layer "F.SilkS")
		)
		(fp_line
			(start -0.508 -0.9398)
			(end -0.508 0.9398)
			(stroke
				(width 0.1524)
				(type default)
			)
			(layer "F.SilkS")
		)
		(fp_rect
			(start -0.508 0.9398)
			(end 0.508 -0.9398)
			(stroke
				(width 0)
				(type default)
			)
			(fill no)
			(layer "F.CrtYd")
		)
		(fp_rect
			(start -0.508 0.9398)
			(end 0.508 -0.9398)
			(stroke
				(width 0)
				(type default)
			)
			(fill no)
			(layer "F.Fab")
		)
		(pad "1" smd custom
			(at 0 -0.4445 180)
			(size 0.1397 0.1397)
			(layers "F.Cu" "F.Mask" "F.Paste")
			(net "VREF_2V2")
			(options
				(clearance outline)
				(anchor circle)
			)
			(primitives
				(gr_poly
					(pts
						(arc
							(start -0.1778 -0.2794)
							(mid -0.249642 -0.249642)
							(end -0.2794 -0.1778)
						)
						(arc
							(start -0.2794 0.1778)
							(mid -0.249642 0.249642)
							(end -0.1778 0.2794)
						)
						(arc
							(start 0.1778 0.2794)
							(mid 0.249642 0.249642)
							(end 0.2794 0.1778)
						)
						(arc
							(start 0.2794 -0.1778)
							(mid 0.249642 -0.249642)
							(end 0.1778 -0.2794)
						)
					)
					(width 0)
					(fill yes)
				)
			)
		)
		(pad "2" smd custom
			(at 0 0.4445 180)
			(size 0.1397 0.1397)
			(layers "F.Cu" "F.Mask" "F.Paste")
			(net "GND")
			(options
				(clearance outline)
				(anchor circle)
			)
			(primitives
				(gr_poly
					(pts
						(arc
							(start -0.1778 -0.2794)
							(mid -0.249642 -0.249642)
							(end -0.2794 -0.1778)
						)
						(arc
							(start -0.2794 0.1778)
							(mid -0.249642 0.249642)
							(end -0.1778 0.2794)
						)
						(arc
							(start 0.1778 0.2794)
							(mid 0.249642 0.249642)
							(end 0.2794 0.1778)
						)
						(arc
							(start 0.2794 -0.1778)
							(mid 0.249642 -0.249642)
							(end 0.1778 -0.2794)
						)
					)
					(width 0)
					(fill yes)
				)
			)
		)
	)
	(footprint ""
		(layer "F.Cu")
		(at 82.94116 -155.321 90)
		(property "Reference" "C236"
			(at 0 0 90)
			(layer "F.SilkS")
			(hide yes)
			(effects
				(font
					(size 1.27 1.27)
				)
			)
		)
		(property "Value" "SC10U6D3V5KX-4GP"
			(at -0.0762 -6.1214 90)
			(unlocked yes)
			(layer "F.Fab")
			(hide yes)
			(effects
				(font
					(size 1.016 1.016)
					(thickness 0.1524)
				)
			)
		)
		(property "Device Type" "C805H58"
			(at -0.0762 -8.1534 90)
			(unlocked yes)
			(layer "F.Fab")
			(hide yes)
			(effects
				(font
					(size 1.016 1.016)
					(thickness 0.1524)
				)
			)
		)
		(duplicate_pad_numbers_are_jumpers no)
		(fp_line
			(start 0.635 0)
			(end -0.635 0)
			(stroke
				(width 0.508)
				(type default)
			)
			(layer "F.SilkS")
		)
		(fp_rect
			(start -0.9652 1.778)
			(end 0.9652 -1.778)
			(stroke
				(width 0)
				(type default)
			)
			(fill no)
			(layer "F.CrtYd")
		)
		(fp_poly
			(pts
				(xy -0.9652 -1.778) (xy 0.9652 -1.778) (xy 0.9652 1.778) (xy -0.9652 1.778)
			)
			(stroke
				(width 0)
				(type default)
			)
			(fill no)
			(layer "F.Fab")
		)
		(pad "1" smd rect
			(at 0 -0.9652 90)
			(size 1.397 1.143)
			(layers "F.Cu" "F.Mask" "F.Paste")
			(net "TPS74801_P1V15_STBY_OUT")
		)
		(pad "2" smd rect
			(at 0 0.9652 90)
			(size 1.397 1.143)
			(layers "F.Cu" "F.Mask" "F.Paste")
			(net "GND")
		)
	)
	(footprint ""
		(layer "F.Cu")
		(at 27.419046 -155.464256 -90)
		(property "Reference" "R772"
			(at 0 0 270)
			(layer "F.SilkS")
			(hide yes)
			(effects
				(font
					(size 1.27 1.27)
				)
			)
		)
		(property "Value" "0R2J-2-GP"
			(at 0.064008 -3.993896 270)
			(unlocked yes)
			(layer "F.Fab")
			(hide yes)
			(effects
				(font
					(size 1.016 1.016)
					(thickness 0.1524)
				)
			)
		)
		(property "Device Type" "R402H16"
			(at 0.064008 -5.517896 270)
			(unlocked yes)
			(layer "F.Fab")
			(hide yes)
			(effects
				(font
					(size 1.016 1.016)
					(thickness 0.1524)
				)
			)
		)
		(duplicate_pad_numbers_are_jumpers no)
		(fp_line
			(start -0.508 -0.9398)
			(end -0.508 0.9398)
			(stroke
				(width 0.1524)
				(type default)
			)
			(layer "F.SilkS")
		)
		(fp_line
			(start 0.508 -0.9398)
			(end -0.508 -0.9398)
			(stroke
				(width 0.1524)
				(type default)
			)
			(layer "F.SilkS")
		)
		(fp_rect
			(start -0.508 0.9398)
			(end 0.508 -0.9398)
			(stroke
				(width 0)
				(type default)
			)
			(fill no)
			(layer "F.CrtYd")
		)
		(fp_rect
			(start -0.508 0.9398)
			(end 0.508 -0.9398)
			(stroke
				(width 0)
				(type default)
			)
			(fill no)
			(layer "F.Fab")
		)
		(pad "1" smd custom
			(at 0 -0.4445 270)
			(size 0.1397 0.1397)
			(layers "F.Cu" "F.Mask" "F.Paste")
			(net "DEBUG_GPIO_BMC_R_5")
			(options
				(clearance outline)
				(anchor circle)
			)
			(primitives
				(gr_poly
					(pts
						(arc
							(start -0.1778 -0.2794)
							(mid -0.249642 -0.249642)
							(end -0.2794 -0.1778)
						)
						(arc
							(start -0.2794 0.1778)
							(mid -0.249642 0.249642)
							(end -0.1778 0.2794)
						)
						(arc
							(start 0.1778 0.2794)
							(mid 0.249642 0.249642)
							(end 0.2794 0.1778)
						)
						(arc
							(start 0.2794 -0.1778)
							(mid 0.249642 -0.249642)
							(end 0.1778 -0.2794)
						)
					)
					(width 0)
					(fill yes)
				)
			)
		)
		(pad "2" smd custom
			(at 0 0.4445 270)
			(size 0.1397 0.1397)
			(layers "F.Cu" "F.Mask" "F.Paste")
			(net "DEBUG_GPIO_BMC_5")
			(options
				(clearance outline)
				(anchor circle)
			)
			(primitives
				(gr_poly
					(pts
						(arc
							(start -0.1778 -0.2794)
							(mid -0.249642 -0.249642)
							(end -0.2794 -0.1778)
						)
						(arc
							(start -0.2794 0.1778)
							(mid -0.249642 0.249642)
							(end -0.1778 0.2794)
						)
						(arc
							(start 0.1778 0.2794)
							(mid 0.249642 0.249642)
							(end 0.2794 0.1778)
						)
						(arc
							(start 0.2794 -0.1778)
							(mid 0.249642 -0.249642)
							(end 0.1778 -0.2794)
						)
					)
					(width 0)
					(fill yes)
				)
			)
		)
	)
	(footprint ""
		(layer "F.Cu")
		(at 79.172816 -181.33568)
		(property "Reference" "C198"
			(at 0 0 0)
			(layer "F.SilkS")
			(hide yes)
			(effects
				(font
					(size 1.27 1.27)
				)
			)
		)
		(property "Value" "SCD1U16V2KX-3GP"
			(at 1.1811 -2.7051 0)
			(unlocked yes)
			(layer "F.Fab")
			(hide yes)
			(effects
				(font
					(size 1.016 1.016)
					(thickness 0.1524)
				)
			)
		)
		(property "Device Type" "C402H22"
			(at 1.1811 -4.2291 0)
			(unlocked yes)
			(layer "F.Fab")
			(hide yes)
			(effects
				(font
					(size 1.016 1.016)
					(thickness 0.1524)
				)
			)
		)
		(duplicate_pad_numbers_are_jumpers no)
		(fp_rect
			(start -0.4318 0.9525)
			(end 0.4318 -0.9525)
			(stroke
				(width 0)
				(type default)
			)
			(fill no)
			(layer "F.CrtYd")
		)
		(fp_rect
			(start -0.4318 0.9525)
			(end 0.4318 -0.9525)
			(stroke
				(width 0)
				(type default)
			)
			(fill no)
			(layer "F.Fab")
		)
		(pad "1" smd custom
			(at 0 -0.4445)
			(size 0.1524 0.1524)
			(layers "F.Cu" "F.Mask" "F.Paste")
			(net "P3V3_STBY")
			(options
				(clearance outline)
				(anchor circle)
			)
			(primitives
				(gr_poly
					(pts
						(arc
							(start 0.3048 -0.2032)
							(mid 0.275042 -0.275042)
							(end 0.2032 -0.3048)
						)
						(arc
							(start -0.2032 -0.3048)
							(mid -0.275042 -0.275042)
							(end -0.3048 -0.2032)
						)
						(arc
							(start -0.3048 0.2032)
							(mid -0.275042 0.275042)
							(end -0.2032 0.3048)
						)
						(arc
							(start 0.2032 0.3048)
							(mid 0.275042 0.275042)
							(end 0.3048 0.2032)
						)
					)
					(width 0)
					(fill yes)
				)
			)
		)
		(pad "2" smd custom
			(at 0 0.4445)
			(size 0.1524 0.1524)
			(layers "F.Cu" "F.Mask" "F.Paste")
			(net "GND")
			(options
				(clearance outline)
				(anchor circle)
			)
			(primitives
				(gr_poly
					(pts
						(arc
							(start 0.3048 -0.2032)
							(mid 0.275042 -0.275042)
							(end 0.2032 -0.3048)
						)
						(arc
							(start -0.2032 -0.3048)
							(mid -0.275042 -0.275042)
							(end -0.3048 -0.2032)
						)
						(arc
							(start -0.3048 0.2032)
							(mid -0.275042 0.275042)
							(end -0.2032 0.3048)
						)
						(arc
							(start 0.2032 0.3048)
							(mid 0.275042 0.275042)
							(end 0.3048 0.2032)
						)
					)
					(width 0)
					(fill yes)
				)
			)
		)
	)
	(footprint ""
		(layer "F.Cu")
		(at 73.561448 -168.460166)
		(property "Reference" "R540"
			(at 0 0 0)
			(layer "F.SilkS")
			(hide yes)
			(effects
				(font
					(size 1.27 1.27)
				)
			)
		)
		(property "Value" "0R2J-2-GP"
			(at 0.064008 -3.993896 0)
			(unlocked yes)
			(layer "F.Fab")
			(hide yes)
			(effects
				(font
					(size 1.016 1.016)
					(thickness 0.1524)
				)
			)
		)
		(property "Device Type" "R402H16"
			(at 0.064008 -5.517896 0)
			(unlocked yes)
			(layer "F.Fab")
			(hide yes)
			(effects
				(font
					(size 1.016 1.016)
					(thickness 0.1524)
				)
			)
		)
		(duplicate_pad_numbers_are_jumpers no)
		(fp_line
			(start -0.508 -0.9398)
			(end -0.508 0.9398)
			(stroke
				(width 0.1524)
				(type default)
			)
			(layer "F.SilkS")
		)
		(fp_line
			(start 0.508 -0.9398)
			(end -0.508 -0.9398)
			(stroke
				(width 0.1524)
				(type default)
			)
			(layer "F.SilkS")
		)
		(fp_rect
			(start -0.508 0.9398)
			(end 0.508 -0.9398)
			(stroke
				(width 0)
				(type default)
			)
			(fill no)
			(layer "F.CrtYd")
		)
		(fp_rect
			(start -0.508 0.9398)
			(end 0.508 -0.9398)
			(stroke
				(width 0)
				(type default)
			)
			(fill no)
			(layer "F.Fab")
		)
		(pad "1" smd custom
			(at 0 -0.4445)
			(size 0.1397 0.1397)
			(layers "F.Cu" "F.Mask" "F.Paste")
			(net "P5V_STBY")
			(options
				(clearance outline)
				(anchor circle)
			)
			(primitives
				(gr_poly
					(pts
						(arc
							(start -0.1778 -0.2794)
							(mid -0.249642 -0.249642)
							(end -0.2794 -0.1778)
						)
						(arc
							(start -0.2794 0.1778)
							(mid -0.249642 0.249642)
							(end -0.1778 0.2794)
						)
						(arc
							(start 0.1778 0.2794)
							(mid 0.249642 0.249642)
							(end 0.2794 0.1778)
						)
						(arc
							(start 0.2794 -0.1778)
							(mid 0.249642 -0.249642)
							(end 0.1778 -0.2794)
						)
					)
					(width 0)
					(fill yes)
				)
			)
		)
		(pad "2" smd custom
			(at 0 0.4445)
			(size 0.1397 0.1397)
			(layers "F.Cu" "F.Mask" "F.Paste")
			(net "TPS74801_P1V15_STBY_BIAS")
			(options
				(clearance outline)
				(anchor circle)
			)
			(primitives
				(gr_poly
					(pts
						(arc
							(start -0.1778 -0.2794)
							(mid -0.249642 -0.249642)
							(end -0.2794 -0.1778)
						)
						(arc
							(start -0.2794 0.1778)
							(mid -0.249642 0.249642)
							(end -0.1778 0.2794)
						)
						(arc
							(start 0.1778 0.2794)
							(mid 0.249642 0.249642)
							(end 0.2794 0.1778)
						)
						(arc
							(start 0.2794 -0.1778)
							(mid 0.249642 -0.249642)
							(end 0.1778 -0.2794)
						)
					)
					(width 0)
					(fill yes)
				)
			)
		)
	)
	(footprint ""
		(layer "F.Cu")
		(at 63.422784 -141.493494 90)
		(property "Reference" "R199"
			(at 0 0 90)
			(layer "F.SilkS")
			(hide yes)
			(effects
				(font
					(size 1.27 1.27)
				)
			)
		)
		(property "Value" "1KR2F-3-GP"
			(at 0.064008 -3.993896 90)
			(unlocked yes)
			(layer "F.Fab")
			(hide yes)
			(effects
				(font
					(size 1.016 1.016)
					(thickness 0.1524)
				)
			)
		)
		(property "Device Type" "R402H16"
			(at 0.064008 -5.517896 90)
			(unlocked yes)
			(layer "F.Fab")
			(hide yes)
			(effects
				(font
					(size 1.016 1.016)
					(thickness 0.1524)
				)
			)
		)
		(duplicate_pad_numbers_are_jumpers no)
		(fp_line
			(start 0.508 -0.9398)
			(end -0.508 -0.9398)
			(stroke
				(width 0.1524)
				(type default)
			)
			(layer "F.SilkS")
		)
		(fp_line
			(start -0.508 -0.9398)
			(end -0.508 0.9398)
			(stroke
				(width 0.1524)
				(type default)
			)
			(layer "F.SilkS")
		)
		(fp_rect
			(start -0.508 0.9398)
			(end 0.508 -0.9398)
			(stroke
				(width 0)
				(type default)
			)
			(fill no)
			(layer "F.CrtYd")
		)
		(fp_rect
			(start -0.508 0.9398)
			(end 0.508 -0.9398)
			(stroke
				(width 0)
				(type default)
			)
			(fill no)
			(layer "F.Fab")
		)
		(pad "1" smd custom
			(at 0 -0.4445 90)
			(size 0.1397 0.1397)
			(layers "F.Cu" "F.Mask" "F.Paste")
			(net "I2C_EXP_RMT_SDA_OUT")
			(options
				(clearance outline)
				(anchor circle)
			)
			(primitives
				(gr_poly
					(pts
						(arc
							(start -0.1778 -0.2794)
							(mid -0.249642 -0.249642)
							(end -0.2794 -0.1778)
						)
						(arc
							(start -0.2794 0.1778)
							(mid -0.249642 0.249642)
							(end -0.1778 0.2794)
						)
						(arc
							(start 0.1778 0.2794)
							(mid 0.249642 0.249642)
							(end 0.2794 0.1778)
						)
						(arc
							(start 0.2794 -0.1778)
							(mid 0.249642 -0.249642)
							(end 0.1778 -0.2794)
						)
					)
					(width 0)
					(fill yes)
				)
			)
		)
		(pad "2" smd custom
			(at 0 0.4445 90)
			(size 0.1397 0.1397)
			(layers "F.Cu" "F.Mask" "F.Paste")
			(net "P3V3_STBY")
			(options
				(clearance outline)
				(anchor circle)
			)
			(primitives
				(gr_poly
					(pts
						(arc
							(start -0.1778 -0.2794)
							(mid -0.249642 -0.249642)
							(end -0.2794 -0.1778)
						)
						(arc
							(start -0.2794 0.1778)
							(mid -0.249642 0.249642)
							(end -0.1778 0.2794)
						)
						(arc
							(start 0.1778 0.2794)
							(mid 0.249642 0.249642)
							(end 0.2794 0.1778)
						)
						(arc
							(start 0.2794 -0.1778)
							(mid 0.249642 -0.249642)
							(end 0.1778 -0.2794)
						)
					)
					(width 0)
					(fill yes)
				)
			)
		)
	)
	(footprint ""
		(layer "F.Cu")
		(at 72.4662 -132.7912 90)
		(property "Reference" "R99"
			(at 0 0 90)
			(layer "F.SilkS")
			(hide yes)
			(effects
				(font
					(size 1.27 1.27)
				)
			)
		)
		(property "Value" "0R2J-2-GP"
			(at 0.064008 -3.993896 90)
			(unlocked yes)
			(layer "F.Fab")
			(hide yes)
			(effects
				(font
					(size 1.016 1.016)
					(thickness 0.1524)
				)
			)
		)
		(property "Device Type" "R402H16"
			(at 0.064008 -5.517896 90)
			(unlocked yes)
			(layer "F.Fab")
			(hide yes)
			(effects
				(font
					(size 1.016 1.016)
					(thickness 0.1524)
				)
			)
		)
		(duplicate_pad_numbers_are_jumpers no)
		(fp_line
			(start 0.508 -0.9398)
			(end -0.508 -0.9398)
			(stroke
				(width 0.1524)
				(type default)
			)
			(layer "F.SilkS")
		)
		(fp_line
			(start -0.508 -0.9398)
			(end -0.508 0.9398)
			(stroke
				(width 0.1524)
				(type default)
			)
			(layer "F.SilkS")
		)
		(fp_rect
			(start -0.508 0.9398)
			(end 0.508 -0.9398)
			(stroke
				(width 0)
				(type default)
			)
			(fill no)
			(layer "F.CrtYd")
		)
		(fp_rect
			(start -0.508 0.9398)
			(end 0.508 -0.9398)
			(stroke
				(width 0)
				(type default)
			)
			(fill no)
			(layer "F.Fab")
		)
		(pad "1" smd custom
			(at 0 -0.4445 90)
			(size 0.1397 0.1397)
			(layers "F.Cu" "F.Mask" "F.Paste")
			(net "P3V3_STBY")
			(options
				(clearance outline)
				(anchor circle)
			)
			(primitives
				(gr_poly
					(pts
						(arc
							(start -0.1778 -0.2794)
							(mid -0.249642 -0.249642)
							(end -0.2794 -0.1778)
						)
						(arc
							(start -0.2794 0.1778)
							(mid -0.249642 0.249642)
							(end -0.1778 0.2794)
						)
						(arc
							(start 0.1778 0.2794)
							(mid 0.249642 0.249642)
							(end 0.2794 0.1778)
						)
						(arc
							(start 0.2794 -0.1778)
							(mid 0.249642 -0.249642)
							(end 0.1778 -0.2794)
						)
					)
					(width 0)
					(fill yes)
				)
			)
		)
		(pad "2" smd custom
			(at 0 0.4445 90)
			(size 0.1397 0.1397)
			(layers "F.Cu" "F.Mask" "F.Paste")
			(net "D_FLIP_PRE#")
			(options
				(clearance outline)
				(anchor circle)
			)
			(primitives
				(gr_poly
					(pts
						(arc
							(start -0.1778 -0.2794)
							(mid -0.249642 -0.249642)
							(end -0.2794 -0.1778)
						)
						(arc
							(start -0.2794 0.1778)
							(mid -0.249642 0.249642)
							(end -0.1778 0.2794)
						)
						(arc
							(start 0.1778 0.2794)
							(mid 0.249642 0.249642)
							(end 0.2794 0.1778)
						)
						(arc
							(start 0.2794 -0.1778)
							(mid 0.249642 -0.249642)
							(end 0.1778 -0.2794)
						)
					)
					(width 0)
					(fill yes)
				)
			)
		)
	)
	(footprint ""
		(layer "F.Cu")
		(at 196.2404 -6.985)
		(property "Reference" "Q27"
			(at 0 0 0)
			(layer "F.SilkS")
			(hide yes)
			(effects
				(font
					(size 1.27 1.27)
				)
			)
		)
		(property "Value" "SSM6P39TU-GP"
			(at 0.0508 -11.5824 0)
			(unlocked yes)
			(layer "F.Fab")
			(hide yes)
			(effects
				(font
					(size 1.016 1.016)
					(thickness 0.1524)
				)
			)
		)
		(property "Device Type" "UMT6H30"
			(at 0.0508 -13.1572 0)
			(unlocked yes)
			(layer "F.Fab")
			(hide yes)
			(effects
				(font
					(size 1.016 1.016)
					(thickness 0.1524)
				)
			)
		)
		(duplicate_pad_numbers_are_jumpers no)
		(fp_line
			(start -1.27 -0.36449)
			(end -1.27 0.36449)
			(stroke
				(width 0.1524)
				(type default)
			)
			(layer "F.SilkS")
		)
		(fp_line
			(start -1.27 -0.36449)
			(end 1.524 -0.36449)
			(stroke
				(width 0.1524)
				(type default)
			)
			(layer "F.SilkS")
		)
		(fp_line
			(start 1.09347 0)
			(end 1.45796 0.36449)
			(stroke
				(width 0.1524)
				(type default)
			)
			(layer "F.SilkS")
		)
		(fp_line
			(start 1.45796 -0.36449)
			(end 1.09347 0)
			(stroke
				(width 0.1524)
				(type default)
			)
			(layer "F.SilkS")
		)
		(fp_line
			(start 1.524 -0.36449)
			(end 1.45796 -0.36449)
			(stroke
				(width 0.1524)
				(type default)
			)
			(layer "F.SilkS")
		)
		(fp_line
			(start 1.524 -0.36449)
			(end 1.524 -1.82245)
			(stroke
				(width 0.508)
				(type default)
			)
			(layer "F.SilkS")
		)
		(fp_line
			(start 1.524 -0.36449)
			(end 1.524 0.36449)
			(stroke
				(width 0.1524)
				(type default)
			)
			(layer "F.SilkS")
		)
		(fp_line
			(start 1.524 0.36449)
			(end -1.27 0.36449)
			(stroke
				(width 0.1524)
				(type default)
			)
			(layer "F.SilkS")
		)
		(fp_poly
			(pts
				(xy -0.65024 0.36449) (xy -0.65024 -0.36449) (xy 0.65024 -0.36449) (xy 0.65024 0.36449)
			)
			(stroke
				(width 0)
				(type default)
			)
			(fill yes)
			(layer "F.SilkS")
		)
		(fp_poly
			(pts
				(xy 1.016 -1.0668) (xy 1.016 1.0668) (xy -1.016 1.0668) (xy -1.016 -1.0668)
			)
			(stroke
				(width 0)
				(type default)
			)
			(fill no)
			(layer "F.CrtYd")
		)
		(fp_poly
			(pts
				(xy -1.524 1.905) (xy 1.524 1.905) (xy 1.524 -1.06426) (xy 1.016 -1.06426) (xy 1.016 1.0668) (xy -1.016 1.0668)
				(xy -1.016 -1.0668) (xy 1.524 -1.0668) (xy 1.524 -1.905) (xy -1.524 -1.905)
			)
			(stroke
				(width 0)
				(type default)
			)
			(fill no)
			(layer "F.CrtYd")
		)
		(fp_poly
			(pts
				(xy -1.524 -1.905) (xy -1.524 1.905) (xy 1.524 1.905) (xy 1.524 -1.905)
			)
			(stroke
				(width 0)
				(type default)
			)
			(fill no)
			(layer "F.Fab")
		)
		(pad "1" smd rect
			(at 0.65024 -1.02489)
			(size 0.4064 0.8128)
			(layers "F.Cu" "F.Mask" "F.Paste")
			(net "P3V3_STBY")
		)
		(pad "2" smd rect
			(at 0 -1.02489)
			(size 0.4064 0.8128)
			(layers "F.Cu" "F.Mask" "F.Paste")
			(net "BMC_ML_PWR_YELLOW_LED_R")
		)
		(pad "3" smd rect
			(at -0.65024 -1.02489)
			(size 0.4064 0.8128)
			(layers "F.Cu" "F.Mask" "F.Paste")
			(net "ML_PWR_BLUE_LED")
		)
		(pad "4" smd rect
			(at -0.65024 1.02489)
			(size 0.4064 0.8128)
			(layers "F.Cu" "F.Mask" "F.Paste")
			(net "P5V_STBY")
		)
		(pad "5" smd rect
			(at 0 1.02489)
			(size 0.4064 0.8128)
			(layers "F.Cu" "F.Mask" "F.Paste")
			(net "BMC_ML_PWR_BLUE_LED_L")
		)
		(pad "6" smd rect
			(at 0.65024 1.02489)
			(size 0.4064 0.8128)
			(layers "F.Cu" "F.Mask" "F.Paste")
			(net "ML_PWR_YELLOW_LED")
		)
	)
	(footprint ""
		(layer "F.Cu")
		(at 36.28771 -121.3612 90)
		(property "Reference" "U11"
			(at 0 0 90)
			(layer "F.SilkS")
			(hide yes)
			(effects
				(font
					(size 1.27 1.27)
				)
			)
		)
		(property "Value" "W25Q256FVFIQ-GP"
			(at -6.7945 -2.2098 90)
			(unlocked yes)
			(layer "F.Fab")
			(hide yes)
			(effects
				(font
					(size 1.016 1.016)
					(thickness 0.1524)
				)
			)
		)
		(property "Device Type" "SOIC16-6H104"
			(at -6.7945 -3.7338 90)
			(unlocked yes)
			(layer "F.Fab")
			(hide yes)
			(effects
				(font
					(size 1.016 1.016)
					(thickness 0.1524)
				)
			)
		)
		(duplicate_pad_numbers_are_jumpers no)
		(fp_line
			(start 4.7498 -3.2258)
			(end 4.7498 3.2258)
			(stroke
				(width 0.1524)
				(type default)
			)
			(layer "F.SilkS")
		)
		(fp_line
			(start -5.588 -3.2258)
			(end 4.7498 -3.2258)
			(stroke
				(width 0.1524)
				(type default)
			)
			(layer "F.SilkS")
		)
		(fp_line
			(start -5.588 -0.50038)
			(end -5.08762 0)
			(stroke
				(width 0.1524)
				(type default)
			)
			(layer "F.SilkS")
		)
		(fp_line
			(start -5.08762 0)
			(end -5.588 0.50038)
			(stroke
				(width 0.1524)
				(type default)
			)
			(layer "F.SilkS")
		)
		(fp_line
			(start 4.7498 3.2258)
			(end -5.588 3.2258)
			(stroke
				(width 0.1524)
				(type default)
			)
			(layer "F.SilkS")
		)
		(fp_line
			(start -5.4102 3.2258)
			(end -5.4102 5.7912)
			(stroke
				(width 0.508)
				(type default)
			)
			(layer "F.SilkS")
		)
		(fp_line
			(start -5.588 3.2258)
			(end -5.588 -3.2258)
			(stroke
				(width 0.1524)
				(type default)
			)
			(layer "F.SilkS")
		)
		(fp_poly
			(pts
				(xy -4.764786 -3.2258) (xy 4.7625 -3.2258) (xy 4.7625 3.2258) (xy -4.764786 3.2258)
			)
			(stroke
				(width 0)
				(type default)
			)
			(fill yes)
			(layer "F.SilkS")
		)
		(fp_rect
			(start -5.1435 5.1562)
			(end 5.1435 -5.1562)
			(stroke
				(width 0)
				(type default)
			)
			(fill no)
			(layer "F.CrtYd")
		)
		(fp_poly
			(pts
				(xy -5.6642 6.0452) (xy -5.6642 -6.0452) (xy 5.6642 -6.0452) (xy 5.6642 -1.7653) (xy 5.1435 -1.7653)
				(xy 5.1435 -5.1562) (xy -5.1435 -5.1562) (xy -5.1435 5.1562) (xy 5.1435 5.1562) (xy 5.1435 -1.7526)
				(xy 5.6642 -1.7526) (xy 5.6642 6.0452)
			)
			(stroke
				(width 0)
				(type default)
			)
			(fill no)
			(layer "F.CrtYd")
		)
		(fp_rect
			(start -5.6642 6.0452)
			(end 5.6642 -6.0452)
			(stroke
				(width 0)
				(type default)
			)
			(fill no)
			(layer "F.Fab")
		)
		(pad "1" smd rect
			(at -4.445 4.71805 90)
			(size 0.635 1.651)
			(layers "F.Cu" "F.Mask" "F.Paste")
			(net "FLA0_SPI_HOLD_N")
		)
		(pad "2" smd rect
			(at -3.175 4.71805 90)
			(size 0.635 1.651)
			(layers "F.Cu" "F.Mask" "F.Paste")
			(net "P3V3_STBY")
		)
		(pad "3" smd rect
			(at -1.905 4.71805 90)
			(size 0.635 1.651)
			(layers "F.Cu" "F.Mask" "F.Paste")
			(net "FLA0_SPI_RST")
		)
		(pad "4" smd rect
			(at -0.635 4.71805 90)
			(size 0.635 1.651)
			(layers "F.Cu" "F.Mask" "F.Paste")
			(net "Net_570")
		)
		(pad "5" smd rect
			(at 0.635 4.71805 90)
			(size 0.635 1.651)
			(layers "F.Cu" "F.Mask" "F.Paste")
			(net "Net_571")
		)
		(pad "6" smd rect
			(at 1.905 4.71805 90)
			(size 0.635 1.651)
			(layers "F.Cu" "F.Mask" "F.Paste")
			(net "Net_572")
		)
		(pad "7" smd rect
			(at 3.175 4.71805 90)
			(size 0.635 1.651)
			(layers "F.Cu" "F.Mask" "F.Paste")
			(net "FLA_CS_0_R")
		)
		(pad "8" smd rect
			(at 4.445 4.71805 90)
			(size 0.635 1.651)
			(layers "F.Cu" "F.Mask" "F.Paste")
			(net "BMC_SPI_MISO_TPM")
		)
		(pad "9" smd rect
			(at 4.445 -4.71805 90)
			(size 0.635 1.651)
			(layers "F.Cu" "F.Mask" "F.Paste")
			(net "FLA0_WP_N")
		)
		(pad "10" smd rect
			(at 3.175 -4.71805 90)
			(size 0.635 1.651)
			(layers "F.Cu" "F.Mask" "F.Paste")
			(net "GND")
		)
		(pad "11" smd rect
			(at 1.905 -4.71805 90)
			(size 0.635 1.651)
			(layers "F.Cu" "F.Mask" "F.Paste")
			(net "Net_566")
		)
		(pad "12" smd rect
			(at 0.635 -4.71805 90)
			(size 0.635 1.651)
			(layers "F.Cu" "F.Mask" "F.Paste")
			(net "Net_567")
		)
		(pad "13" smd rect
			(at -0.635 -4.71805 90)
			(size 0.635 1.651)
			(layers "F.Cu" "F.Mask" "F.Paste")
			(net "Net_568")
		)
		(pad "14" smd rect
			(at -1.905 -4.71805 90)
			(size 0.635 1.651)
			(layers "F.Cu" "F.Mask" "F.Paste")
			(net "Net_569")
		)
		(pad "15" smd rect
			(at -3.175 -4.71805 90)
			(size 0.635 1.651)
			(layers "F.Cu" "F.Mask" "F.Paste")
			(net "BMC_SPI_MOSI_R")
		)
		(pad "16" smd rect
			(at -4.445 -4.71805 90)
			(size 0.635 1.651)
			(layers "F.Cu" "F.Mask" "F.Paste")
			(net "BMC_SPI_CLK_R")
		)
	)
	(footprint ""
		(layer "F.Cu")
		(at 65.659 -172.085 180)
		(property "Reference" "R78"
			(at 0 0 180)
			(layer "F.SilkS")
			(hide yes)
			(effects
				(font
					(size 1.27 1.27)
				)
			)
		)
		(property "Value" "10KR2F-2-GP"
			(at 0.064008 -3.993896 180)
			(unlocked yes)
			(layer "F.Fab")
			(hide yes)
			(effects
				(font
					(size 1.016 1.016)
					(thickness 0.1524)
				)
			)
		)
		(property "Device Type" "R402H16"
			(at 0.064008 -5.517896 180)
			(unlocked yes)
			(layer "F.Fab")
			(hide yes)
			(effects
				(font
					(size 1.016 1.016)
					(thickness 0.1524)
				)
			)
		)
		(duplicate_pad_numbers_are_jumpers no)
		(fp_line
			(start 0.508 -0.9398)
			(end -0.508 -0.9398)
			(stroke
				(width 0.1524)
				(type default)
			)
			(layer "F.SilkS")
		)
		(fp_line
			(start -0.508 -0.9398)
			(end -0.508 0.9398)
			(stroke
				(width 0.1524)
				(type default)
			)
			(layer "F.SilkS")
		)
		(fp_rect
			(start -0.508 0.9398)
			(end 0.508 -0.9398)
			(stroke
				(width 0)
				(type default)
			)
			(fill no)
			(layer "F.CrtYd")
		)
		(fp_rect
			(start -0.508 0.9398)
			(end 0.508 -0.9398)
			(stroke
				(width 0)
				(type default)
			)
			(fill no)
			(layer "F.Fab")
		)
		(pad "1" smd custom
			(at 0 -0.4445 180)
			(size 0.1397 0.1397)
			(layers "F.Cu" "F.Mask" "F.Paste")
			(net "P3V3_STBY")
			(options
				(clearance outline)
				(anchor circle)
			)
			(primitives
				(gr_poly
					(pts
						(arc
							(start -0.1778 -0.2794)
							(mid -0.249642 -0.249642)
							(end -0.2794 -0.1778)
						)
						(arc
							(start -0.2794 0.1778)
							(mid -0.249642 0.249642)
							(end -0.1778 0.2794)
						)
						(arc
							(start 0.1778 0.2794)
							(mid 0.249642 0.249642)
							(end 0.2794 0.1778)
						)
						(arc
							(start 0.2794 -0.1778)
							(mid 0.249642 -0.249642)
							(end 0.1778 -0.2794)
						)
					)
					(width 0)
					(fill yes)
				)
			)
		)
		(pad "2" smd custom
			(at 0 0.4445 180)
			(size 0.1397 0.1397)
			(layers "F.Cu" "F.Mask" "F.Paste")
			(net "FM_TPM_PRSNT_N")
			(options
				(clearance outline)
				(anchor circle)
			)
			(primitives
				(gr_poly
					(pts
						(arc
							(start -0.1778 -0.2794)
							(mid -0.249642 -0.249642)
							(end -0.2794 -0.1778)
						)
						(arc
							(start -0.2794 0.1778)
							(mid -0.249642 0.249642)
							(end -0.1778 0.2794)
						)
						(arc
							(start 0.1778 0.2794)
							(mid 0.249642 0.249642)
							(end 0.2794 0.1778)
						)
						(arc
							(start 0.2794 -0.1778)
							(mid 0.249642 -0.249642)
							(end 0.1778 -0.2794)
						)
					)
					(width 0)
					(fill yes)
				)
			)
		)
	)
	(footprint ""
		(layer "F.Cu")
		(at 53.7972 -181.3306)
		(property "Reference" "C174"
			(at 0 0 0)
			(layer "F.SilkS")
			(hide yes)
			(effects
				(font
					(size 1.27 1.27)
				)
			)
		)
		(property "Value" "SC10U6D3V5KX-4GP"
			(at -0.0762 -6.1214 0)
			(unlocked yes)
			(layer "F.Fab")
			(hide yes)
			(effects
				(font
					(size 1.016 1.016)
					(thickness 0.1524)
				)
			)
		)
		(property "Device Type" "C805H58"
			(at -0.0762 -8.1534 0)
			(unlocked yes)
			(layer "F.Fab")
			(hide yes)
			(effects
				(font
					(size 1.016 1.016)
					(thickness 0.1524)
				)
			)
		)
		(duplicate_pad_numbers_are_jumpers no)
		(fp_line
			(start 0.635 0)
			(end -0.635 0)
			(stroke
				(width 0.508)
				(type default)
			)
			(layer "F.SilkS")
		)
		(fp_rect
			(start -0.9652 1.778)
			(end 0.9652 -1.778)
			(stroke
				(width 0)
				(type default)
			)
			(fill no)
			(layer "F.CrtYd")
		)
		(fp_poly
			(pts
				(xy -0.9652 -1.778) (xy 0.9652 -1.778) (xy 0.9652 1.778) (xy -0.9652 1.778)
			)
			(stroke
				(width 0)
				(type default)
			)
			(fill no)
			(layer "F.Fab")
		)
		(pad "1" smd rect
			(at 0 -0.9652)
			(size 1.397 1.143)
			(layers "F.Cu" "F.Mask" "F.Paste")
			(net "P3V3_STBY_OUT")
		)
		(pad "2" smd rect
			(at 0 0.9652)
			(size 1.397 1.143)
			(layers "F.Cu" "F.Mask" "F.Paste")
			(net "GND")
		)
	)
	(footprint ""
		(layer "F.Cu")
		(at 60.2742 -132.223002 -90)
		(property "Reference" "R289"
			(at 0 0 270)
			(layer "F.SilkS")
			(hide yes)
			(effects
				(font
					(size 1.27 1.27)
				)
			)
		)
		(property "Value" "0R2J-2-GP"
			(at 0.064008 -3.993896 270)
			(unlocked yes)
			(layer "F.Fab")
			(hide yes)
			(effects
				(font
					(size 1.016 1.016)
					(thickness 0.1524)
				)
			)
		)
		(property "Device Type" "R402H16"
			(at 0.064008 -5.517896 270)
			(unlocked yes)
			(layer "F.Fab")
			(hide yes)
			(effects
				(font
					(size 1.016 1.016)
					(thickness 0.1524)
				)
			)
		)
		(duplicate_pad_numbers_are_jumpers no)
		(fp_line
			(start -0.508 -0.9398)
			(end -0.508 0.9398)
			(stroke
				(width 0.1524)
				(type default)
			)
			(layer "F.SilkS")
		)
		(fp_line
			(start 0.508 -0.9398)
			(end -0.508 -0.9398)
			(stroke
				(width 0.1524)
				(type default)
			)
			(layer "F.SilkS")
		)
		(fp_rect
			(start -0.508 0.9398)
			(end 0.508 -0.9398)
			(stroke
				(width 0)
				(type default)
			)
			(fill no)
			(layer "F.CrtYd")
		)
		(fp_rect
			(start -0.508 0.9398)
			(end 0.508 -0.9398)
			(stroke
				(width 0)
				(type default)
			)
			(fill no)
			(layer "F.Fab")
		)
		(pad "1" smd custom
			(at 0 -0.4445 270)
			(size 0.1397 0.1397)
			(layers "F.Cu" "F.Mask" "F.Paste")
			(net "EXP_SPARE_1")
			(options
				(clearance outline)
				(anchor circle)
			)
			(primitives
				(gr_poly
					(pts
						(arc
							(start -0.1778 -0.2794)
							(mid -0.249642 -0.249642)
							(end -0.2794 -0.1778)
						)
						(arc
							(start -0.2794 0.1778)
							(mid -0.249642 0.249642)
							(end -0.1778 0.2794)
						)
						(arc
							(start 0.1778 0.2794)
							(mid 0.249642 0.249642)
							(end 0.2794 0.1778)
						)
						(arc
							(start 0.2794 -0.1778)
							(mid 0.249642 -0.249642)
							(end 0.1778 -0.2794)
						)
					)
					(width 0)
					(fill yes)
				)
			)
		)
		(pad "2" smd custom
			(at 0 0.4445 270)
			(size 0.1397 0.1397)
			(layers "F.Cu" "F.Mask" "F.Paste")
			(net "EXP_SPARE_1_R")
			(options
				(clearance outline)
				(anchor circle)
			)
			(primitives
				(gr_poly
					(pts
						(arc
							(start -0.1778 -0.2794)
							(mid -0.249642 -0.249642)
							(end -0.2794 -0.1778)
						)
						(arc
							(start -0.2794 0.1778)
							(mid -0.249642 0.249642)
							(end -0.1778 0.2794)
						)
						(arc
							(start 0.1778 0.2794)
							(mid 0.249642 0.249642)
							(end 0.2794 0.1778)
						)
						(arc
							(start 0.2794 -0.1778)
							(mid 0.249642 -0.249642)
							(end 0.1778 -0.2794)
						)
					)
					(width 0)
					(fill yes)
				)
			)
		)
	)
	(footprint ""
		(layer "F.Cu")
		(at 25.682702 -132.353558 180)
		(property "Reference" "R232"
			(at 0 0 180)
			(layer "F.SilkS")
			(hide yes)
			(effects
				(font
					(size 1.27 1.27)
				)
			)
		)
		(property "Value" "120R2F-GP"
			(at 0.064008 -3.993896 180)
			(unlocked yes)
			(layer "F.Fab")
			(hide yes)
			(effects
				(font
					(size 1.016 1.016)
					(thickness 0.1524)
				)
			)
		)
		(property "Device Type" "R402H16"
			(at 0.064008 -5.517896 180)
			(unlocked yes)
			(layer "F.Fab")
			(hide yes)
			(effects
				(font
					(size 1.016 1.016)
					(thickness 0.1524)
				)
			)
		)
		(duplicate_pad_numbers_are_jumpers no)
		(fp_line
			(start 0.508 -0.9398)
			(end -0.508 -0.9398)
			(stroke
				(width 0.1524)
				(type default)
			)
			(layer "F.SilkS")
		)
		(fp_line
			(start -0.508 -0.9398)
			(end -0.508 0.9398)
			(stroke
				(width 0.1524)
				(type default)
			)
			(layer "F.SilkS")
		)
		(fp_rect
			(start -0.508 0.9398)
			(end 0.508 -0.9398)
			(stroke
				(width 0)
				(type default)
			)
			(fill no)
			(layer "F.CrtYd")
		)
		(fp_rect
			(start -0.508 0.9398)
			(end 0.508 -0.9398)
			(stroke
				(width 0)
				(type default)
			)
			(fill no)
			(layer "F.Fab")
		)
		(pad "1" smd custom
			(at 0 -0.4445 180)
			(size 0.1397 0.1397)
			(layers "F.Cu" "F.Mask" "F.Paste")
			(net "MEMBA_1")
			(options
				(clearance outline)
				(anchor circle)
			)
			(primitives
				(gr_poly
					(pts
						(arc
							(start -0.1778 -0.2794)
							(mid -0.249642 -0.249642)
							(end -0.2794 -0.1778)
						)
						(arc
							(start -0.2794 0.1778)
							(mid -0.249642 0.249642)
							(end -0.1778 0.2794)
						)
						(arc
							(start 0.1778 0.2794)
							(mid 0.249642 0.249642)
							(end 0.2794 0.1778)
						)
						(arc
							(start 0.2794 -0.1778)
							(mid 0.249642 -0.249642)
							(end 0.1778 -0.2794)
						)
					)
					(width 0)
					(fill yes)
				)
			)
		)
		(pad "2" smd custom
			(at 0 0.4445 180)
			(size 0.1397 0.1397)
			(layers "F.Cu" "F.Mask" "F.Paste")
			(net "P1V2_STBY")
			(options
				(clearance outline)
				(anchor circle)
			)
			(primitives
				(gr_poly
					(pts
						(arc
							(start -0.1778 -0.2794)
							(mid -0.249642 -0.249642)
							(end -0.2794 -0.1778)
						)
						(arc
							(start -0.2794 0.1778)
							(mid -0.249642 0.249642)
							(end -0.1778 0.2794)
						)
						(arc
							(start 0.1778 0.2794)
							(mid 0.249642 0.249642)
							(end 0.2794 0.1778)
						)
						(arc
							(start 0.2794 -0.1778)
							(mid 0.249642 -0.249642)
							(end 0.1778 -0.2794)
						)
					)
					(width 0)
					(fill yes)
				)
			)
		)
	)
	(footprint ""
		(layer "F.Cu")
		(at 81.407 -152.146 -90)
		(property "Reference" "C44"
			(at 0 0 270)
			(layer "F.SilkS")
			(hide yes)
			(effects
				(font
					(size 1.27 1.27)
				)
			)
		)
		(property "Value" "SCD1U16V2KX-3GP"
			(at 1.1811 -2.7051 270)
			(unlocked yes)
			(layer "F.Fab")
			(hide yes)
			(effects
				(font
					(size 1.016 1.016)
					(thickness 0.1524)
				)
			)
		)
		(property "Device Type" "C402H22"
			(at 1.1811 -4.2291 270)
			(unlocked yes)
			(layer "F.Fab")
			(hide yes)
			(effects
				(font
					(size 1.016 1.016)
					(thickness 0.1524)
				)
			)
		)
		(duplicate_pad_numbers_are_jumpers no)
		(fp_rect
			(start -0.4318 0.9525)
			(end 0.4318 -0.9525)
			(stroke
				(width 0)
				(type default)
			)
			(fill no)
			(layer "F.CrtYd")
		)
		(fp_rect
			(start -0.4318 0.9525)
			(end 0.4318 -0.9525)
			(stroke
				(width 0)
				(type default)
			)
			(fill no)
			(layer "F.Fab")
		)
		(pad "1" smd custom
			(at 0 -0.4445 270)
			(size 0.1524 0.1524)
			(layers "F.Cu" "F.Mask" "F.Paste")
			(net "P3V3_STBY")
			(options
				(clearance outline)
				(anchor circle)
			)
			(primitives
				(gr_poly
					(pts
						(arc
							(start 0.3048 -0.2032)
							(mid 0.275042 -0.275042)
							(end 0.2032 -0.3048)
						)
						(arc
							(start -0.2032 -0.3048)
							(mid -0.275042 -0.275042)
							(end -0.3048 -0.2032)
						)
						(arc
							(start -0.3048 0.2032)
							(mid -0.275042 0.275042)
							(end -0.2032 0.3048)
						)
						(arc
							(start 0.2032 0.3048)
							(mid 0.275042 0.275042)
							(end 0.3048 0.2032)
						)
					)
					(width 0)
					(fill yes)
				)
			)
		)
		(pad "2" smd custom
			(at 0 0.4445 270)
			(size 0.1524 0.1524)
			(layers "F.Cu" "F.Mask" "F.Paste")
			(net "GND")
			(options
				(clearance outline)
				(anchor circle)
			)
			(primitives
				(gr_poly
					(pts
						(arc
							(start 0.3048 -0.2032)
							(mid 0.275042 -0.275042)
							(end 0.2032 -0.3048)
						)
						(arc
							(start -0.2032 -0.3048)
							(mid -0.275042 -0.275042)
							(end -0.3048 -0.2032)
						)
						(arc
							(start -0.3048 0.2032)
							(mid -0.275042 0.275042)
							(end -0.2032 0.3048)
						)
						(arc
							(start 0.2032 0.3048)
							(mid 0.275042 0.275042)
							(end 0.3048 0.2032)
						)
					)
					(width 0)
					(fill yes)
				)
			)
		)
	)
	(footprint ""
		(layer "F.Cu")
		(at 99.2886 -162.0266 -90)
		(property "Reference" "R32"
			(at 0 0 270)
			(layer "F.SilkS")
			(hide yes)
			(effects
				(font
					(size 1.27 1.27)
				)
			)
		)
		(property "Value" "4K7R2F-GP"
			(at 0.064008 -3.993896 270)
			(unlocked yes)
			(layer "F.Fab")
			(hide yes)
			(effects
				(font
					(size 1.016 1.016)
					(thickness 0.1524)
				)
			)
		)
		(property "Device Type" "R402H16"
			(at 0.064008 -5.517896 270)
			(unlocked yes)
			(layer "F.Fab")
			(hide yes)
			(effects
				(font
					(size 1.016 1.016)
					(thickness 0.1524)
				)
			)
		)
		(duplicate_pad_numbers_are_jumpers no)
		(fp_line
			(start -0.508 -0.9398)
			(end -0.508 0.9398)
			(stroke
				(width 0.1524)
				(type default)
			)
			(layer "F.SilkS")
		)
		(fp_line
			(start 0.508 -0.9398)
			(end -0.508 -0.9398)
			(stroke
				(width 0.1524)
				(type default)
			)
			(layer "F.SilkS")
		)
		(fp_rect
			(start -0.508 0.9398)
			(end 0.508 -0.9398)
			(stroke
				(width 0)
				(type default)
			)
			(fill no)
			(layer "F.CrtYd")
		)
		(fp_rect
			(start -0.508 0.9398)
			(end 0.508 -0.9398)
			(stroke
				(width 0)
				(type default)
			)
			(fill no)
			(layer "F.Fab")
		)
		(pad "1" smd custom
			(at 0 -0.4445 270)
			(size 0.1397 0.1397)
			(layers "F.Cu" "F.Mask" "F.Paste")
			(net "P3V3_STBY")
			(options
				(clearance outline)
				(anchor circle)
			)
			(primitives
				(gr_poly
					(pts
						(arc
							(start -0.1778 -0.2794)
							(mid -0.249642 -0.249642)
							(end -0.2794 -0.1778)
						)
						(arc
							(start -0.2794 0.1778)
							(mid -0.249642 0.249642)
							(end -0.1778 0.2794)
						)
						(arc
							(start 0.1778 0.2794)
							(mid 0.249642 0.249642)
							(end 0.2794 0.1778)
						)
						(arc
							(start 0.2794 -0.1778)
							(mid 0.249642 -0.249642)
							(end 0.1778 -0.2794)
						)
					)
					(width 0)
					(fill yes)
				)
			)
		)
		(pad "2" smd custom
			(at 0 0.4445 270)
			(size 0.1397 0.1397)
			(layers "F.Cu" "F.Mask" "F.Paste")
			(net "USB_SUSP_IND")
			(options
				(clearance outline)
				(anchor circle)
			)
			(primitives
				(gr_poly
					(pts
						(arc
							(start -0.1778 -0.2794)
							(mid -0.249642 -0.249642)
							(end -0.2794 -0.1778)
						)
						(arc
							(start -0.2794 0.1778)
							(mid -0.249642 0.249642)
							(end -0.1778 0.2794)
						)
						(arc
							(start 0.1778 0.2794)
							(mid 0.249642 0.249642)
							(end 0.2794 0.1778)
						)
						(arc
							(start 0.2794 -0.1778)
							(mid 0.249642 -0.249642)
							(end 0.1778 -0.2794)
						)
					)
					(width 0)
					(fill yes)
				)
			)
		)
	)
	(footprint ""
		(layer "F.Cu")
		(at 124.841 -6.604 -90)
		(property "Reference" "R711"
			(at 0 0 270)
			(layer "F.SilkS")
			(hide yes)
			(effects
				(font
					(size 1.27 1.27)
				)
			)
		)
		(property "Value" "0R2J-2-GP"
			(at 0.064008 -3.993896 270)
			(unlocked yes)
			(layer "F.Fab")
			(hide yes)
			(effects
				(font
					(size 1.016 1.016)
					(thickness 0.1524)
				)
			)
		)
		(property "Device Type" "R402H16"
			(at 0.064008 -5.517896 270)
			(unlocked yes)
			(layer "F.Fab")
			(hide yes)
			(effects
				(font
					(size 1.016 1.016)
					(thickness 0.1524)
				)
			)
		)
		(duplicate_pad_numbers_are_jumpers no)
		(fp_line
			(start -0.508 -0.9398)
			(end -0.508 0.9398)
			(stroke
				(width 0.1524)
				(type default)
			)
			(layer "F.SilkS")
		)
		(fp_line
			(start 0.508 -0.9398)
			(end -0.508 -0.9398)
			(stroke
				(width 0.1524)
				(type default)
			)
			(layer "F.SilkS")
		)
		(fp_rect
			(start -0.508 0.9398)
			(end 0.508 -0.9398)
			(stroke
				(width 0)
				(type default)
			)
			(fill no)
			(layer "F.CrtYd")
		)
		(fp_rect
			(start -0.508 0.9398)
			(end 0.508 -0.9398)
			(stroke
				(width 0)
				(type default)
			)
			(fill no)
			(layer "F.Fab")
		)
		(pad "1" smd custom
			(at 0 -0.4445 270)
			(size 0.1397 0.1397)
			(layers "F.Cu" "F.Mask" "F.Paste")
			(net "I2C_IOM_SCL")
			(options
				(clearance outline)
				(anchor circle)
			)
			(primitives
				(gr_poly
					(pts
						(arc
							(start -0.1778 -0.2794)
							(mid -0.249642 -0.249642)
							(end -0.2794 -0.1778)
						)
						(arc
							(start -0.2794 0.1778)
							(mid -0.249642 0.249642)
							(end -0.1778 0.2794)
						)
						(arc
							(start 0.1778 0.2794)
							(mid 0.249642 0.249642)
							(end 0.2794 0.1778)
						)
						(arc
							(start 0.2794 -0.1778)
							(mid 0.249642 -0.249642)
							(end 0.1778 -0.2794)
						)
					)
					(width 0)
					(fill yes)
				)
			)
		)
		(pad "2" smd custom
			(at 0 0.4445 270)
			(size 0.1397 0.1397)
			(layers "F.Cu" "F.Mask" "F.Paste")
			(net "HSW_SCL")
			(options
				(clearance outline)
				(anchor circle)
			)
			(primitives
				(gr_poly
					(pts
						(arc
							(start -0.1778 -0.2794)
							(mid -0.249642 -0.249642)
							(end -0.2794 -0.1778)
						)
						(arc
							(start -0.2794 0.1778)
							(mid -0.249642 0.249642)
							(end -0.1778 0.2794)
						)
						(arc
							(start 0.1778 0.2794)
							(mid 0.249642 0.249642)
							(end 0.2794 0.1778)
						)
						(arc
							(start 0.2794 -0.1778)
							(mid 0.249642 -0.249642)
							(end 0.1778 -0.2794)
						)
					)
					(width 0)
					(fill yes)
				)
			)
		)
	)
	(footprint ""
		(layer "F.Cu")
		(at 182.446676 -105.37825)
		(property "Reference" "U84"
			(at 0 0 0)
			(layer "F.SilkS")
			(hide yes)
			(effects
				(font
					(size 1.27 1.27)
				)
			)
		)
		(property "Value" "TMP75AIDGKR-GP"
			(at -0.1143 -9.1948 0)
			(unlocked yes)
			(layer "F.Fab")
			(hide yes)
			(effects
				(font
					(size 1.016 1.016)
					(thickness 0.1524)
				)
			)
		)
		(property "Device Type" "MSOP8-1H44"
			(at -0.1143 -10.795 0)
			(unlocked yes)
			(layer "F.Fab")
			(hide yes)
			(effects
				(font
					(size 1.016 1.016)
					(thickness 0.1524)
				)
			)
		)
		(duplicate_pad_numbers_are_jumpers no)
		(fp_line
			(start -1.9558 -1.016)
			(end -1.9558 1.016)
			(stroke
				(width 0.1524)
				(type default)
			)
			(layer "F.SilkS")
		)
		(fp_line
			(start -1.9558 -0.5461)
			(end -1.4478 -0.0381)
			(stroke
				(width 0.1524)
				(type default)
			)
			(layer "F.SilkS")
		)
		(fp_line
			(start -1.9558 1.016)
			(end 1.0795 1.016)
			(stroke
				(width 0.1524)
				(type default)
			)
			(layer "F.SilkS")
		)
		(fp_line
			(start -1.778 1.0922)
			(end -1.778 3.048)
			(stroke
				(width 0.508)
				(type default)
			)
			(layer "F.SilkS")
		)
		(fp_line
			(start -1.4478 -0.0381)
			(end -1.9558 0.4699)
			(stroke
				(width 0.1524)
				(type default)
			)
			(layer "F.SilkS")
		)
		(fp_line
			(start 1.0795 -1.016)
			(end -1.9558 -1.016)
			(stroke
				(width 0.1524)
				(type default)
			)
			(layer "F.SilkS")
		)
		(fp_line
			(start 1.0795 1.016)
			(end 1.0795 -1.016)
			(stroke
				(width 0.1524)
				(type default)
			)
			(layer "F.SilkS")
		)
		(fp_poly
			(pts
				(xy -1.1557 -1.016) (xy -1.1557 1.016) (xy 1.1557 1.016) (xy 1.1557 -1.016)
			)
			(stroke
				(width 0)
				(type default)
			)
			(fill yes)
			(layer "F.SilkS")
		)
		(fp_rect
			(start -1.4986 2.4511)
			(end 1.4986 -2.4511)
			(stroke
				(width 0)
				(type default)
			)
			(fill no)
			(layer "F.CrtYd")
		)
		(fp_poly
			(pts
				(xy -2.032 3.302) (xy -2.032 -3.302) (xy 2.032 -3.302) (xy 2.032 -2.1209) (xy 1.4986 -2.1209) (xy 1.4986 -2.4511)
				(xy -1.4986 -2.4511) (xy -1.4986 2.4511) (xy 1.4986 2.4511) (xy 1.4986 -2.1082) (xy 2.032 -2.1082)
				(xy 2.032 3.302)
			)
			(stroke
				(width 0)
				(type default)
			)
			(fill no)
			(layer "F.CrtYd")
		)
		(fp_rect
			(start -2.032 3.302)
			(end 2.032 -3.302)
			(stroke
				(width 0)
				(type default)
			)
			(fill no)
			(layer "F.Fab")
		)
		(pad "1" smd rect
			(at -0.97536 2.05486)
			(size 0.3556 1.524)
			(layers "F.Cu" "F.Mask" "F.Paste")
			(net "TEMP_1_SDA")
		)
		(pad "2" smd rect
			(at -0.32512 2.05486)
			(size 0.3556 1.524)
			(layers "F.Cu" "F.Mask" "F.Paste")
			(net "TEMP_1_SCL")
		)
		(pad "3" smd rect
			(at 0.32512 2.05486)
			(size 0.3556 1.524)
			(layers "F.Cu" "F.Mask" "F.Paste")
			(net "TEMP_1_ALERT")
		)
		(pad "4" smd rect
			(at 0.97536 2.05486)
			(size 0.3556 1.524)
			(layers "F.Cu" "F.Mask" "F.Paste")
			(net "GND")
		)
		(pad "5" smd rect
			(at 0.97536 -2.05486)
			(size 0.3556 1.524)
			(layers "F.Cu" "F.Mask" "F.Paste")
			(net "TEMP_1_A2")
		)
		(pad "6" smd rect
			(at 0.32512 -2.05486)
			(size 0.3556 1.524)
			(layers "F.Cu" "F.Mask" "F.Paste")
			(net "TEMP_1_A1")
		)
		(pad "7" smd rect
			(at -0.32512 -2.05486)
			(size 0.3556 1.524)
			(layers "F.Cu" "F.Mask" "F.Paste")
			(net "TEMP_1_A0")
		)
		(pad "8" smd rect
			(at -0.97536 -2.05486)
			(size 0.3556 1.524)
			(layers "F.Cu" "F.Mask" "F.Paste")
			(net "P3V3_STBY")
		)
	)
	(footprint ""
		(layer "F.Cu")
		(at 47.879 -175.7172)
		(property "Reference" "C49"
			(at 0 0 0)
			(layer "F.SilkS")
			(hide yes)
			(effects
				(font
					(size 1.27 1.27)
				)
			)
		)
		(property "Value" "SCD1U16V2KX-3GP"
			(at 1.1811 -2.7051 0)
			(unlocked yes)
			(layer "F.Fab")
			(hide yes)
			(effects
				(font
					(size 1.016 1.016)
					(thickness 0.1524)
				)
			)
		)
		(property "Device Type" "C402H22"
			(at 1.1811 -4.2291 0)
			(unlocked yes)
			(layer "F.Fab")
			(hide yes)
			(effects
				(font
					(size 1.016 1.016)
					(thickness 0.1524)
				)
			)
		)
		(duplicate_pad_numbers_are_jumpers no)
		(fp_rect
			(start -0.4318 0.9525)
			(end 0.4318 -0.9525)
			(stroke
				(width 0)
				(type default)
			)
			(fill no)
			(layer "F.CrtYd")
		)
		(fp_rect
			(start -0.4318 0.9525)
			(end 0.4318 -0.9525)
			(stroke
				(width 0)
				(type default)
			)
			(fill no)
			(layer "F.Fab")
		)
		(pad "1" smd custom
			(at 0 -0.4445)
			(size 0.1524 0.1524)
			(layers "F.Cu" "F.Mask" "F.Paste")
			(net "P3V3_STBY")
			(options
				(clearance outline)
				(anchor circle)
			)
			(primitives
				(gr_poly
					(pts
						(arc
							(start 0.3048 -0.2032)
							(mid 0.275042 -0.275042)
							(end 0.2032 -0.3048)
						)
						(arc
							(start -0.2032 -0.3048)
							(mid -0.275042 -0.275042)
							(end -0.3048 -0.2032)
						)
						(arc
							(start -0.3048 0.2032)
							(mid -0.275042 0.275042)
							(end -0.2032 0.3048)
						)
						(arc
							(start 0.2032 0.3048)
							(mid 0.275042 0.275042)
							(end 0.3048 0.2032)
						)
					)
					(width 0)
					(fill yes)
				)
			)
		)
		(pad "2" smd custom
			(at 0 0.4445)
			(size 0.1524 0.1524)
			(layers "F.Cu" "F.Mask" "F.Paste")
			(net "GND")
			(options
				(clearance outline)
				(anchor circle)
			)
			(primitives
				(gr_poly
					(pts
						(arc
							(start 0.3048 -0.2032)
							(mid 0.275042 -0.275042)
							(end 0.2032 -0.3048)
						)
						(arc
							(start -0.2032 -0.3048)
							(mid -0.275042 -0.275042)
							(end -0.3048 -0.2032)
						)
						(arc
							(start -0.3048 0.2032)
							(mid -0.275042 0.275042)
							(end -0.2032 0.3048)
						)
						(arc
							(start 0.2032 0.3048)
							(mid 0.275042 0.275042)
							(end 0.3048 0.2032)
						)
					)
					(width 0)
					(fill yes)
				)
			)
		)
	)
	(footprint ""
		(layer "F.Cu")
		(at 86.872572 -58.973974 90)
		(property "Reference" "R4"
			(at 0 0 90)
			(layer "F.SilkS")
			(hide yes)
			(effects
				(font
					(size 1.27 1.27)
				)
			)
		)
		(property "Value" "0R2J-2-GP"
			(at 0.064008 -3.993896 90)
			(unlocked yes)
			(layer "F.Fab")
			(hide yes)
			(effects
				(font
					(size 1.016 1.016)
					(thickness 0.1524)
				)
			)
		)
		(property "Device Type" "R402H16"
			(at 0.064008 -5.517896 90)
			(unlocked yes)
			(layer "F.Fab")
			(hide yes)
			(effects
				(font
					(size 1.016 1.016)
					(thickness 0.1524)
				)
			)
		)
		(duplicate_pad_numbers_are_jumpers no)
		(fp_line
			(start 0.508 -0.9398)
			(end -0.508 -0.9398)
			(stroke
				(width 0.1524)
				(type default)
			)
			(layer "F.SilkS")
		)
		(fp_line
			(start -0.508 -0.9398)
			(end -0.508 0.9398)
			(stroke
				(width 0.1524)
				(type default)
			)
			(layer "F.SilkS")
		)
		(fp_rect
			(start -0.508 0.9398)
			(end 0.508 -0.9398)
			(stroke
				(width 0)
				(type default)
			)
			(fill no)
			(layer "F.CrtYd")
		)
		(fp_rect
			(start -0.508 0.9398)
			(end 0.508 -0.9398)
			(stroke
				(width 0)
				(type default)
			)
			(fill no)
			(layer "F.Fab")
		)
		(pad "1" smd custom
			(at 0 -0.4445 90)
			(size 0.1397 0.1397)
			(layers "F.Cu" "F.Mask" "F.Paste")
			(net "I2C_MEZZ_ALERT_R_N")
			(options
				(clearance outline)
				(anchor circle)
			)
			(primitives
				(gr_poly
					(pts
						(arc
							(start -0.1778 -0.2794)
							(mid -0.249642 -0.249642)
							(end -0.2794 -0.1778)
						)
						(arc
							(start -0.2794 0.1778)
							(mid -0.249642 0.249642)
							(end -0.1778 0.2794)
						)
						(arc
							(start 0.1778 0.2794)
							(mid 0.249642 0.249642)
							(end 0.2794 0.1778)
						)
						(arc
							(start 0.2794 -0.1778)
							(mid 0.249642 -0.249642)
							(end 0.1778 -0.2794)
						)
					)
					(width 0)
					(fill yes)
				)
			)
		)
		(pad "2" smd custom
			(at 0 0.4445 90)
			(size 0.1397 0.1397)
			(layers "F.Cu" "F.Mask" "F.Paste")
			(net "I2C_MEZZ_ALERT_N")
			(options
				(clearance outline)
				(anchor circle)
			)
			(primitives
				(gr_poly
					(pts
						(arc
							(start -0.1778 -0.2794)
							(mid -0.249642 -0.249642)
							(end -0.2794 -0.1778)
						)
						(arc
							(start -0.2794 0.1778)
							(mid -0.249642 0.249642)
							(end -0.1778 0.2794)
						)
						(arc
							(start 0.1778 0.2794)
							(mid 0.249642 0.249642)
							(end 0.2794 0.1778)
						)
						(arc
							(start 0.2794 -0.1778)
							(mid 0.249642 -0.249642)
							(end 0.1778 -0.2794)
						)
					)
					(width 0)
					(fill yes)
				)
			)
		)
	)
	(footprint ""
		(layer "F.Cu")
		(at 92.6084 -125.3998 180)
		(property "Reference" "C522"
			(at 0 0 180)
			(layer "F.SilkS")
			(hide yes)
			(effects
				(font
					(size 1.27 1.27)
				)
			)
		)
		(property "Value" "SCD1U25V2KX-2-GP"
			(at 1.1811 -2.7051 180)
			(unlocked yes)
			(layer "F.Fab")
			(hide yes)
			(effects
				(font
					(size 1.016 1.016)
					(thickness 0.1524)
				)
			)
		)
		(property "Device Type" "C402H22"
			(at 1.1811 -4.2291 180)
			(unlocked yes)
			(layer "F.Fab")
			(hide yes)
			(effects
				(font
					(size 1.016 1.016)
					(thickness 0.1524)
				)
			)
		)
		(duplicate_pad_numbers_are_jumpers no)
		(fp_rect
			(start -0.4318 0.9525)
			(end 0.4318 -0.9525)
			(stroke
				(width 0)
				(type default)
			)
			(fill no)
			(layer "F.CrtYd")
		)
		(fp_rect
			(start -0.4318 0.9525)
			(end 0.4318 -0.9525)
			(stroke
				(width 0)
				(type default)
			)
			(fill no)
			(layer "F.Fab")
		)
		(pad "1" smd custom
			(at 0 -0.4445 180)
			(size 0.1524 0.1524)
			(layers "F.Cu" "F.Mask" "F.Paste")
			(net "P3V3_STBY")
			(options
				(clearance outline)
				(anchor circle)
			)
			(primitives
				(gr_poly
					(pts
						(arc
							(start 0.3048 -0.2032)
							(mid 0.275042 -0.275042)
							(end 0.2032 -0.3048)
						)
						(arc
							(start -0.2032 -0.3048)
							(mid -0.275042 -0.275042)
							(end -0.3048 -0.2032)
						)
						(arc
							(start -0.3048 0.2032)
							(mid -0.275042 0.275042)
							(end -0.2032 0.3048)
						)
						(arc
							(start 0.2032 0.3048)
							(mid 0.275042 0.275042)
							(end 0.3048 0.2032)
						)
					)
					(width 0)
					(fill yes)
				)
			)
		)
		(pad "2" smd custom
			(at 0 0.4445 180)
			(size 0.1524 0.1524)
			(layers "F.Cu" "F.Mask" "F.Paste")
			(net "GND")
			(options
				(clearance outline)
				(anchor circle)
			)
			(primitives
				(gr_poly
					(pts
						(arc
							(start 0.3048 -0.2032)
							(mid 0.275042 -0.275042)
							(end 0.2032 -0.3048)
						)
						(arc
							(start -0.2032 -0.3048)
							(mid -0.275042 -0.275042)
							(end -0.3048 -0.2032)
						)
						(arc
							(start -0.3048 0.2032)
							(mid -0.275042 0.275042)
							(end -0.2032 0.3048)
						)
						(arc
							(start 0.2032 0.3048)
							(mid 0.275042 0.275042)
							(end 0.3048 0.2032)
						)
					)
					(width 0)
					(fill yes)
				)
			)
		)
	)
	(footprint ""
		(layer "F.Cu")
		(at 85.45957 -144.252188 -90)
		(property "Reference" "R131"
			(at 0 0 270)
			(layer "F.SilkS")
			(hide yes)
			(effects
				(font
					(size 1.27 1.27)
				)
			)
		)
		(property "Value" "0R2J-2-GP"
			(at 0.064008 -3.993896 270)
			(unlocked yes)
			(layer "F.Fab")
			(hide yes)
			(effects
				(font
					(size 1.016 1.016)
					(thickness 0.1524)
				)
			)
		)
		(property "Device Type" "R402H16"
			(at 0.064008 -5.517896 270)
			(unlocked yes)
			(layer "F.Fab")
			(hide yes)
			(effects
				(font
					(size 1.016 1.016)
					(thickness 0.1524)
				)
			)
		)
		(duplicate_pad_numbers_are_jumpers no)
		(fp_line
			(start -0.508 -0.9398)
			(end -0.508 0.9398)
			(stroke
				(width 0.1524)
				(type default)
			)
			(layer "F.SilkS")
		)
		(fp_line
			(start 0.508 -0.9398)
			(end -0.508 -0.9398)
			(stroke
				(width 0.1524)
				(type default)
			)
			(layer "F.SilkS")
		)
		(fp_rect
			(start -0.508 0.9398)
			(end 0.508 -0.9398)
			(stroke
				(width 0)
				(type default)
			)
			(fill no)
			(layer "F.CrtYd")
		)
		(fp_rect
			(start -0.508 0.9398)
			(end 0.508 -0.9398)
			(stroke
				(width 0)
				(type default)
			)
			(fill no)
			(layer "F.Fab")
		)
		(pad "1" smd custom
			(at 0 -0.4445 270)
			(size 0.1397 0.1397)
			(layers "F.Cu" "F.Mask" "F.Paste")
			(net "I2C_SCC_SCL")
			(options
				(clearance outline)
				(anchor circle)
			)
			(primitives
				(gr_poly
					(pts
						(arc
							(start -0.1778 -0.2794)
							(mid -0.249642 -0.249642)
							(end -0.2794 -0.1778)
						)
						(arc
							(start -0.2794 0.1778)
							(mid -0.249642 0.249642)
							(end -0.1778 0.2794)
						)
						(arc
							(start 0.1778 0.2794)
							(mid 0.249642 0.249642)
							(end 0.2794 0.1778)
						)
						(arc
							(start 0.2794 -0.1778)
							(mid 0.249642 -0.249642)
							(end 0.1778 -0.2794)
						)
					)
					(width 0)
					(fill yes)
				)
			)
		)
		(pad "2" smd custom
			(at 0 0.4445 270)
			(size 0.1397 0.1397)
			(layers "F.Cu" "F.Mask" "F.Paste")
			(net "I2C_SCC_SCL_R")
			(options
				(clearance outline)
				(anchor circle)
			)
			(primitives
				(gr_poly
					(pts
						(arc
							(start -0.1778 -0.2794)
							(mid -0.249642 -0.249642)
							(end -0.2794 -0.1778)
						)
						(arc
							(start -0.2794 0.1778)
							(mid -0.249642 0.249642)
							(end -0.1778 0.2794)
						)
						(arc
							(start 0.1778 0.2794)
							(mid 0.249642 0.249642)
							(end 0.2794 0.1778)
						)
						(arc
							(start 0.2794 -0.1778)
							(mid 0.249642 -0.249642)
							(end 0.1778 -0.2794)
						)
					)
					(width 0)
					(fill yes)
				)
			)
		)
	)
	(footprint ""
		(layer "F.Cu")
		(at 45.331126 -132.002022 180)
		(property "Reference" "R158"
			(at 0 0 180)
			(layer "F.SilkS")
			(hide yes)
			(effects
				(font
					(size 1.27 1.27)
				)
			)
		)
		(property "Value" "0R2J-2-GP"
			(at 0.064008 -3.993896 180)
			(unlocked yes)
			(layer "F.Fab")
			(hide yes)
			(effects
				(font
					(size 1.016 1.016)
					(thickness 0.1524)
				)
			)
		)
		(property "Device Type" "R402H16"
			(at 0.064008 -5.517896 180)
			(unlocked yes)
			(layer "F.Fab")
			(hide yes)
			(effects
				(font
					(size 1.016 1.016)
					(thickness 0.1524)
				)
			)
		)
		(duplicate_pad_numbers_are_jumpers no)
		(fp_line
			(start 0.508 -0.9398)
			(end -0.508 -0.9398)
			(stroke
				(width 0.1524)
				(type default)
			)
			(layer "F.SilkS")
		)
		(fp_line
			(start -0.508 -0.9398)
			(end -0.508 0.9398)
			(stroke
				(width 0.1524)
				(type default)
			)
			(layer "F.SilkS")
		)
		(fp_rect
			(start -0.508 0.9398)
			(end 0.508 -0.9398)
			(stroke
				(width 0)
				(type default)
			)
			(fill no)
			(layer "F.CrtYd")
		)
		(fp_rect
			(start -0.508 0.9398)
			(end 0.508 -0.9398)
			(stroke
				(width 0)
				(type default)
			)
			(fill no)
			(layer "F.Fab")
		)
		(pad "1" smd custom
			(at 0 -0.4445 180)
			(size 0.1397 0.1397)
			(layers "F.Cu" "F.Mask" "F.Paste")
			(net "BMC_SMB2_DAT_TP")
			(options
				(clearance outline)
				(anchor circle)
			)
			(primitives
				(gr_poly
					(pts
						(arc
							(start -0.1778 -0.2794)
							(mid -0.249642 -0.249642)
							(end -0.2794 -0.1778)
						)
						(arc
							(start -0.2794 0.1778)
							(mid -0.249642 0.249642)
							(end -0.1778 0.2794)
						)
						(arc
							(start 0.1778 0.2794)
							(mid 0.249642 0.249642)
							(end 0.2794 0.1778)
						)
						(arc
							(start 0.2794 -0.1778)
							(mid 0.249642 -0.249642)
							(end 0.1778 -0.2794)
						)
					)
					(width 0)
					(fill yes)
				)
			)
		)
		(pad "2" smd custom
			(at 0 0.4445 180)
			(size 0.1397 0.1397)
			(layers "F.Cu" "F.Mask" "F.Paste")
			(net "BMC_SMB2_DAT")
			(options
				(clearance outline)
				(anchor circle)
			)
			(primitives
				(gr_poly
					(pts
						(arc
							(start -0.1778 -0.2794)
							(mid -0.249642 -0.249642)
							(end -0.2794 -0.1778)
						)
						(arc
							(start -0.2794 0.1778)
							(mid -0.249642 0.249642)
							(end -0.1778 0.2794)
						)
						(arc
							(start 0.1778 0.2794)
							(mid 0.249642 0.249642)
							(end 0.2794 0.1778)
						)
						(arc
							(start 0.2794 -0.1778)
							(mid 0.249642 -0.249642)
							(end 0.1778 -0.2794)
						)
					)
					(width 0)
					(fill yes)
				)
			)
		)
	)
	(footprint ""
		(layer "F.Cu")
		(at 49.09439 -158.5976)
		(property "Reference" "R168"
			(at 0 0 0)
			(layer "F.SilkS")
			(hide yes)
			(effects
				(font
					(size 1.27 1.27)
				)
			)
		)
		(property "Value" "0R2J-2-GP"
			(at 0.064008 -3.993896 0)
			(unlocked yes)
			(layer "F.Fab")
			(hide yes)
			(effects
				(font
					(size 1.016 1.016)
					(thickness 0.1524)
				)
			)
		)
		(property "Device Type" "R402H16"
			(at 0.064008 -5.517896 0)
			(unlocked yes)
			(layer "F.Fab")
			(hide yes)
			(effects
				(font
					(size 1.016 1.016)
					(thickness 0.1524)
				)
			)
		)
		(duplicate_pad_numbers_are_jumpers no)
		(fp_line
			(start -0.508 -0.9398)
			(end -0.508 0.9398)
			(stroke
				(width 0.1524)
				(type default)
			)
			(layer "F.SilkS")
		)
		(fp_line
			(start 0.508 -0.9398)
			(end -0.508 -0.9398)
			(stroke
				(width 0.1524)
				(type default)
			)
			(layer "F.SilkS")
		)
		(fp_rect
			(start -0.508 0.9398)
			(end 0.508 -0.9398)
			(stroke
				(width 0)
				(type default)
			)
			(fill no)
			(layer "F.CrtYd")
		)
		(fp_rect
			(start -0.508 0.9398)
			(end 0.508 -0.9398)
			(stroke
				(width 0)
				(type default)
			)
			(fill no)
			(layer "F.Fab")
		)
		(pad "1" smd custom
			(at 0 -0.4445)
			(size 0.1397 0.1397)
			(layers "F.Cu" "F.Mask" "F.Paste")
			(net "I2C_DPB_MISC_SCL_OUT")
			(options
				(clearance outline)
				(anchor circle)
			)
			(primitives
				(gr_poly
					(pts
						(arc
							(start -0.1778 -0.2794)
							(mid -0.249642 -0.249642)
							(end -0.2794 -0.1778)
						)
						(arc
							(start -0.2794 0.1778)
							(mid -0.249642 0.249642)
							(end -0.1778 0.2794)
						)
						(arc
							(start 0.1778 0.2794)
							(mid 0.249642 0.249642)
							(end 0.2794 0.1778)
						)
						(arc
							(start 0.2794 -0.1778)
							(mid 0.249642 -0.249642)
							(end 0.1778 -0.2794)
						)
					)
					(width 0)
					(fill yes)
				)
			)
		)
		(pad "2" smd custom
			(at 0 0.4445)
			(size 0.1397 0.1397)
			(layers "F.Cu" "F.Mask" "F.Paste")
			(net "BMC_SMB6_CLK")
			(options
				(clearance outline)
				(anchor circle)
			)
			(primitives
				(gr_poly
					(pts
						(arc
							(start -0.1778 -0.2794)
							(mid -0.249642 -0.249642)
							(end -0.2794 -0.1778)
						)
						(arc
							(start -0.2794 0.1778)
							(mid -0.249642 0.249642)
							(end -0.1778 0.2794)
						)
						(arc
							(start 0.1778 0.2794)
							(mid 0.249642 0.249642)
							(end 0.2794 0.1778)
						)
						(arc
							(start 0.2794 -0.1778)
							(mid 0.249642 -0.249642)
							(end 0.1778 -0.2794)
						)
					)
					(width 0)
					(fill yes)
				)
			)
		)
	)
	(footprint ""
		(layer "F.Cu")
		(at 88.768428 -49.168812 90)
		(property "Reference" "R523"
			(at 0 0 90)
			(layer "F.SilkS")
			(hide yes)
			(effects
				(font
					(size 1.27 1.27)
				)
			)
		)
		(property "Value" "1KR2F-3-GP"
			(at 0.064008 -3.993896 90)
			(unlocked yes)
			(layer "F.Fab")
			(hide yes)
			(effects
				(font
					(size 1.016 1.016)
					(thickness 0.1524)
				)
			)
		)
		(property "Device Type" "R402H16"
			(at 0.064008 -5.517896 90)
			(unlocked yes)
			(layer "F.Fab")
			(hide yes)
			(effects
				(font
					(size 1.016 1.016)
					(thickness 0.1524)
				)
			)
		)
		(duplicate_pad_numbers_are_jumpers no)
		(fp_line
			(start 0.508 -0.9398)
			(end -0.508 -0.9398)
			(stroke
				(width 0.1524)
				(type default)
			)
			(layer "F.SilkS")
		)
		(fp_line
			(start -0.508 -0.9398)
			(end -0.508 0.9398)
			(stroke
				(width 0.1524)
				(type default)
			)
			(layer "F.SilkS")
		)
		(fp_rect
			(start -0.508 0.9398)
			(end 0.508 -0.9398)
			(stroke
				(width 0)
				(type default)
			)
			(fill no)
			(layer "F.CrtYd")
		)
		(fp_rect
			(start -0.508 0.9398)
			(end 0.508 -0.9398)
			(stroke
				(width 0)
				(type default)
			)
			(fill no)
			(layer "F.Fab")
		)
		(pad "1" smd custom
			(at 0 -0.4445 90)
			(size 0.1397 0.1397)
			(layers "F.Cu" "F.Mask" "F.Paste")
			(net "P3V3")
			(options
				(clearance outline)
				(anchor circle)
			)
			(primitives
				(gr_poly
					(pts
						(arc
							(start -0.1778 -0.2794)
							(mid -0.249642 -0.249642)
							(end -0.2794 -0.1778)
						)
						(arc
							(start -0.2794 0.1778)
							(mid -0.249642 0.249642)
							(end -0.1778 0.2794)
						)
						(arc
							(start 0.1778 0.2794)
							(mid 0.249642 0.249642)
							(end 0.2794 0.1778)
						)
						(arc
							(start 0.2794 -0.1778)
							(mid 0.249642 -0.249642)
							(end 0.1778 -0.2794)
						)
					)
					(width 0)
					(fill yes)
				)
			)
		)
		(pad "2" smd custom
			(at 0 0.4445 90)
			(size 0.1397 0.1397)
			(layers "F.Cu" "F.Mask" "F.Paste")
			(net "GND")
			(options
				(clearance outline)
				(anchor circle)
			)
			(primitives
				(gr_poly
					(pts
						(arc
							(start -0.1778 -0.2794)
							(mid -0.249642 -0.249642)
							(end -0.2794 -0.1778)
						)
						(arc
							(start -0.2794 0.1778)
							(mid -0.249642 0.249642)
							(end -0.1778 0.2794)
						)
						(arc
							(start 0.1778 0.2794)
							(mid 0.249642 0.249642)
							(end 0.2794 0.1778)
						)
						(arc
							(start 0.2794 -0.1778)
							(mid 0.249642 -0.249642)
							(end 0.1778 -0.2794)
						)
					)
					(width 0)
					(fill yes)
				)
			)
		)
	)
	(footprint ""
		(layer "F.Cu")
		(at 27.419046 -158.588456 -90)
		(property "Reference" "R773"
			(at 0 0 270)
			(layer "F.SilkS")
			(hide yes)
			(effects
				(font
					(size 1.27 1.27)
				)
			)
		)
		(property "Value" "0R2J-2-GP"
			(at 0.064008 -3.993896 270)
			(unlocked yes)
			(layer "F.Fab")
			(hide yes)
			(effects
				(font
					(size 1.016 1.016)
					(thickness 0.1524)
				)
			)
		)
		(property "Device Type" "R402H16"
			(at 0.064008 -5.517896 270)
			(unlocked yes)
			(layer "F.Fab")
			(hide yes)
			(effects
				(font
					(size 1.016 1.016)
					(thickness 0.1524)
				)
			)
		)
		(duplicate_pad_numbers_are_jumpers no)
		(fp_line
			(start -0.508 -0.9398)
			(end -0.508 0.9398)
			(stroke
				(width 0.1524)
				(type default)
			)
			(layer "F.SilkS")
		)
		(fp_line
			(start 0.508 -0.9398)
			(end -0.508 -0.9398)
			(stroke
				(width 0.1524)
				(type default)
			)
			(layer "F.SilkS")
		)
		(fp_rect
			(start -0.508 0.9398)
			(end 0.508 -0.9398)
			(stroke
				(width 0)
				(type default)
			)
			(fill no)
			(layer "F.CrtYd")
		)
		(fp_rect
			(start -0.508 0.9398)
			(end 0.508 -0.9398)
			(stroke
				(width 0)
				(type default)
			)
			(fill no)
			(layer "F.Fab")
		)
		(pad "1" smd custom
			(at 0 -0.4445 270)
			(size 0.1397 0.1397)
			(layers "F.Cu" "F.Mask" "F.Paste")
			(net "DEBUG_GPIO_BMC_R_6")
			(options
				(clearance outline)
				(anchor circle)
			)
			(primitives
				(gr_poly
					(pts
						(arc
							(start -0.1778 -0.2794)
							(mid -0.249642 -0.249642)
							(end -0.2794 -0.1778)
						)
						(arc
							(start -0.2794 0.1778)
							(mid -0.249642 0.249642)
							(end -0.1778 0.2794)
						)
						(arc
							(start 0.1778 0.2794)
							(mid 0.249642 0.249642)
							(end 0.2794 0.1778)
						)
						(arc
							(start 0.2794 -0.1778)
							(mid 0.249642 -0.249642)
							(end 0.1778 -0.2794)
						)
					)
					(width 0)
					(fill yes)
				)
			)
		)
		(pad "2" smd custom
			(at 0 0.4445 270)
			(size 0.1397 0.1397)
			(layers "F.Cu" "F.Mask" "F.Paste")
			(net "DEBUG_GPIO_BMC_6")
			(options
				(clearance outline)
				(anchor circle)
			)
			(primitives
				(gr_poly
					(pts
						(arc
							(start -0.1778 -0.2794)
							(mid -0.249642 -0.249642)
							(end -0.2794 -0.1778)
						)
						(arc
							(start -0.2794 0.1778)
							(mid -0.249642 0.249642)
							(end -0.1778 0.2794)
						)
						(arc
							(start 0.1778 0.2794)
							(mid 0.249642 0.249642)
							(end 0.2794 0.1778)
						)
						(arc
							(start 0.2794 -0.1778)
							(mid 0.249642 -0.249642)
							(end 0.1778 -0.2794)
						)
					)
					(width 0)
					(fill yes)
				)
			)
		)
	)
	(footprint ""
		(layer "F.Cu")
		(at 30.3784 -159.2834 180)
		(property "Reference" "R368"
			(at 0 0 180)
			(layer "F.SilkS")
			(hide yes)
			(effects
				(font
					(size 1.27 1.27)
				)
			)
		)
		(property "Value" "0R2J-2-GP"
			(at 0.064008 -3.993896 180)
			(unlocked yes)
			(layer "F.Fab")
			(hide yes)
			(effects
				(font
					(size 1.016 1.016)
					(thickness 0.1524)
				)
			)
		)
		(property "Device Type" "R402H16"
			(at 0.064008 -5.517896 180)
			(unlocked yes)
			(layer "F.Fab")
			(hide yes)
			(effects
				(font
					(size 1.016 1.016)
					(thickness 0.1524)
				)
			)
		)
		(duplicate_pad_numbers_are_jumpers no)
		(fp_line
			(start 0.508 -0.9398)
			(end -0.508 -0.9398)
			(stroke
				(width 0.1524)
				(type default)
			)
			(layer "F.SilkS")
		)
		(fp_line
			(start -0.508 -0.9398)
			(end -0.508 0.9398)
			(stroke
				(width 0.1524)
				(type default)
			)
			(layer "F.SilkS")
		)
		(fp_rect
			(start -0.508 0.9398)
			(end 0.508 -0.9398)
			(stroke
				(width 0)
				(type default)
			)
			(fill no)
			(layer "F.CrtYd")
		)
		(fp_rect
			(start -0.508 0.9398)
			(end 0.508 -0.9398)
			(stroke
				(width 0)
				(type default)
			)
			(fill no)
			(layer "F.Fab")
		)
		(pad "1" smd custom
			(at 0 -0.4445 180)
			(size 0.1397 0.1397)
			(layers "F.Cu" "F.Mask" "F.Paste")
			(net "P3V3_STBY")
			(options
				(clearance outline)
				(anchor circle)
			)
			(primitives
				(gr_poly
					(pts
						(arc
							(start -0.1778 -0.2794)
							(mid -0.249642 -0.249642)
							(end -0.2794 -0.1778)
						)
						(arc
							(start -0.2794 0.1778)
							(mid -0.249642 0.249642)
							(end -0.1778 0.2794)
						)
						(arc
							(start 0.1778 0.2794)
							(mid 0.249642 0.249642)
							(end 0.2794 0.1778)
						)
						(arc
							(start 0.2794 -0.1778)
							(mid 0.249642 -0.249642)
							(end 0.1778 -0.2794)
						)
					)
					(width 0)
					(fill yes)
				)
			)
		)
		(pad "2" smd custom
			(at 0 0.4445 180)
			(size 0.1397 0.1397)
			(layers "F.Cu" "F.Mask" "F.Paste")
			(net "DACAV33")
			(options
				(clearance outline)
				(anchor circle)
			)
			(primitives
				(gr_poly
					(pts
						(arc
							(start -0.1778 -0.2794)
							(mid -0.249642 -0.249642)
							(end -0.2794 -0.1778)
						)
						(arc
							(start -0.2794 0.1778)
							(mid -0.249642 0.249642)
							(end -0.1778 0.2794)
						)
						(arc
							(start 0.1778 0.2794)
							(mid 0.249642 0.249642)
							(end 0.2794 0.1778)
						)
						(arc
							(start 0.2794 -0.1778)
							(mid 0.249642 -0.249642)
							(end 0.1778 -0.2794)
						)
					)
					(width 0)
					(fill yes)
				)
			)
		)
	)
	(footprint ""
		(layer "F.Cu")
		(at 95.220282 -46.444662)
		(property "Reference" "R500"
			(at 0 0 0)
			(layer "F.SilkS")
			(hide yes)
			(effects
				(font
					(size 1.27 1.27)
				)
			)
		)
		(property "Value" "2K2R2J-2-GP"
			(at 0.064008 -3.993896 0)
			(unlocked yes)
			(layer "F.Fab")
			(hide yes)
			(effects
				(font
					(size 1.016 1.016)
					(thickness 0.1524)
				)
			)
		)
		(property "Device Type" "R402H16"
			(at 0.064008 -5.517896 0)
			(unlocked yes)
			(layer "F.Fab")
			(hide yes)
			(effects
				(font
					(size 1.016 1.016)
					(thickness 0.1524)
				)
			)
		)
		(duplicate_pad_numbers_are_jumpers no)
		(fp_line
			(start -0.508 -0.9398)
			(end -0.508 0.9398)
			(stroke
				(width 0.1524)
				(type default)
			)
			(layer "F.SilkS")
		)
		(fp_line
			(start 0.508 -0.9398)
			(end -0.508 -0.9398)
			(stroke
				(width 0.1524)
				(type default)
			)
			(layer "F.SilkS")
		)
		(fp_rect
			(start -0.508 0.9398)
			(end 0.508 -0.9398)
			(stroke
				(width 0)
				(type default)
			)
			(fill no)
			(layer "F.CrtYd")
		)
		(fp_rect
			(start -0.508 0.9398)
			(end 0.508 -0.9398)
			(stroke
				(width 0)
				(type default)
			)
			(fill no)
			(layer "F.Fab")
		)
		(pad "1" smd custom
			(at 0 -0.4445)
			(size 0.1397 0.1397)
			(layers "F.Cu" "F.Mask" "F.Paste")
			(net "P3V3_STBY")
			(options
				(clearance outline)
				(anchor circle)
			)
			(primitives
				(gr_poly
					(pts
						(arc
							(start -0.1778 -0.2794)
							(mid -0.249642 -0.249642)
							(end -0.2794 -0.1778)
						)
						(arc
							(start -0.2794 0.1778)
							(mid -0.249642 0.249642)
							(end -0.1778 0.2794)
						)
						(arc
							(start 0.1778 0.2794)
							(mid 0.249642 0.249642)
							(end 0.2794 0.1778)
						)
						(arc
							(start 0.2794 -0.1778)
							(mid 0.249642 -0.249642)
							(end 0.1778 -0.2794)
						)
					)
					(width 0)
					(fill yes)
				)
			)
		)
		(pad "2" smd custom
			(at 0 0.4445)
			(size 0.1397 0.1397)
			(layers "F.Cu" "F.Mask" "F.Paste")
			(net "PQ2_G")
			(options
				(clearance outline)
				(anchor circle)
			)
			(primitives
				(gr_poly
					(pts
						(arc
							(start -0.1778 -0.2794)
							(mid -0.249642 -0.249642)
							(end -0.2794 -0.1778)
						)
						(arc
							(start -0.2794 0.1778)
							(mid -0.249642 0.249642)
							(end -0.1778 0.2794)
						)
						(arc
							(start 0.1778 0.2794)
							(mid 0.249642 0.249642)
							(end 0.2794 0.1778)
						)
						(arc
							(start 0.2794 -0.1778)
							(mid 0.249642 -0.249642)
							(end 0.1778 -0.2794)
						)
					)
					(width 0)
					(fill yes)
				)
			)
		)
	)
	(footprint ""
		(layer "F.Cu")
		(at 60.375546 -182.561738 -90)
		(property "Reference" "R481"
			(at 0 0 270)
			(layer "F.SilkS")
			(hide yes)
			(effects
				(font
					(size 1.27 1.27)
				)
			)
		)
		(property "Value" "0R6J-3-GP"
			(at -0.0508 -4.8514 270)
			(unlocked yes)
			(layer "F.Fab")
			(hide yes)
			(effects
				(font
					(size 1.016 1.016)
					(thickness 0.1524)
				)
			)
		)
		(property "Device Type" "R1206H28"
			(at 0 -6.3754 270)
			(unlocked yes)
			(layer "F.Fab")
			(hide yes)
			(effects
				(font
					(size 1.016 1.016)
					(thickness 0.1524)
				)
			)
		)
		(duplicate_pad_numbers_are_jumpers no)
		(fp_line
			(start -1.016 2.2352)
			(end -1.016 -2.2352)
			(stroke
				(width 0.1524)
				(type default)
			)
			(layer "F.SilkS")
		)
		(fp_line
			(start 1.016 2.2352)
			(end -1.016 2.2352)
			(stroke
				(width 0.1524)
				(type default)
			)
			(layer "F.SilkS")
		)
		(fp_line
			(start -1.016 -2.2352)
			(end 1.016 -2.2352)
			(stroke
				(width 0.1524)
				(type default)
			)
			(layer "F.SilkS")
		)
		(fp_line
			(start 1.016 -2.2352)
			(end 1.016 2.2352)
			(stroke
				(width 0.1524)
				(type default)
			)
			(layer "F.SilkS")
		)
		(fp_rect
			(start -1.0922 2.3114)
			(end 1.0922 -2.3114)
			(stroke
				(width 0)
				(type default)
			)
			(fill no)
			(layer "F.CrtYd")
		)
		(fp_poly
			(pts
				(xy -1.0922 -2.3114) (xy 1.0922 -2.3114) (xy 1.0922 2.3114) (xy -1.0922 2.3114)
			)
			(stroke
				(width 0)
				(type default)
			)
			(fill no)
			(layer "F.Fab")
		)
		(pad "1" smd rect
			(at 0 -1.397 270)
			(size 1.651 1.27)
			(layers "F.Cu" "F.Mask" "F.Paste")
			(net "P3V3_STBY")
		)
		(pad "2" smd rect
			(at 0 1.397 270)
			(size 1.651 1.27)
			(layers "F.Cu" "F.Mask" "F.Paste")
			(net "P3V3_STBY_OUT")
		)
	)
	(footprint ""
		(layer "F.Cu")
		(at 93.7514 -150.369524 -90)
		(property "Reference" "TP5"
			(at 0 0 270)
			(layer "F.SilkS")
			(hide yes)
			(effects
				(font
					(size 1.27 1.27)
				)
			)
		)
		(property "Value" "TPAD28-2-GP"
			(at -0.0127 -1.6637 270)
			(unlocked yes)
			(layer "F.Fab")
			(hide yes)
			(effects
				(font
					(size 1.016 1.016)
					(thickness 0.1524)
				)
			)
		)
		(property "Device Type" "TPAD28"
			(at -0.0127 -3.1877 270)
			(unlocked yes)
			(layer "F.Fab")
			(hide yes)
			(effects
				(font
					(size 1.016 1.016)
					(thickness 0.1524)
				)
			)
		)
		(duplicate_pad_numbers_are_jumpers no)
		(fp_poly
			(pts
				(arc
					(start 0 -0.3556)
					(mid 0 0.3556)
					(end 0 -0.3556)
				)
			)
			(stroke
				(width 0)
				(type default)
			)
			(fill no)
			(layer "F.CrtYd")
		)
		(fp_poly
			(pts
				(arc
					(start 0 -0.6096)
					(mid 0 0.6096)
					(end 0 -0.6096)
				)
			)
			(stroke
				(width 0)
				(type default)
			)
			(fill no)
			(layer "F.Fab")
		)
		(pad "1" smd circle
			(at 0 0 270)
			(size 0.7112 0.7112)
			(layers "F.Cu" "F.Mask" "F.Paste")
			(net "CRFILT")
		)
	)
	(footprint ""
		(layer "F.Cu")
		(at 61.907674 -178.834796)
		(property "Reference" "C33"
			(at 0 0 0)
			(layer "F.SilkS")
			(hide yes)
			(effects
				(font
					(size 1.27 1.27)
				)
			)
		)
		(property "Value" "SCD1U16V2KX-3GP"
			(at 1.1811 -2.7051 0)
			(unlocked yes)
			(layer "F.Fab")
			(hide yes)
			(effects
				(font
					(size 1.016 1.016)
					(thickness 0.1524)
				)
			)
		)
		(property "Device Type" "C402H22"
			(at 1.1811 -4.2291 0)
			(unlocked yes)
			(layer "F.Fab")
			(hide yes)
			(effects
				(font
					(size 1.016 1.016)
					(thickness 0.1524)
				)
			)
		)
		(duplicate_pad_numbers_are_jumpers no)
		(fp_rect
			(start -0.4318 0.9525)
			(end 0.4318 -0.9525)
			(stroke
				(width 0)
				(type default)
			)
			(fill no)
			(layer "F.CrtYd")
		)
		(fp_rect
			(start -0.4318 0.9525)
			(end 0.4318 -0.9525)
			(stroke
				(width 0)
				(type default)
			)
			(fill no)
			(layer "F.Fab")
		)
		(pad "1" smd custom
			(at 0 -0.4445)
			(size 0.1524 0.1524)
			(layers "F.Cu" "F.Mask" "F.Paste")
			(net "P3V3_STBY")
			(options
				(clearance outline)
				(anchor circle)
			)
			(primitives
				(gr_poly
					(pts
						(arc
							(start 0.3048 -0.2032)
							(mid 0.275042 -0.275042)
							(end 0.2032 -0.3048)
						)
						(arc
							(start -0.2032 -0.3048)
							(mid -0.275042 -0.275042)
							(end -0.3048 -0.2032)
						)
						(arc
							(start -0.3048 0.2032)
							(mid -0.275042 0.275042)
							(end -0.2032 0.3048)
						)
						(arc
							(start 0.2032 0.3048)
							(mid 0.275042 0.275042)
							(end 0.3048 0.2032)
						)
					)
					(width 0)
					(fill yes)
				)
			)
		)
		(pad "2" smd custom
			(at 0 0.4445)
			(size 0.1524 0.1524)
			(layers "F.Cu" "F.Mask" "F.Paste")
			(net "GND")
			(options
				(clearance outline)
				(anchor circle)
			)
			(primitives
				(gr_poly
					(pts
						(arc
							(start 0.3048 -0.2032)
							(mid 0.275042 -0.275042)
							(end 0.2032 -0.3048)
						)
						(arc
							(start -0.2032 -0.3048)
							(mid -0.275042 -0.275042)
							(end -0.3048 -0.2032)
						)
						(arc
							(start -0.3048 0.2032)
							(mid -0.275042 0.275042)
							(end -0.2032 0.3048)
						)
						(arc
							(start 0.2032 0.3048)
							(mid 0.275042 0.275042)
							(end 0.3048 0.2032)
						)
					)
					(width 0)
					(fill yes)
				)
			)
		)
	)
	(footprint ""
		(layer "F.Cu")
		(at 128.94691 -8.745728 90)
		(property "Reference" "R709"
			(at 0 0 90)
			(layer "F.SilkS")
			(hide yes)
			(effects
				(font
					(size 1.27 1.27)
				)
			)
		)
		(property "Value" "0R5J-5-GP"
			(at 0 -8.953754 90)
			(unlocked yes)
			(layer "F.Fab")
			(hide yes)
			(effects
				(font
					(size 1.27 1.016)
					(thickness 0.1524)
				)
			)
		)
		(property "Device Type" "R805H24"
			(at 0 -10.629646 90)
			(unlocked yes)
			(layer "F.Fab")
			(hide yes)
			(effects
				(font
					(size 1.27 1.016)
					(thickness 0.1524)
				)
			)
		)
		(duplicate_pad_numbers_are_jumpers no)
		(fp_line
			(start 0.888746 -1.7018)
			(end -0.888746 -1.7018)
			(stroke
				(width 0.1524)
				(type default)
			)
			(layer "F.SilkS")
		)
		(fp_line
			(start 0.888746 -1.7018)
			(end 0.889 -0.381)
			(stroke
				(width 0.1524)
				(type default)
			)
			(layer "F.SilkS")
		)
		(fp_line
			(start -0.888746 -1.7018)
			(end -0.889 0.2794)
			(stroke
				(width 0.1524)
				(type default)
			)
			(layer "F.SilkS")
		)
		(fp_line
			(start -0.889 0.0762)
			(end -0.888746 1.7018)
			(stroke
				(width 0.1524)
				(type default)
			)
			(layer "F.SilkS")
		)
		(fp_line
			(start 0.888746 1.7018)
			(end 0.889 -0.508)
			(stroke
				(width 0.1524)
				(type default)
			)
			(layer "F.SilkS")
		)
		(fp_line
			(start -0.888746 1.7018)
			(end 0.888746 1.7018)
			(stroke
				(width 0.1524)
				(type default)
			)
			(layer "F.SilkS")
		)
		(fp_poly
			(pts
				(xy 0.9652 -1.778) (xy 0.9652 1.778) (xy -0.9652 1.778) (xy -0.9652 -1.778)
			)
			(stroke
				(width 0)
				(type default)
			)
			(fill no)
			(layer "F.CrtYd")
		)
		(fp_rect
			(start -0.9652 1.778)
			(end 0.9652 -1.778)
			(stroke
				(width 0)
				(type default)
			)
			(fill no)
			(layer "F.Fab")
		)
		(pad "1" smd rect
			(at 0 -0.9652 90)
			(size 1.397 1.143)
			(layers "F.Cu" "F.Mask" "F.Paste")
			(net "MB0_CM_GATE_2")
		)
		(pad "2" smd rect
			(at 0 0.9652 90)
			(size 1.397 1.143)
			(layers "F.Cu" "F.Mask" "F.Paste")
			(net "MB0_CM_GATE_R")
		)
	)
	(footprint ""
		(layer "F.Cu")
		(at 110.71479 -9.666478 -90)
		(property "Reference" "R454"
			(at 0 0 270)
			(layer "F.SilkS")
			(hide yes)
			(effects
				(font
					(size 1.27 1.27)
				)
			)
		)
		(property "Value" "66K5R2F-GP"
			(at 0.064008 -3.993896 270)
			(unlocked yes)
			(layer "F.Fab")
			(hide yes)
			(effects
				(font
					(size 1.016 1.016)
					(thickness 0.1524)
				)
			)
		)
		(property "Device Type" "R402H16"
			(at 0.064008 -5.517896 270)
			(unlocked yes)
			(layer "F.Fab")
			(hide yes)
			(effects
				(font
					(size 1.016 1.016)
					(thickness 0.1524)
				)
			)
		)
		(duplicate_pad_numbers_are_jumpers no)
		(fp_line
			(start -0.508 -0.9398)
			(end -0.508 0.9398)
			(stroke
				(width 0.1524)
				(type default)
			)
			(layer "F.SilkS")
		)
		(fp_line
			(start 0.508 -0.9398)
			(end -0.508 -0.9398)
			(stroke
				(width 0.1524)
				(type default)
			)
			(layer "F.SilkS")
		)
		(fp_rect
			(start -0.508 0.9398)
			(end 0.508 -0.9398)
			(stroke
				(width 0)
				(type default)
			)
			(fill no)
			(layer "F.CrtYd")
		)
		(fp_rect
			(start -0.508 0.9398)
			(end 0.508 -0.9398)
			(stroke
				(width 0)
				(type default)
			)
			(fill no)
			(layer "F.Fab")
		)
		(pad "1" smd custom
			(at 0 -0.4445 270)
			(size 0.1397 0.1397)
			(layers "F.Cu" "F.Mask" "F.Paste")
			(net "MB0_ISET_R")
			(options
				(clearance outline)
				(anchor circle)
			)
			(primitives
				(gr_poly
					(pts
						(arc
							(start -0.1778 -0.2794)
							(mid -0.249642 -0.249642)
							(end -0.2794 -0.1778)
						)
						(arc
							(start -0.2794 0.1778)
							(mid -0.249642 0.249642)
							(end -0.1778 0.2794)
						)
						(arc
							(start 0.1778 0.2794)
							(mid 0.249642 0.249642)
							(end 0.2794 0.1778)
						)
						(arc
							(start 0.2794 -0.1778)
							(mid 0.249642 -0.249642)
							(end 0.1778 -0.2794)
						)
					)
					(width 0)
					(fill yes)
				)
			)
		)
		(pad "2" smd custom
			(at 0 0.4445 270)
			(size 0.1397 0.1397)
			(layers "F.Cu" "F.Mask" "F.Paste")
			(net "AGND_CURRENT_MON")
			(options
				(clearance outline)
				(anchor circle)
			)
			(primitives
				(gr_poly
					(pts
						(arc
							(start -0.1778 -0.2794)
							(mid -0.249642 -0.249642)
							(end -0.2794 -0.1778)
						)
						(arc
							(start -0.2794 0.1778)
							(mid -0.249642 0.249642)
							(end -0.1778 0.2794)
						)
						(arc
							(start 0.1778 0.2794)
							(mid 0.249642 0.249642)
							(end 0.2794 0.1778)
						)
						(arc
							(start 0.2794 -0.1778)
							(mid 0.249642 -0.249642)
							(end 0.1778 -0.2794)
						)
					)
					(width 0)
					(fill yes)
				)
			)
		)
	)
	(footprint ""
		(layer "F.Cu")
		(at 214.117936 -94.683326 180)
		(property "Reference" "C644"
			(at 0 0 180)
			(layer "F.SilkS")
			(hide yes)
			(effects
				(font
					(size 1.27 1.27)
				)
			)
		)
		(property "Value" "SC470P50V2KX-3GP"
			(at 1.1811 -2.7051 180)
			(unlocked yes)
			(layer "F.Fab")
			(hide yes)
			(effects
				(font
					(size 1.016 1.016)
					(thickness 0.1524)
				)
			)
		)
		(property "Device Type" "C402H22"
			(at 1.1811 -4.2291 180)
			(unlocked yes)
			(layer "F.Fab")
			(hide yes)
			(effects
				(font
					(size 1.016 1.016)
					(thickness 0.1524)
				)
			)
		)
		(duplicate_pad_numbers_are_jumpers no)
		(fp_rect
			(start -0.4318 0.9525)
			(end 0.4318 -0.9525)
			(stroke
				(width 0)
				(type default)
			)
			(fill no)
			(layer "F.CrtYd")
		)
		(fp_rect
			(start -0.4318 0.9525)
			(end 0.4318 -0.9525)
			(stroke
				(width 0)
				(type default)
			)
			(fill no)
			(layer "F.Fab")
		)
		(pad "1" smd custom
			(at 0 -0.4445 180)
			(size 0.1524 0.1524)
			(layers "F.Cu" "F.Mask" "F.Paste")
			(net "P3V3_M2_LL_R")
			(options
				(clearance outline)
				(anchor circle)
			)
			(primitives
				(gr_poly
					(pts
						(arc
							(start 0.3048 -0.2032)
							(mid 0.275042 -0.275042)
							(end 0.2032 -0.3048)
						)
						(arc
							(start -0.2032 -0.3048)
							(mid -0.275042 -0.275042)
							(end -0.3048 -0.2032)
						)
						(arc
							(start -0.3048 0.2032)
							(mid -0.275042 0.275042)
							(end -0.2032 0.3048)
						)
						(arc
							(start 0.2032 0.3048)
							(mid 0.275042 0.275042)
							(end 0.3048 0.2032)
						)
					)
					(width 0)
					(fill yes)
				)
			)
		)
		(pad "2" smd custom
			(at 0 0.4445 180)
			(size 0.1524 0.1524)
			(layers "F.Cu" "F.Mask" "F.Paste")
			(net "P3V3_M2_VFB")
			(options
				(clearance outline)
				(anchor circle)
			)
			(primitives
				(gr_poly
					(pts
						(arc
							(start 0.3048 -0.2032)
							(mid 0.275042 -0.275042)
							(end 0.2032 -0.3048)
						)
						(arc
							(start -0.2032 -0.3048)
							(mid -0.275042 -0.275042)
							(end -0.3048 -0.2032)
						)
						(arc
							(start -0.3048 0.2032)
							(mid -0.275042 0.275042)
							(end -0.2032 0.3048)
						)
						(arc
							(start 0.2032 0.3048)
							(mid 0.275042 0.275042)
							(end 0.3048 0.2032)
						)
					)
					(width 0)
					(fill yes)
				)
			)
		)
	)
	(footprint ""
		(layer "F.Cu")
		(at 26.416 -122.047)
		(property "Reference" "R85"
			(at 0 0 0)
			(layer "F.SilkS")
			(hide yes)
			(effects
				(font
					(size 1.27 1.27)
				)
			)
		)
		(property "Value" "100KR2F-L1-GP"
			(at 0.064008 -3.993896 0)
			(unlocked yes)
			(layer "F.Fab")
			(hide yes)
			(effects
				(font
					(size 1.016 1.016)
					(thickness 0.1524)
				)
			)
		)
		(property "Device Type" "R402H16"
			(at 0.064008 -5.517896 0)
			(unlocked yes)
			(layer "F.Fab")
			(hide yes)
			(effects
				(font
					(size 1.016 1.016)
					(thickness 0.1524)
				)
			)
		)
		(duplicate_pad_numbers_are_jumpers no)
		(fp_line
			(start -0.508 -0.9398)
			(end -0.508 0.9398)
			(stroke
				(width 0.1524)
				(type default)
			)
			(layer "F.SilkS")
		)
		(fp_line
			(start 0.508 -0.9398)
			(end -0.508 -0.9398)
			(stroke
				(width 0.1524)
				(type default)
			)
			(layer "F.SilkS")
		)
		(fp_rect
			(start -0.508 0.9398)
			(end 0.508 -0.9398)
			(stroke
				(width 0)
				(type default)
			)
			(fill no)
			(layer "F.CrtYd")
		)
		(fp_rect
			(start -0.508 0.9398)
			(end 0.508 -0.9398)
			(stroke
				(width 0)
				(type default)
			)
			(fill no)
			(layer "F.Fab")
		)
		(pad "1" smd custom
			(at 0 -0.4445)
			(size 0.1397 0.1397)
			(layers "F.Cu" "F.Mask" "F.Paste")
			(net "WP_ENABLE")
			(options
				(clearance outline)
				(anchor circle)
			)
			(primitives
				(gr_poly
					(pts
						(arc
							(start -0.1778 -0.2794)
							(mid -0.249642 -0.249642)
							(end -0.2794 -0.1778)
						)
						(arc
							(start -0.2794 0.1778)
							(mid -0.249642 0.249642)
							(end -0.1778 0.2794)
						)
						(arc
							(start 0.1778 0.2794)
							(mid 0.249642 0.249642)
							(end 0.2794 0.1778)
						)
						(arc
							(start 0.2794 -0.1778)
							(mid 0.249642 -0.249642)
							(end 0.1778 -0.2794)
						)
					)
					(width 0)
					(fill yes)
				)
			)
		)
		(pad "2" smd custom
			(at 0 0.4445)
			(size 0.1397 0.1397)
			(layers "F.Cu" "F.Mask" "F.Paste")
			(net "GND")
			(options
				(clearance outline)
				(anchor circle)
			)
			(primitives
				(gr_poly
					(pts
						(arc
							(start -0.1778 -0.2794)
							(mid -0.249642 -0.249642)
							(end -0.2794 -0.1778)
						)
						(arc
							(start -0.2794 0.1778)
							(mid -0.249642 0.249642)
							(end -0.1778 0.2794)
						)
						(arc
							(start 0.1778 0.2794)
							(mid 0.249642 0.249642)
							(end 0.2794 0.1778)
						)
						(arc
							(start 0.2794 -0.1778)
							(mid 0.249642 -0.249642)
							(end 0.1778 -0.2794)
						)
					)
					(width 0)
					(fill yes)
				)
			)
		)
	)
	(footprint ""
		(layer "F.Cu")
		(at 70.59803 -139.546076 90)
		(property "Reference" "U5"
			(at 0 0 90)
			(layer "F.SilkS")
			(hide yes)
			(effects
				(font
					(size 1.27 1.27)
				)
			)
		)
		(property "Value" "74LVC2G07GW-GP"
			(at -2.3622 -8.2042 90)
			(unlocked yes)
			(layer "F.Fab")
			(hide yes)
			(effects
				(font
					(size 1.016 1.016)
					(thickness 0.1524)
				)
			)
		)
		(property "Device Type" "SOT-363H44"
			(at -2.3622 -10.1092 90)
			(unlocked yes)
			(layer "F.Fab")
			(hide yes)
			(effects
				(font
					(size 1.016 1.016)
					(thickness 0.1524)
				)
			)
		)
		(duplicate_pad_numbers_are_jumpers no)
		(fp_line
			(start 1.4478 -1.7018)
			(end -1.4478 -1.7018)
			(stroke
				(width 0.1524)
				(type default)
			)
			(layer "F.SilkS")
		)
		(fp_line
			(start -1.4478 -1.7018)
			(end -1.4478 1.7018)
			(stroke
				(width 0.1524)
				(type default)
			)
			(layer "F.SilkS")
		)
		(fp_line
			(start -1.27 1.524)
			(end -1.27 0.6604)
			(stroke
				(width 0.4826)
				(type default)
			)
			(layer "F.SilkS")
		)
		(fp_line
			(start 1.4478 1.7018)
			(end 1.4478 -1.7018)
			(stroke
				(width 0.1524)
				(type default)
			)
			(layer "F.SilkS")
		)
		(fp_line
			(start -1.4478 1.7018)
			(end 1.4478 1.7018)
			(stroke
				(width 0.1524)
				(type default)
			)
			(layer "F.SilkS")
		)
		(fp_poly
			(pts
				(xy -1.524 -1.778) (xy 1.524 -1.778) (xy 1.524 1.778) (xy -1.524 1.778)
			)
			(stroke
				(width 0)
				(type default)
			)
			(fill no)
			(layer "F.CrtYd")
		)
		(fp_poly
			(pts
				(xy -1.524 -1.778) (xy 1.524 -1.778) (xy 1.524 1.778) (xy -1.524 1.778)
			)
			(stroke
				(width 0)
				(type default)
			)
			(fill no)
			(layer "F.Fab")
		)
		(pad "1" smd rect
			(at -0.65024 0.9398 90)
			(size 0.4064 1.016)
			(layers "F.Cu" "F.Mask" "F.Paste")
			(net "FP_PWR_BTN_N_R")
		)
		(pad "2" smd rect
			(at 0 0.9398 90)
			(size 0.4064 1.016)
			(layers "F.Cu" "F.Mask" "F.Paste")
			(net "GND")
		)
		(pad "3" smd rect
			(at 0.65024 0.9398 90)
			(size 0.4064 1.016)
			(layers "F.Cu" "F.Mask" "F.Paste")
			(net "FP_RESET_RC_N")
		)
		(pad "4" smd rect
			(at 0.65024 -0.9398 90)
			(size 0.4064 1.016)
			(layers "F.Cu" "F.Mask" "F.Paste")
			(net "FP_RETBTN")
		)
		(pad "5" smd rect
			(at 0 -0.9398 90)
			(size 0.4064 1.016)
			(layers "F.Cu" "F.Mask" "F.Paste")
			(net "P3V3_STBY")
		)
		(pad "6" smd rect
			(at -0.65024 -0.9398 90)
			(size 0.4064 1.016)
			(layers "F.Cu" "F.Mask" "F.Paste")
			(net "FP_PWRBTN")
		)
	)
	(footprint ""
		(layer "F.Cu")
		(at 165.619684 -132.507482 90)
		(property "Reference" "R804"
			(at 0 0 90)
			(layer "F.SilkS")
			(hide yes)
			(effects
				(font
					(size 1.27 1.27)
				)
			)
		)
		(property "Value" "4K7R2F-GP"
			(at 0.064008 -3.993896 90)
			(unlocked yes)
			(layer "F.Fab")
			(hide yes)
			(effects
				(font
					(size 1.016 1.016)
					(thickness 0.1524)
				)
			)
		)
		(property "Device Type" "R402H16"
			(at 0.064008 -5.517896 90)
			(unlocked yes)
			(layer "F.Fab")
			(hide yes)
			(effects
				(font
					(size 1.016 1.016)
					(thickness 0.1524)
				)
			)
		)
		(duplicate_pad_numbers_are_jumpers no)
		(fp_line
			(start 0.508 -0.9398)
			(end -0.508 -0.9398)
			(stroke
				(width 0.1524)
				(type default)
			)
			(layer "F.SilkS")
		)
		(fp_line
			(start -0.508 -0.9398)
			(end -0.508 0.9398)
			(stroke
				(width 0.1524)
				(type default)
			)
			(layer "F.SilkS")
		)
		(fp_rect
			(start -0.508 0.9398)
			(end 0.508 -0.9398)
			(stroke
				(width 0)
				(type default)
			)
			(fill no)
			(layer "F.CrtYd")
		)
		(fp_rect
			(start -0.508 0.9398)
			(end 0.508 -0.9398)
			(stroke
				(width 0)
				(type default)
			)
			(fill no)
			(layer "F.Fab")
		)
		(pad "1" smd custom
			(at 0 -0.4445 90)
			(size 0.1397 0.1397)
			(layers "F.Cu" "F.Mask" "F.Paste")
			(net "P3V3_STBY")
			(options
				(clearance outline)
				(anchor circle)
			)
			(primitives
				(gr_poly
					(pts
						(arc
							(start -0.1778 -0.2794)
							(mid -0.249642 -0.249642)
							(end -0.2794 -0.1778)
						)
						(arc
							(start -0.2794 0.1778)
							(mid -0.249642 0.249642)
							(end -0.1778 0.2794)
						)
						(arc
							(start 0.1778 0.2794)
							(mid 0.249642 0.249642)
							(end 0.2794 0.1778)
						)
						(arc
							(start 0.2794 -0.1778)
							(mid 0.249642 -0.249642)
							(end 0.1778 -0.2794)
						)
					)
					(width 0)
					(fill yes)
				)
			)
		)
		(pad "2" smd custom
			(at 0 0.4445 90)
			(size 0.1397 0.1397)
			(layers "F.Cu" "F.Mask" "F.Paste")
			(net "M2_2_PRESENT_N")
			(options
				(clearance outline)
				(anchor circle)
			)
			(primitives
				(gr_poly
					(pts
						(arc
							(start -0.1778 -0.2794)
							(mid -0.249642 -0.249642)
							(end -0.2794 -0.1778)
						)
						(arc
							(start -0.2794 0.1778)
							(mid -0.249642 0.249642)
							(end -0.1778 0.2794)
						)
						(arc
							(start 0.1778 0.2794)
							(mid 0.249642 0.249642)
							(end 0.2794 0.1778)
						)
						(arc
							(start 0.2794 -0.1778)
							(mid 0.249642 -0.249642)
							(end 0.1778 -0.2794)
						)
					)
					(width 0)
					(fill yes)
				)
			)
		)
	)
	(footprint ""
		(layer "F.Cu")
		(at 78.122018 -90.155268 90)
		(property "Reference" "VIA7"
			(at 0 0 90)
			(layer "F.SilkS")
			(hide yes)
			(effects
				(font
					(size 1.27 1.27)
				)
			)
		)
		(property "Value" "85OHM-8L-1D6MM-L16L18-GP"
			(at 4.064 0.6096 90)
			(unlocked yes)
			(layer "F.Fab")
			(hide yes)
			(effects
				(font
					(size 1.016 1.016)
					(thickness 0.1524)
				)
			)
		)
		(property "Device Type" "VIA-PCIE-4P-368076"
			(at 4.064 -0.9144 90)
			(unlocked yes)
			(layer "F.Fab")
			(hide yes)
			(effects
				(font
					(size 1.016 1.016)
					(thickness 0.1524)
				)
			)
		)
		(duplicate_pad_numbers_are_jumpers no)
		(fp_rect
			(start -1.8415 0.381)
			(end 1.8415 -0.381)
			(stroke
				(width 0)
				(type default)
			)
			(fill no)
			(layer "F.CrtYd")
		)
		(fp_rect
			(start -1.8415 0.381)
			(end 1.8415 -0.381)
			(stroke
				(width 0)
				(type default)
			)
			(fill no)
			(layer "F.Fab")
		)
		(pad "1" thru_hole circle
			(at -1.4605 0 90)
			(size 0.508 0.508)
			(drill 0.254)
			(layers "*.Cu" "*.Mask")
			(remove_unused_layers no)
			(net "GND")
			(clearance 0.127)
			(thermal_gap 0.127)
		)
		(pad "2" thru_hole circle
			(at -0.4445 0 90)
			(size 0.508 0.508)
			(drill 0.254)
			(layers "*.Cu" "*.Mask")
			(remove_unused_layers no)
			(net "PCIE_COMP_TO_IOM_22_DP")
			(clearance 0.127)
			(thermal_gap 0.127)
		)
		(pad "3" thru_hole circle
			(at 0.4445 0 90)
			(size 0.508 0.508)
			(drill 0.254)
			(layers "*.Cu" "*.Mask")
			(remove_unused_layers no)
			(net "PCIE_COMP_TO_IOM_22_DN")
			(clearance 0.127)
			(thermal_gap 0.127)
		)
		(pad "4" thru_hole circle
			(at 1.4605 0 90)
			(size 0.508 0.508)
			(drill 0.254)
			(layers "*.Cu" "*.Mask")
			(remove_unused_layers no)
			(net "GND")
			(clearance 0.127)
			(thermal_gap 0.127)
		)
	)
	(footprint ""
		(layer "F.Cu")
		(at 92.775786 -44.664376 90)
		(property "Reference" "PQ2"
			(at 0 0 90)
			(layer "F.SilkS")
			(hide yes)
			(effects
				(font
					(size 1.27 1.27)
				)
			)
		)
		(property "Value" "2N7002K-1-GP"
			(at 0.127 -8.9662 90)
			(unlocked yes)
			(layer "F.Fab")
			(hide yes)
			(effects
				(font
					(size 1.016 1.016)
					(thickness 0.1524)
				)
			)
		)
		(property "Device Type" "SOT23DGS2D4H44"
			(at 0.127 -10.4902 90)
			(unlocked yes)
			(layer "F.Fab")
			(hide yes)
			(effects
				(font
					(size 1.016 1.016)
					(thickness 0.1524)
				)
			)
		)
		(duplicate_pad_numbers_are_jumpers no)
		(fp_line
			(start 1.651 -1.778)
			(end -1.651 -1.778)
			(stroke
				(width 0.1524)
				(type default)
			)
			(layer "F.SilkS")
		)
		(fp_line
			(start -1.651 -1.778)
			(end -1.651 1.778)
			(stroke
				(width 0.1524)
				(type default)
			)
			(layer "F.SilkS")
		)
		(fp_line
			(start 1.651 1.778)
			(end 1.651 -1.778)
			(stroke
				(width 0.1524)
				(type default)
			)
			(layer "F.SilkS")
		)
		(fp_line
			(start -1.651 1.778)
			(end 1.651 1.778)
			(stroke
				(width 0.1524)
				(type default)
			)
			(layer "F.SilkS")
		)
		(fp_poly
			(pts
				(xy -1.778 1.8796) (xy -1.778 -1.8796) (xy 1.778 -1.8796) (xy 1.778 1.8796)
			)
			(stroke
				(width 0)
				(type default)
			)
			(fill no)
			(layer "F.CrtYd")
		)
		(fp_poly
			(pts
				(xy -1.778 1.8796) (xy -1.778 -1.8796) (xy 1.778 -1.8796) (xy 1.778 1.8796)
			)
			(stroke
				(width 0)
				(type default)
			)
			(fill no)
			(layer "F.Fab")
		)
		(pad "D" smd custom
			(at 0 -0.9525 90)
			(size 0.1905 0.1905)
			(layers "F.Cu" "F.Mask" "F.Paste")
			(net "PQ2_D")
			(options
				(clearance outline)
				(anchor circle)
			)
			(primitives
				(gr_poly
					(pts
						(arc
							(start -0.1778 0.5715)
							(mid -0.321484 0.511984)
							(end -0.381 0.3683)
						)
						(arc
							(start -0.381 -0.3683)
							(mid -0.321484 -0.511984)
							(end -0.1778 -0.5715)
						)
						(arc
							(start 0.1778 -0.5715)
							(mid 0.321484 -0.511984)
							(end 0.381 -0.3683)
						)
						(arc
							(start 0.381 0.3683)
							(mid 0.321484 0.511984)
							(end 0.1778 0.5715)
						)
					)
					(width 0)
					(fill yes)
				)
			)
		)
		(pad "G" smd custom
			(at -0.98425 0.9525 90)
			(size 0.1905 0.1905)
			(layers "F.Cu" "F.Mask" "F.Paste")
			(net "PQ2_G")
			(options
				(clearance outline)
				(anchor circle)
			)
			(primitives
				(gr_poly
					(pts
						(arc
							(start -0.1778 0.5715)
							(mid -0.321484 0.511984)
							(end -0.381 0.3683)
						)
						(arc
							(start -0.381 -0.3683)
							(mid -0.321484 -0.511984)
							(end -0.1778 -0.5715)
						)
						(arc
							(start 0.1778 -0.5715)
							(mid 0.321484 -0.511984)
							(end 0.381 -0.3683)
						)
						(arc
							(start 0.381 0.3683)
							(mid 0.321484 0.511984)
							(end 0.1778 0.5715)
						)
					)
					(width 0)
					(fill yes)
				)
			)
		)
		(pad "S" smd custom
			(at 0.98425 0.9525 90)
			(size 0.1905 0.1905)
			(layers "F.Cu" "F.Mask" "F.Paste")
			(net "P3V3_EN_R")
			(options
				(clearance outline)
				(anchor circle)
			)
			(primitives
				(gr_poly
					(pts
						(arc
							(start -0.1778 0.5715)
							(mid -0.321484 0.511984)
							(end -0.381 0.3683)
						)
						(arc
							(start -0.381 -0.3683)
							(mid -0.321484 -0.511984)
							(end -0.1778 -0.5715)
						)
						(arc
							(start 0.1778 -0.5715)
							(mid 0.321484 -0.511984)
							(end 0.381 -0.3683)
						)
						(arc
							(start 0.381 0.3683)
							(mid 0.321484 0.511984)
							(end 0.1778 0.5715)
						)
					)
					(width 0)
					(fill yes)
				)
			)
		)
	)
	(footprint ""
		(layer "F.Cu")
		(at 73.92797 -138.863324 -90)
		(property "Reference" "R51"
			(at 0 0 270)
			(layer "F.SilkS")
			(hide yes)
			(effects
				(font
					(size 1.27 1.27)
				)
			)
		)
		(property "Value" "33R2F-3-GP"
			(at 0.064008 -3.993896 270)
			(unlocked yes)
			(layer "F.Fab")
			(hide yes)
			(effects
				(font
					(size 1.016 1.016)
					(thickness 0.1524)
				)
			)
		)
		(property "Device Type" "R402H16"
			(at 0.064008 -5.517896 270)
			(unlocked yes)
			(layer "F.Fab")
			(hide yes)
			(effects
				(font
					(size 1.016 1.016)
					(thickness 0.1524)
				)
			)
		)
		(duplicate_pad_numbers_are_jumpers no)
		(fp_line
			(start -0.508 -0.9398)
			(end -0.508 0.9398)
			(stroke
				(width 0.1524)
				(type default)
			)
			(layer "F.SilkS")
		)
		(fp_line
			(start 0.508 -0.9398)
			(end -0.508 -0.9398)
			(stroke
				(width 0.1524)
				(type default)
			)
			(layer "F.SilkS")
		)
		(fp_rect
			(start -0.508 0.9398)
			(end 0.508 -0.9398)
			(stroke
				(width 0)
				(type default)
			)
			(fill no)
			(layer "F.CrtYd")
		)
		(fp_rect
			(start -0.508 0.9398)
			(end 0.508 -0.9398)
			(stroke
				(width 0)
				(type default)
			)
			(fill no)
			(layer "F.Fab")
		)
		(pad "1" smd custom
			(at 0 -0.4445 270)
			(size 0.1397 0.1397)
			(layers "F.Cu" "F.Mask" "F.Paste")
			(net "FP_PWR_BTN_N")
			(options
				(clearance outline)
				(anchor circle)
			)
			(primitives
				(gr_poly
					(pts
						(arc
							(start -0.1778 -0.2794)
							(mid -0.249642 -0.249642)
							(end -0.2794 -0.1778)
						)
						(arc
							(start -0.2794 0.1778)
							(mid -0.249642 0.249642)
							(end -0.1778 0.2794)
						)
						(arc
							(start 0.1778 0.2794)
							(mid 0.249642 0.249642)
							(end 0.2794 0.1778)
						)
						(arc
							(start 0.2794 -0.1778)
							(mid 0.249642 -0.249642)
							(end 0.1778 -0.2794)
						)
					)
					(width 0)
					(fill yes)
				)
			)
		)
		(pad "2" smd custom
			(at 0 0.4445 270)
			(size 0.1397 0.1397)
			(layers "F.Cu" "F.Mask" "F.Paste")
			(net "FP_PWR_BTN_N_R")
			(options
				(clearance outline)
				(anchor circle)
			)
			(primitives
				(gr_poly
					(pts
						(arc
							(start -0.1778 -0.2794)
							(mid -0.249642 -0.249642)
							(end -0.2794 -0.1778)
						)
						(arc
							(start -0.2794 0.1778)
							(mid -0.249642 0.249642)
							(end -0.1778 0.2794)
						)
						(arc
							(start 0.1778 0.2794)
							(mid 0.249642 0.249642)
							(end 0.2794 0.1778)
						)
						(arc
							(start 0.2794 -0.1778)
							(mid 0.249642 -0.249642)
							(end 0.1778 -0.2794)
						)
					)
					(width 0)
					(fill yes)
				)
			)
		)
	)
	(footprint ""
		(layer "F.Cu")
		(at 213.011258 -96.65081)
		(property "Reference" "R825"
			(at 0 0 0)
			(layer "F.SilkS")
			(hide yes)
			(effects
				(font
					(size 1.27 1.27)
				)
			)
		)
		(property "Value" "10KR2F-2-GP"
			(at 0.064008 -3.993896 0)
			(unlocked yes)
			(layer "F.Fab")
			(hide yes)
			(effects
				(font
					(size 1.016 1.016)
					(thickness 0.1524)
				)
			)
		)
		(property "Device Type" "R402H16"
			(at 0.064008 -5.517896 0)
			(unlocked yes)
			(layer "F.Fab")
			(hide yes)
			(effects
				(font
					(size 1.016 1.016)
					(thickness 0.1524)
				)
			)
		)
		(duplicate_pad_numbers_are_jumpers no)
		(fp_line
			(start -0.508 -0.9398)
			(end -0.508 0.9398)
			(stroke
				(width 0.1524)
				(type default)
			)
			(layer "F.SilkS")
		)
		(fp_line
			(start 0.508 -0.9398)
			(end -0.508 -0.9398)
			(stroke
				(width 0.1524)
				(type default)
			)
			(layer "F.SilkS")
		)
		(fp_rect
			(start -0.508 0.9398)
			(end 0.508 -0.9398)
			(stroke
				(width 0)
				(type default)
			)
			(fill no)
			(layer "F.CrtYd")
		)
		(fp_rect
			(start -0.508 0.9398)
			(end 0.508 -0.9398)
			(stroke
				(width 0)
				(type default)
			)
			(fill no)
			(layer "F.Fab")
		)
		(pad "1" smd custom
			(at 0 -0.4445)
			(size 0.1397 0.1397)
			(layers "F.Cu" "F.Mask" "F.Paste")
			(net "AGND_P3V3_M2")
			(options
				(clearance outline)
				(anchor circle)
			)
			(primitives
				(gr_poly
					(pts
						(arc
							(start -0.1778 -0.2794)
							(mid -0.249642 -0.249642)
							(end -0.2794 -0.1778)
						)
						(arc
							(start -0.2794 0.1778)
							(mid -0.249642 0.249642)
							(end -0.1778 0.2794)
						)
						(arc
							(start 0.1778 0.2794)
							(mid 0.249642 0.249642)
							(end 0.2794 0.1778)
						)
						(arc
							(start 0.2794 -0.1778)
							(mid 0.249642 -0.249642)
							(end 0.1778 -0.2794)
						)
					)
					(width 0)
					(fill yes)
				)
			)
		)
		(pad "2" smd custom
			(at 0 0.4445)
			(size 0.1397 0.1397)
			(layers "F.Cu" "F.Mask" "F.Paste")
			(net "P3V3_M2_VFB")
			(options
				(clearance outline)
				(anchor circle)
			)
			(primitives
				(gr_poly
					(pts
						(arc
							(start -0.1778 -0.2794)
							(mid -0.249642 -0.249642)
							(end -0.2794 -0.1778)
						)
						(arc
							(start -0.2794 0.1778)
							(mid -0.249642 0.249642)
							(end -0.1778 0.2794)
						)
						(arc
							(start 0.1778 0.2794)
							(mid 0.249642 0.249642)
							(end 0.2794 0.1778)
						)
						(arc
							(start 0.2794 -0.1778)
							(mid 0.249642 -0.249642)
							(end 0.1778 -0.2794)
						)
					)
					(width 0)
					(fill yes)
				)
			)
		)
	)
	(footprint ""
		(layer "F.Cu")
		(at 92.499942 -187.999878)
		(property "Reference" ""
			(at 0 0 0)
			(layer "F.SilkS")
			(hide yes)
			(effects
				(font
					(size 1.27 1.27)
				)
			)
		)
		(property "Value" "*"
			(at -6.38175 0.19685 0)
			(unlocked yes)
			(layer "F.Fab")
			(hide yes)
			(effects
				(font
					(size 1.016 1.016)
					(thickness 0.1524)
				)
			)
		)
		(duplicate_pad_numbers_are_jumpers no)
		(fp_poly
			(pts
				(arc
					(start 5.0673 0)
					(mid -5.0673 0)
					(end 5.0673 0)
				)
			)
			(stroke
				(width 0)
				(type default)
			)
			(fill no)
			(layer "B.CrtYd")
		)
		(fp_poly
			(pts
				(arc
					(start 5.0673 0)
					(mid -5.0673 0)
					(end 5.0673 0)
				)
			)
			(stroke
				(width 0)
				(type default)
			)
			(fill no)
			(layer "F.CrtYd")
		)
		(fp_poly
			(pts
				(arc
					(start 5.0673 0)
					(mid -5.0673 0)
					(end 5.0673 0)
				)
			)
			(stroke
				(width 0)
				(type default)
			)
			(fill no)
			(layer "B.Fab")
		)
		(fp_poly
			(pts
				(arc
					(start 5.0673 0)
					(mid -5.0673 0)
					(end 5.0673 0)
				)
			)
			(stroke
				(width 0)
				(type default)
			)
			(fill no)
			(layer "F.Fab")
		)
		(pad "1" thru_hole circle
			(at 0 0)
			(size 9.525 9.525)
			(drill 3.5052)
			(layers "*.Cu" "*.Mask")
			(remove_unused_layers no)
			(net "Net_33")
			(clearance -2.5019)
			(thermal_gap 0.3048)
			(padstack
				(mode front_inner_back)
				(layer "Inner"
					(shape circle)
					(size 3.9116 3.9116)
					(clearance 0.3048)
				)
				(layer "B.Cu"
					(shape circle)
					(size 9.525 9.525)
					(clearance -2.5019)
				)
			)
		)
	)
	(footprint ""
		(layer "F.Cu")
		(at 149.516338 -8.586978)
		(property "Reference" "G5"
			(at 0 0 0)
			(layer "F.SilkS")
			(hide yes)
			(effects
				(font
					(size 1.27 1.27)
				)
			)
		)
		(property "Value" "COPPER-CLOSE-GP-U"
			(at 0.0762 -2.8702 0)
			(unlocked yes)
			(layer "F.Fab")
			(hide yes)
			(effects
				(font
					(size 1.016 1.016)
					(thickness 0.1524)
				)
			)
		)
		(property "Device Type" "CON2C-U"
			(at 0.0762 -4.3942 0)
			(unlocked yes)
			(layer "F.Fab")
			(hide yes)
			(effects
				(font
					(size 1.016 1.016)
					(thickness 0.1524)
				)
			)
		)
		(duplicate_pad_numbers_are_jumpers no)
		(fp_rect
			(start -0.9398 0.9652)
			(end 0.9398 -0.9652)
			(stroke
				(width 0)
				(type default)
			)
			(fill no)
			(layer "F.CrtYd")
		)
		(fp_rect
			(start -0.9398 0.9652)
			(end 0.9398 -0.9652)
			(stroke
				(width 0)
				(type default)
			)
			(fill no)
			(layer "F.Fab")
		)
		(pad "1" smd custom
			(at 0 -0.5334)
			(size 0.17145 0.17145)
			(layers "F.Cu" "F.Mask" "F.Paste")
			(net "AGND_P1V8_STBY")
			(options
				(clearance outline)
				(anchor circle)
			)
			(primitives
				(gr_poly
					(pts
						(xy -0.127 0.3429) (xy -0.127 0.1651) (xy -0.635 -0.3429) (xy 0.635 -0.3429) (xy 0.127 0.1651)
						(xy 0.127 0.3429)
					)
					(width 0)
					(fill yes)
				)
			)
		)
		(pad "2" smd custom
			(at 0 0.5334)
			(size 0.17145 0.17145)
			(layers "F.Cu" "F.Mask" "F.Paste")
			(net "GND")
			(options
				(clearance outline)
				(anchor circle)
			)
			(primitives
				(gr_poly
					(pts
						(xy -0.635 0.3429) (xy -0.127 -0.1651) (xy -0.127 -0.3429) (xy 0.127 -0.3429) (xy 0.127 -0.1651)
						(xy 0.635 0.3429)
					)
					(width 0)
					(fill yes)
				)
			)
		)
	)
	(footprint ""
		(layer "F.Cu")
		(at 53.848 -127.254 180)
		(property "Reference" "R610"
			(at 0 0 180)
			(layer "F.SilkS")
			(hide yes)
			(effects
				(font
					(size 1.27 1.27)
				)
			)
		)
		(property "Value" "100KR2F-L1-GP"
			(at 0.064008 -3.993896 180)
			(unlocked yes)
			(layer "F.Fab")
			(hide yes)
			(effects
				(font
					(size 1.016 1.016)
					(thickness 0.1524)
				)
			)
		)
		(property "Device Type" "R402H16"
			(at 0.064008 -5.517896 180)
			(unlocked yes)
			(layer "F.Fab")
			(hide yes)
			(effects
				(font
					(size 1.016 1.016)
					(thickness 0.1524)
				)
			)
		)
		(duplicate_pad_numbers_are_jumpers no)
		(fp_line
			(start 0.508 -0.9398)
			(end -0.508 -0.9398)
			(stroke
				(width 0.1524)
				(type default)
			)
			(layer "F.SilkS")
		)
		(fp_line
			(start -0.508 -0.9398)
			(end -0.508 0.9398)
			(stroke
				(width 0.1524)
				(type default)
			)
			(layer "F.SilkS")
		)
		(fp_rect
			(start -0.508 0.9398)
			(end 0.508 -0.9398)
			(stroke
				(width 0)
				(type default)
			)
			(fill no)
			(layer "F.CrtYd")
		)
		(fp_rect
			(start -0.508 0.9398)
			(end 0.508 -0.9398)
			(stroke
				(width 0)
				(type default)
			)
			(fill no)
			(layer "F.Fab")
		)
		(pad "1" smd custom
			(at 0 -0.4445 180)
			(size 0.1397 0.1397)
			(layers "F.Cu" "F.Mask" "F.Paste")
			(net "FLA1_WP_N")
			(options
				(clearance outline)
				(anchor circle)
			)
			(primitives
				(gr_poly
					(pts
						(arc
							(start -0.1778 -0.2794)
							(mid -0.249642 -0.249642)
							(end -0.2794 -0.1778)
						)
						(arc
							(start -0.2794 0.1778)
							(mid -0.249642 0.249642)
							(end -0.1778 0.2794)
						)
						(arc
							(start 0.1778 0.2794)
							(mid 0.249642 0.249642)
							(end 0.2794 0.1778)
						)
						(arc
							(start 0.2794 -0.1778)
							(mid 0.249642 -0.249642)
							(end 0.1778 -0.2794)
						)
					)
					(width 0)
					(fill yes)
				)
			)
		)
		(pad "2" smd custom
			(at 0 0.4445 180)
			(size 0.1397 0.1397)
			(layers "F.Cu" "F.Mask" "F.Paste")
			(net "GND")
			(options
				(clearance outline)
				(anchor circle)
			)
			(primitives
				(gr_poly
					(pts
						(arc
							(start -0.1778 -0.2794)
							(mid -0.249642 -0.249642)
							(end -0.2794 -0.1778)
						)
						(arc
							(start -0.2794 0.1778)
							(mid -0.249642 0.249642)
							(end -0.1778 0.2794)
						)
						(arc
							(start 0.1778 0.2794)
							(mid 0.249642 0.249642)
							(end 0.2794 0.1778)
						)
						(arc
							(start 0.2794 -0.1778)
							(mid 0.249642 -0.249642)
							(end 0.1778 -0.2794)
						)
					)
					(width 0)
					(fill yes)
				)
			)
		)
	)
	(footprint ""
		(layer "F.Cu")
		(at 82.677 -133.604 -90)
		(property "Reference" "R102"
			(at 0 0 270)
			(layer "F.SilkS")
			(hide yes)
			(effects
				(font
					(size 1.27 1.27)
				)
			)
		)
		(property "Value" "0R2J-2-GP"
			(at 0.064008 -3.993896 270)
			(unlocked yes)
			(layer "F.Fab")
			(hide yes)
			(effects
				(font
					(size 1.016 1.016)
					(thickness 0.1524)
				)
			)
		)
		(property "Device Type" "R402H16"
			(at 0.064008 -5.517896 270)
			(unlocked yes)
			(layer "F.Fab")
			(hide yes)
			(effects
				(font
					(size 1.016 1.016)
					(thickness 0.1524)
				)
			)
		)
		(duplicate_pad_numbers_are_jumpers no)
		(fp_line
			(start -0.508 -0.9398)
			(end -0.508 0.9398)
			(stroke
				(width 0.1524)
				(type default)
			)
			(layer "F.SilkS")
		)
		(fp_line
			(start 0.508 -0.9398)
			(end -0.508 -0.9398)
			(stroke
				(width 0.1524)
				(type default)
			)
			(layer "F.SilkS")
		)
		(fp_rect
			(start -0.508 0.9398)
			(end 0.508 -0.9398)
			(stroke
				(width 0)
				(type default)
			)
			(fill no)
			(layer "F.CrtYd")
		)
		(fp_rect
			(start -0.508 0.9398)
			(end 0.508 -0.9398)
			(stroke
				(width 0)
				(type default)
			)
			(fill no)
			(layer "F.Fab")
		)
		(pad "1" smd custom
			(at 0 -0.4445 270)
			(size 0.1397 0.1397)
			(layers "F.Cu" "F.Mask" "F.Paste")
			(net "BMC_UART_SEL_IN")
			(options
				(clearance outline)
				(anchor circle)
			)
			(primitives
				(gr_poly
					(pts
						(arc
							(start -0.1778 -0.2794)
							(mid -0.249642 -0.249642)
							(end -0.2794 -0.1778)
						)
						(arc
							(start -0.2794 0.1778)
							(mid -0.249642 0.249642)
							(end -0.1778 0.2794)
						)
						(arc
							(start 0.1778 0.2794)
							(mid 0.249642 0.249642)
							(end 0.2794 0.1778)
						)
						(arc
							(start 0.2794 -0.1778)
							(mid 0.249642 -0.249642)
							(end 0.1778 -0.2794)
						)
					)
					(width 0)
					(fill yes)
				)
			)
		)
		(pad "2" smd custom
			(at 0 0.4445 270)
			(size 0.1397 0.1397)
			(layers "F.Cu" "F.Mask" "F.Paste")
			(net "DEBUG_HDR_UART_SEL")
			(options
				(clearance outline)
				(anchor circle)
			)
			(primitives
				(gr_poly
					(pts
						(arc
							(start -0.1778 -0.2794)
							(mid -0.249642 -0.249642)
							(end -0.2794 -0.1778)
						)
						(arc
							(start -0.2794 0.1778)
							(mid -0.249642 0.249642)
							(end -0.1778 0.2794)
						)
						(arc
							(start 0.1778 0.2794)
							(mid 0.249642 0.249642)
							(end 0.2794 0.1778)
						)
						(arc
							(start 0.2794 -0.1778)
							(mid 0.249642 -0.249642)
							(end 0.1778 -0.2794)
						)
					)
					(width 0)
					(fill yes)
				)
			)
		)
	)
	(footprint ""
		(layer "F.Cu")
		(at 39.994332 -161.425128)
		(property "Reference" "R309"
			(at 0 0 0)
			(layer "F.SilkS")
			(hide yes)
			(effects
				(font
					(size 1.27 1.27)
				)
			)
		)
		(property "Value" "4K7R2F-GP"
			(at 0.064008 -3.993896 0)
			(unlocked yes)
			(layer "F.Fab")
			(hide yes)
			(effects
				(font
					(size 1.016 1.016)
					(thickness 0.1524)
				)
			)
		)
		(property "Device Type" "R402H16"
			(at 0.064008 -5.517896 0)
			(unlocked yes)
			(layer "F.Fab")
			(hide yes)
			(effects
				(font
					(size 1.016 1.016)
					(thickness 0.1524)
				)
			)
		)
		(duplicate_pad_numbers_are_jumpers no)
		(fp_line
			(start -0.508 -0.9398)
			(end -0.508 0.9398)
			(stroke
				(width 0.1524)
				(type default)
			)
			(layer "F.SilkS")
		)
		(fp_line
			(start 0.508 -0.9398)
			(end -0.508 -0.9398)
			(stroke
				(width 0.1524)
				(type default)
			)
			(layer "F.SilkS")
		)
		(fp_rect
			(start -0.508 0.9398)
			(end 0.508 -0.9398)
			(stroke
				(width 0)
				(type default)
			)
			(fill no)
			(layer "F.CrtYd")
		)
		(fp_rect
			(start -0.508 0.9398)
			(end 0.508 -0.9398)
			(stroke
				(width 0)
				(type default)
			)
			(fill no)
			(layer "F.Fab")
		)
		(pad "1" smd custom
			(at 0 -0.4445)
			(size 0.1397 0.1397)
			(layers "F.Cu" "F.Mask" "F.Paste")
			(net "P3V3_STBY")
			(options
				(clearance outline)
				(anchor circle)
			)
			(primitives
				(gr_poly
					(pts
						(arc
							(start -0.1778 -0.2794)
							(mid -0.249642 -0.249642)
							(end -0.2794 -0.1778)
						)
						(arc
							(start -0.2794 0.1778)
							(mid -0.249642 0.249642)
							(end -0.1778 0.2794)
						)
						(arc
							(start 0.1778 0.2794)
							(mid 0.249642 0.249642)
							(end 0.2794 0.1778)
						)
						(arc
							(start 0.2794 -0.1778)
							(mid 0.249642 -0.249642)
							(end 0.1778 -0.2794)
						)
					)
					(width 0)
					(fill yes)
				)
			)
		)
		(pad "2" smd custom
			(at 0 0.4445)
			(size 0.1397 0.1397)
			(layers "F.Cu" "F.Mask" "F.Paste")
			(net "BOARD_REV_0")
			(options
				(clearance outline)
				(anchor circle)
			)
			(primitives
				(gr_poly
					(pts
						(arc
							(start -0.1778 -0.2794)
							(mid -0.249642 -0.249642)
							(end -0.2794 -0.1778)
						)
						(arc
							(start -0.2794 0.1778)
							(mid -0.249642 0.249642)
							(end -0.1778 0.2794)
						)
						(arc
							(start 0.1778 0.2794)
							(mid 0.249642 0.249642)
							(end 0.2794 0.1778)
						)
						(arc
							(start 0.2794 -0.1778)
							(mid 0.249642 -0.249642)
							(end 0.1778 -0.2794)
						)
					)
					(width 0)
					(fill yes)
				)
			)
		)
	)
	(footprint ""
		(layer "F.Cu")
		(at 89.468198 -26.4668 90)
		(property "Reference" "D13"
			(at 0 0 90)
			(layer "F.SilkS")
			(hide yes)
			(effects
				(font
					(size 1.27 1.27)
				)
			)
		)
		(property "Value" "PESD5V0S1BL-1-GP"
			(at 1.8923 -1.5621 90)
			(unlocked yes)
			(layer "F.Fab")
			(hide yes)
			(effects
				(font
					(size 1.016 1.016)
					(thickness 0.1524)
				)
			)
		)
		(property "Device Type" "SOD882-10D6-1H20"
			(at 1.8923 -3.0861 90)
			(unlocked yes)
			(layer "F.Fab")
			(hide yes)
			(effects
				(font
					(size 1.016 1.016)
					(thickness 0.1524)
				)
			)
		)
		(duplicate_pad_numbers_are_jumpers no)
		(fp_line
			(start -0.3048 -0.9271)
			(end 0.3048 -0.9271)
			(stroke
				(width 0.254)
				(type default)
			)
			(layer "F.SilkS")
		)
		(fp_rect
			(start -0.2921 0.4953)
			(end 0.2921 -0.4953)
			(stroke
				(width 0)
				(type default)
			)
			(fill no)
			(layer "F.CrtYd")
		)
		(fp_poly
			(pts
				(xy -0.4318 0.8001) (xy -0.4318 -0.266192) (xy -0.2921 -0.266192) (xy -0.2921 0.4953) (xy 0.2921 0.4953)
				(xy 0.2921 -0.4953) (xy -0.2921 -0.4953) (xy -0.2921 -0.2667) (xy -0.4318 -0.2667) (xy -0.4318 -0.8001)
				(xy 0.4318 -0.8001) (xy 0.4318 0.8001)
			)
			(stroke
				(width 0)
				(type default)
			)
			(fill no)
			(layer "F.CrtYd")
		)
		(fp_rect
			(start -0.4318 0.8001)
			(end 0.4318 -0.8001)
			(stroke
				(width 0)
				(type default)
			)
			(fill no)
			(layer "F.Fab")
		)
		(pad "1" smd custom
			(at 0 -0.4445 90)
			(size 0.1143 0.1143)
			(layers "F.Cu" "F.Mask" "F.Paste")
			(net "P5V_VBUS_CONN")
			(options
				(clearance outline)
				(anchor circle)
			)
			(primitives
				(gr_poly
					(pts
						(arc
							(start -0.2032 0.2286)
							(mid -0.275042 0.198842)
							(end -0.3048 0.127)
						)
						(arc
							(start -0.3048 -0.127)
							(mid -0.275042 -0.198842)
							(end -0.2032 -0.2286)
						)
						(arc
							(start 0.2032 -0.2286)
							(mid 0.275042 -0.198842)
							(end 0.3048 -0.127)
						)
						(arc
							(start 0.3048 0.127)
							(mid 0.275042 0.198842)
							(end 0.2032 0.2286)
						)
					)
					(width 0)
					(fill yes)
				)
			)
		)
		(pad "2" smd custom
			(at 0 0.4445 90)
			(size 0.1143 0.1143)
			(layers "F.Cu" "F.Mask" "F.Paste")
			(net "GND")
			(options
				(clearance outline)
				(anchor circle)
			)
			(primitives
				(gr_poly
					(pts
						(arc
							(start 0.2032 -0.2286)
							(mid 0.275042 -0.198842)
							(end 0.3048 -0.127)
						)
						(arc
							(start 0.3048 0.127)
							(mid 0.275042 0.198842)
							(end 0.2032 0.2286)
						)
						(arc
							(start -0.2032 0.2286)
							(mid -0.275042 0.198842)
							(end -0.3048 0.127)
						)
						(arc
							(start -0.3048 -0.127)
							(mid -0.275042 -0.198842)
							(end -0.2032 -0.2286)
						)
					)
					(width 0)
					(fill yes)
				)
			)
		)
	)
	(footprint ""
		(layer "F.Cu")
		(at 37.589968 -130.984244 90)
		(property "Reference" "R377"
			(at 0 0 90)
			(layer "F.SilkS")
			(hide yes)
			(effects
				(font
					(size 1.27 1.27)
				)
			)
		)
		(property "Value" "4K7R2F-GP"
			(at 0.064008 -3.993896 90)
			(unlocked yes)
			(layer "F.Fab")
			(hide yes)
			(effects
				(font
					(size 1.016 1.016)
					(thickness 0.1524)
				)
			)
		)
		(property "Device Type" "R402H16"
			(at 0.064008 -5.517896 90)
			(unlocked yes)
			(layer "F.Fab")
			(hide yes)
			(effects
				(font
					(size 1.016 1.016)
					(thickness 0.1524)
				)
			)
		)
		(duplicate_pad_numbers_are_jumpers no)
		(fp_line
			(start 0.508 -0.9398)
			(end -0.508 -0.9398)
			(stroke
				(width 0.1524)
				(type default)
			)
			(layer "F.SilkS")
		)
		(fp_line
			(start -0.508 -0.9398)
			(end -0.508 0.9398)
			(stroke
				(width 0.1524)
				(type default)
			)
			(layer "F.SilkS")
		)
		(fp_rect
			(start -0.508 0.9398)
			(end 0.508 -0.9398)
			(stroke
				(width 0)
				(type default)
			)
			(fill no)
			(layer "F.CrtYd")
		)
		(fp_rect
			(start -0.508 0.9398)
			(end 0.508 -0.9398)
			(stroke
				(width 0)
				(type default)
			)
			(fill no)
			(layer "F.Fab")
		)
		(pad "1" smd custom
			(at 0 -0.4445 90)
			(size 0.1397 0.1397)
			(layers "F.Cu" "F.Mask" "F.Paste")
			(net "P3V3_STBY")
			(options
				(clearance outline)
				(anchor circle)
			)
			(primitives
				(gr_poly
					(pts
						(arc
							(start -0.1778 -0.2794)
							(mid -0.249642 -0.249642)
							(end -0.2794 -0.1778)
						)
						(arc
							(start -0.2794 0.1778)
							(mid -0.249642 0.249642)
							(end -0.1778 0.2794)
						)
						(arc
							(start 0.1778 0.2794)
							(mid 0.249642 0.249642)
							(end 0.2794 0.1778)
						)
						(arc
							(start 0.2794 -0.1778)
							(mid 0.249642 -0.249642)
							(end 0.1778 -0.2794)
						)
					)
					(width 0)
					(fill yes)
				)
			)
		)
		(pad "2" smd custom
			(at 0 0.4445 90)
			(size 0.1397 0.1397)
			(layers "F.Cu" "F.Mask" "F.Paste")
			(net "BMC_GPIOZ5")
			(options
				(clearance outline)
				(anchor circle)
			)
			(primitives
				(gr_poly
					(pts
						(arc
							(start -0.1778 -0.2794)
							(mid -0.249642 -0.249642)
							(end -0.2794 -0.1778)
						)
						(arc
							(start -0.2794 0.1778)
							(mid -0.249642 0.249642)
							(end -0.1778 0.2794)
						)
						(arc
							(start 0.1778 0.2794)
							(mid 0.249642 0.249642)
							(end 0.2794 0.1778)
						)
						(arc
							(start 0.2794 -0.1778)
							(mid 0.249642 -0.249642)
							(end 0.1778 -0.2794)
						)
					)
					(width 0)
					(fill yes)
				)
			)
		)
	)
	(footprint ""
		(layer "F.Cu")
		(at 99.430332 -18.402046 180)
		(property "Reference" "R38"
			(at 0 0 180)
			(layer "F.SilkS")
			(hide yes)
			(effects
				(font
					(size 1.27 1.27)
				)
			)
		)
		(property "Value" "0R2J-2-GP"
			(at 0.064008 -3.993896 180)
			(unlocked yes)
			(layer "F.Fab")
			(hide yes)
			(effects
				(font
					(size 1.016 1.016)
					(thickness 0.1524)
				)
			)
		)
		(property "Device Type" "R402H16"
			(at 0.064008 -5.517896 180)
			(unlocked yes)
			(layer "F.Fab")
			(hide yes)
			(effects
				(font
					(size 1.016 1.016)
					(thickness 0.1524)
				)
			)
		)
		(duplicate_pad_numbers_are_jumpers no)
		(fp_line
			(start 0.508 -0.9398)
			(end -0.508 -0.9398)
			(stroke
				(width 0.1524)
				(type default)
			)
			(layer "F.SilkS")
		)
		(fp_line
			(start -0.508 -0.9398)
			(end -0.508 0.9398)
			(stroke
				(width 0.1524)
				(type default)
			)
			(layer "F.SilkS")
		)
		(fp_rect
			(start -0.508 0.9398)
			(end 0.508 -0.9398)
			(stroke
				(width 0)
				(type default)
			)
			(fill no)
			(layer "F.CrtYd")
		)
		(fp_rect
			(start -0.508 0.9398)
			(end 0.508 -0.9398)
			(stroke
				(width 0)
				(type default)
			)
			(fill no)
			(layer "F.Fab")
		)
		(pad "1" smd custom
			(at 0 -0.4445 180)
			(size 0.1397 0.1397)
			(layers "F.Cu" "F.Mask" "F.Paste")
			(net "USB_P1_F_DP1")
			(options
				(clearance outline)
				(anchor circle)
			)
			(primitives
				(gr_poly
					(pts
						(arc
							(start -0.1778 -0.2794)
							(mid -0.249642 -0.249642)
							(end -0.2794 -0.1778)
						)
						(arc
							(start -0.2794 0.1778)
							(mid -0.249642 0.249642)
							(end -0.1778 0.2794)
						)
						(arc
							(start 0.1778 0.2794)
							(mid 0.249642 0.249642)
							(end 0.2794 0.1778)
						)
						(arc
							(start 0.2794 -0.1778)
							(mid 0.249642 -0.249642)
							(end 0.1778 -0.2794)
						)
					)
					(width 0)
					(fill yes)
				)
			)
		)
		(pad "2" smd custom
			(at 0 0.4445 180)
			(size 0.1397 0.1397)
			(layers "F.Cu" "F.Mask" "F.Paste")
			(net "USB_P1_DP")
			(options
				(clearance outline)
				(anchor circle)
			)
			(primitives
				(gr_poly
					(pts
						(arc
							(start -0.1778 -0.2794)
							(mid -0.249642 -0.249642)
							(end -0.2794 -0.1778)
						)
						(arc
							(start -0.2794 0.1778)
							(mid -0.249642 0.249642)
							(end -0.1778 0.2794)
						)
						(arc
							(start 0.1778 0.2794)
							(mid 0.249642 0.249642)
							(end 0.2794 0.1778)
						)
						(arc
							(start 0.2794 -0.1778)
							(mid 0.249642 -0.249642)
							(end 0.1778 -0.2794)
						)
					)
					(width 0)
					(fill yes)
				)
			)
		)
	)
	(footprint ""
		(layer "F.Cu")
		(at 216.069672 -53.813456 90)
		(property "Reference" "R472"
			(at 0 0 90)
			(layer "F.SilkS")
			(hide yes)
			(effects
				(font
					(size 1.27 1.27)
				)
			)
		)
		(property "Value" "100KR2F-L1-GP"
			(at 0.064008 -3.993896 90)
			(unlocked yes)
			(layer "F.Fab")
			(hide yes)
			(effects
				(font
					(size 1.016 1.016)
					(thickness 0.1524)
				)
			)
		)
		(property "Device Type" "R402H16"
			(at 0.064008 -5.517896 90)
			(unlocked yes)
			(layer "F.Fab")
			(hide yes)
			(effects
				(font
					(size 1.016 1.016)
					(thickness 0.1524)
				)
			)
		)
		(duplicate_pad_numbers_are_jumpers no)
		(fp_line
			(start 0.508 -0.9398)
			(end -0.508 -0.9398)
			(stroke
				(width 0.1524)
				(type default)
			)
			(layer "F.SilkS")
		)
		(fp_line
			(start -0.508 -0.9398)
			(end -0.508 0.9398)
			(stroke
				(width 0.1524)
				(type default)
			)
			(layer "F.SilkS")
		)
		(fp_rect
			(start -0.508 0.9398)
			(end 0.508 -0.9398)
			(stroke
				(width 0)
				(type default)
			)
			(fill no)
			(layer "F.CrtYd")
		)
		(fp_rect
			(start -0.508 0.9398)
			(end 0.508 -0.9398)
			(stroke
				(width 0)
				(type default)
			)
			(fill no)
			(layer "F.Fab")
		)
		(pad "1" smd custom
			(at 0 -0.4445 90)
			(size 0.1397 0.1397)
			(layers "F.Cu" "F.Mask" "F.Paste")
			(net "AGND_P5V")
			(options
				(clearance outline)
				(anchor circle)
			)
			(primitives
				(gr_poly
					(pts
						(arc
							(start -0.1778 -0.2794)
							(mid -0.249642 -0.249642)
							(end -0.2794 -0.1778)
						)
						(arc
							(start -0.2794 0.1778)
							(mid -0.249642 0.249642)
							(end -0.1778 0.2794)
						)
						(arc
							(start 0.1778 0.2794)
							(mid 0.249642 0.249642)
							(end 0.2794 0.1778)
						)
						(arc
							(start 0.2794 -0.1778)
							(mid 0.249642 -0.249642)
							(end 0.1778 -0.2794)
						)
					)
					(width 0)
					(fill yes)
				)
			)
		)
		(pad "2" smd custom
			(at 0 0.4445 90)
			(size 0.1397 0.1397)
			(layers "F.Cu" "F.Mask" "F.Paste")
			(net "P5V_MODE")
			(options
				(clearance outline)
				(anchor circle)
			)
			(primitives
				(gr_poly
					(pts
						(arc
							(start -0.1778 -0.2794)
							(mid -0.249642 -0.249642)
							(end -0.2794 -0.1778)
						)
						(arc
							(start -0.2794 0.1778)
							(mid -0.249642 0.249642)
							(end -0.1778 0.2794)
						)
						(arc
							(start 0.1778 0.2794)
							(mid 0.249642 0.249642)
							(end 0.2794 0.1778)
						)
						(arc
							(start 0.2794 -0.1778)
							(mid 0.249642 -0.249642)
							(end 0.1778 -0.2794)
						)
					)
					(width 0)
					(fill yes)
				)
			)
		)
	)
	(footprint ""
		(layer "F.Cu")
		(at 36.068 -130.5052 180)
		(property "Reference" "R308"
			(at 0 0 180)
			(layer "F.SilkS")
			(hide yes)
			(effects
				(font
					(size 1.27 1.27)
				)
			)
		)
		(property "Value" "4K7R2F-GP"
			(at 0.064008 -3.993896 180)
			(unlocked yes)
			(layer "F.Fab")
			(hide yes)
			(effects
				(font
					(size 1.016 1.016)
					(thickness 0.1524)
				)
			)
		)
		(property "Device Type" "R402H16"
			(at 0.064008 -5.517896 180)
			(unlocked yes)
			(layer "F.Fab")
			(hide yes)
			(effects
				(font
					(size 1.016 1.016)
					(thickness 0.1524)
				)
			)
		)
		(duplicate_pad_numbers_are_jumpers no)
		(fp_line
			(start 0.508 -0.9398)
			(end -0.508 -0.9398)
			(stroke
				(width 0.1524)
				(type default)
			)
			(layer "F.SilkS")
		)
		(fp_line
			(start -0.508 -0.9398)
			(end -0.508 0.9398)
			(stroke
				(width 0.1524)
				(type default)
			)
			(layer "F.SilkS")
		)
		(fp_rect
			(start -0.508 0.9398)
			(end 0.508 -0.9398)
			(stroke
				(width 0)
				(type default)
			)
			(fill no)
			(layer "F.CrtYd")
		)
		(fp_rect
			(start -0.508 0.9398)
			(end 0.508 -0.9398)
			(stroke
				(width 0)
				(type default)
			)
			(fill no)
			(layer "F.Fab")
		)
		(pad "1" smd custom
			(at 0 -0.4445 180)
			(size 0.1397 0.1397)
			(layers "F.Cu" "F.Mask" "F.Paste")
			(net "P3V3_STBY")
			(options
				(clearance outline)
				(anchor circle)
			)
			(primitives
				(gr_poly
					(pts
						(arc
							(start -0.1778 -0.2794)
							(mid -0.249642 -0.249642)
							(end -0.2794 -0.1778)
						)
						(arc
							(start -0.2794 0.1778)
							(mid -0.249642 0.249642)
							(end -0.1778 0.2794)
						)
						(arc
							(start 0.1778 0.2794)
							(mid 0.249642 0.249642)
							(end 0.2794 0.1778)
						)
						(arc
							(start 0.2794 -0.1778)
							(mid 0.249642 -0.249642)
							(end 0.1778 -0.2794)
						)
					)
					(width 0)
					(fill yes)
				)
			)
		)
		(pad "2" smd custom
			(at 0 0.4445 180)
			(size 0.1397 0.1397)
			(layers "F.Cu" "F.Mask" "F.Paste")
			(net "OSC_OE")
			(options
				(clearance outline)
				(anchor circle)
			)
			(primitives
				(gr_poly
					(pts
						(arc
							(start -0.1778 -0.2794)
							(mid -0.249642 -0.249642)
							(end -0.2794 -0.1778)
						)
						(arc
							(start -0.2794 0.1778)
							(mid -0.249642 0.249642)
							(end -0.1778 0.2794)
						)
						(arc
							(start 0.1778 0.2794)
							(mid 0.249642 0.249642)
							(end 0.2794 0.1778)
						)
						(arc
							(start 0.2794 -0.1778)
							(mid 0.249642 -0.249642)
							(end 0.1778 -0.2794)
						)
					)
					(width 0)
					(fill yes)
				)
			)
		)
	)
	(footprint ""
		(layer "F.Cu")
		(at 110.755684 -13.1572 -90)
		(property "Reference" "C149"
			(at 0 0 270)
			(layer "F.SilkS")
			(hide yes)
			(effects
				(font
					(size 1.27 1.27)
				)
			)
		)
		(property "Value" "SCD1U50V3KX-GP"
			(at 0 -2.8194 270)
			(unlocked yes)
			(layer "F.Fab")
			(hide yes)
			(effects
				(font
					(size 1.016 1.016)
					(thickness 0.1524)
				)
			)
		)
		(property "Device Type" "C603H36"
			(at 0 -4.3434 270)
			(unlocked yes)
			(layer "F.Fab")
			(hide yes)
			(effects
				(font
					(size 1.016 1.016)
					(thickness 0.1524)
				)
			)
		)
		(duplicate_pad_numbers_are_jumpers no)
		(fp_line
			(start 0.508 0)
			(end -0.508 0)
			(stroke
				(width 0.2032)
				(type default)
			)
			(layer "F.SilkS")
		)
		(fp_rect
			(start -0.5842 1.3335)
			(end 0.5842 -1.3335)
			(stroke
				(width 0)
				(type default)
			)
			(fill no)
			(layer "F.CrtYd")
		)
		(fp_rect
			(start -0.5842 1.3335)
			(end 0.5842 -1.3335)
			(stroke
				(width 0)
				(type default)
			)
			(fill no)
			(layer "F.Fab")
		)
		(pad "1" smd custom
			(at 0 -0.762 270)
			(size 0.2159 0.2159)
			(layers "F.Cu" "F.Mask" "F.Paste")
			(net "MB0_PSET_R")
			(options
				(clearance outline)
				(anchor circle)
			)
			(primitives
				(gr_poly
					(pts
						(arc
							(start -0.3302 -0.4318)
							(mid -0.402042 -0.402042)
							(end -0.4318 -0.3302)
						)
						(arc
							(start -0.4318 0.3302)
							(mid -0.402042 0.402042)
							(end -0.3302 0.4318)
						)
						(arc
							(start 0.3302 0.4318)
							(mid 0.402042 0.402042)
							(end 0.4318 0.3302)
						)
						(arc
							(start 0.4318 -0.3302)
							(mid 0.402042 -0.402042)
							(end 0.3302 -0.4318)
						)
					)
					(width 0)
					(fill yes)
				)
			)
		)
		(pad "2" smd custom
			(at 0 0.762 270)
			(size 0.2159 0.2159)
			(layers "F.Cu" "F.Mask" "F.Paste")
			(net "AGND_CURRENT_MON")
			(options
				(clearance outline)
				(anchor circle)
			)
			(primitives
				(gr_poly
					(pts
						(arc
							(start -0.3302 -0.4318)
							(mid -0.402042 -0.402042)
							(end -0.4318 -0.3302)
						)
						(arc
							(start -0.4318 0.3302)
							(mid -0.402042 0.402042)
							(end -0.3302 0.4318)
						)
						(arc
							(start 0.3302 0.4318)
							(mid 0.402042 0.402042)
							(end 0.4318 0.3302)
						)
						(arc
							(start 0.4318 -0.3302)
							(mid 0.402042 -0.402042)
							(end 0.3302 -0.4318)
						)
					)
					(width 0)
					(fill yes)
				)
			)
		)
	)
	(footprint ""
		(layer "F.Cu")
		(at 215.968072 -48.911256 90)
		(property "Reference" "G2"
			(at 0 0 90)
			(layer "F.SilkS")
			(hide yes)
			(effects
				(font
					(size 1.27 1.27)
				)
			)
		)
		(property "Value" "COPPER-CLOSE-GP-U"
			(at 0.0762 -2.8702 90)
			(unlocked yes)
			(layer "F.Fab")
			(hide yes)
			(effects
				(font
					(size 1.016 1.016)
					(thickness 0.1524)
				)
			)
		)
		(property "Device Type" "CON2C-U"
			(at 0.0762 -4.3942 90)
			(unlocked yes)
			(layer "F.Fab")
			(hide yes)
			(effects
				(font
					(size 1.016 1.016)
					(thickness 0.1524)
				)
			)
		)
		(duplicate_pad_numbers_are_jumpers no)
		(fp_rect
			(start -0.9398 0.9652)
			(end 0.9398 -0.9652)
			(stroke
				(width 0)
				(type default)
			)
			(fill no)
			(layer "F.CrtYd")
		)
		(fp_rect
			(start -0.9398 0.9652)
			(end 0.9398 -0.9652)
			(stroke
				(width 0)
				(type default)
			)
			(fill no)
			(layer "F.Fab")
		)
		(pad "1" smd custom
			(at 0 -0.5334 90)
			(size 0.17145 0.17145)
			(layers "F.Cu" "F.Mask" "F.Paste")
			(net "AGND_P5V")
			(options
				(clearance outline)
				(anchor circle)
			)
			(primitives
				(gr_poly
					(pts
						(xy -0.127 0.3429) (xy -0.127 0.1651) (xy -0.635 -0.3429) (xy 0.635 -0.3429) (xy 0.127 0.1651)
						(xy 0.127 0.3429)
					)
					(width 0)
					(fill yes)
				)
			)
		)
		(pad "2" smd custom
			(at 0 0.5334 90)
			(size 0.17145 0.17145)
			(layers "F.Cu" "F.Mask" "F.Paste")
			(net "GND")
			(options
				(clearance outline)
				(anchor circle)
			)
			(primitives
				(gr_poly
					(pts
						(xy -0.635 0.3429) (xy -0.127 -0.1651) (xy -0.127 -0.3429) (xy 0.127 -0.3429) (xy 0.127 -0.1651)
						(xy 0.635 0.3429)
					)
					(width 0)
					(fill yes)
				)
			)
		)
	)
	(footprint ""
		(layer "F.Cu")
		(at 87.638636 -29.238448)
		(property "Reference" "C21"
			(at 0 0 0)
			(layer "F.SilkS")
			(hide yes)
			(effects
				(font
					(size 1.27 1.27)
				)
			)
		)
		(property "Value" "SC1U16V3KX-5GP"
			(at 0 -2.8194 0)
			(unlocked yes)
			(layer "F.Fab")
			(hide yes)
			(effects
				(font
					(size 1.016 1.016)
					(thickness 0.1524)
				)
			)
		)
		(property "Device Type" "C603H36"
			(at 0 -4.3434 0)
			(unlocked yes)
			(layer "F.Fab")
			(hide yes)
			(effects
				(font
					(size 1.016 1.016)
					(thickness 0.1524)
				)
			)
		)
		(duplicate_pad_numbers_are_jumpers no)
		(fp_line
			(start 0.508 0)
			(end -0.508 0)
			(stroke
				(width 0.2032)
				(type default)
			)
			(layer "F.SilkS")
		)
		(fp_rect
			(start -0.5842 1.3335)
			(end 0.5842 -1.3335)
			(stroke
				(width 0)
				(type default)
			)
			(fill no)
			(layer "F.CrtYd")
		)
		(fp_rect
			(start -0.5842 1.3335)
			(end 0.5842 -1.3335)
			(stroke
				(width 0)
				(type default)
			)
			(fill no)
			(layer "F.Fab")
		)
		(pad "1" smd custom
			(at 0 -0.762)
			(size 0.2159 0.2159)
			(layers "F.Cu" "F.Mask" "F.Paste")
			(net "P5V_USB")
			(options
				(clearance outline)
				(anchor circle)
			)
			(primitives
				(gr_poly
					(pts
						(arc
							(start -0.3302 -0.4318)
							(mid -0.402042 -0.402042)
							(end -0.4318 -0.3302)
						)
						(arc
							(start -0.4318 0.3302)
							(mid -0.402042 0.402042)
							(end -0.3302 0.4318)
						)
						(arc
							(start 0.3302 0.4318)
							(mid 0.402042 0.402042)
							(end 0.4318 0.3302)
						)
						(arc
							(start 0.4318 -0.3302)
							(mid 0.402042 -0.402042)
							(end 0.3302 -0.4318)
						)
					)
					(width 0)
					(fill yes)
				)
			)
		)
		(pad "2" smd custom
			(at 0 0.762)
			(size 0.2159 0.2159)
			(layers "F.Cu" "F.Mask" "F.Paste")
			(net "GND")
			(options
				(clearance outline)
				(anchor circle)
			)
			(primitives
				(gr_poly
					(pts
						(arc
							(start -0.3302 -0.4318)
							(mid -0.402042 -0.402042)
							(end -0.4318 -0.3302)
						)
						(arc
							(start -0.4318 0.3302)
							(mid -0.402042 0.402042)
							(end -0.3302 0.4318)
						)
						(arc
							(start 0.3302 0.4318)
							(mid 0.402042 0.402042)
							(end 0.4318 0.3302)
						)
						(arc
							(start 0.4318 -0.3302)
							(mid 0.402042 -0.402042)
							(end 0.3302 -0.4318)
						)
					)
					(width 0)
					(fill yes)
				)
			)
		)
	)
	(footprint ""
		(layer "F.Cu")
		(at 224.185988 -37.290756)
		(property "Reference" "L7"
			(at 0 0 0)
			(layer "F.SilkS")
			(hide yes)
			(effects
				(font
					(size 1.27 1.27)
				)
			)
		)
		(property "Value" "IND-4D7UH-291-GP"
			(at -6.34492 -3.502152 0)
			(unlocked yes)
			(layer "F.Fab")
			(hide yes)
			(effects
				(font
					(size 1.016 1.016)
					(thickness 0.1524)
				)
			)
		)
		(property "Device Type" "L11102530H158"
			(at -6.3246 -5.08 0)
			(unlocked yes)
			(layer "F.Fab")
			(hide yes)
			(effects
				(font
					(size 1.016 1.016)
					(thickness 0.1524)
				)
			)
		)
		(duplicate_pad_numbers_are_jumpers no)
		(fp_line
			(start -5.2578 -6.3754)
			(end -5.2578 6.3754)
			(stroke
				(width 0.1524)
				(type default)
			)
			(layer "F.SilkS")
		)
		(fp_line
			(start -5.2578 6.3754)
			(end 5.2578 6.3754)
			(stroke
				(width 0.1524)
				(type default)
			)
			(layer "F.SilkS")
		)
		(fp_line
			(start 5.2578 -6.3754)
			(end -5.2578 -6.3754)
			(stroke
				(width 0.1524)
				(type default)
			)
			(layer "F.SilkS")
		)
		(fp_line
			(start 5.2578 6.3754)
			(end 5.2578 -6.3754)
			(stroke
				(width 0.1524)
				(type default)
			)
			(layer "F.SilkS")
		)
		(fp_rect
			(start -5.0038 5.4991)
			(end 5.0038 -5.4991)
			(stroke
				(width 0)
				(type default)
			)
			(fill no)
			(layer "F.CrtYd")
		)
		(fp_poly
			(pts
				(xy -5.5118 6.4516) (xy -5.5118 -6.4516) (xy 5.5118 -6.4516) (xy 5.5118 -0.8509) (xy 5.0038 -0.8509)
				(xy 5.0038 -5.4991) (xy -5.0038 -5.4991) (xy -5.0038 5.4991) (xy 5.0038 5.4991) (xy 5.0038 -0.8382)
				(xy 5.5118 -0.8382) (xy 5.5118 6.4516)
			)
			(stroke
				(width 0)
				(type default)
			)
			(fill no)
			(layer "F.CrtYd")
		)
		(fp_rect
			(start -5.5118 6.4516)
			(end 5.5118 -6.4516)
			(stroke
				(width 0)
				(type default)
			)
			(fill no)
			(layer "F.Fab")
		)
		(pad "1" smd rect
			(at 0 -4.435094)
			(size 3.2512 3.3782)
			(layers "F.Cu" "F.Mask" "F.Paste")
			(net "P5V_LL")
		)
		(pad "2" smd rect
			(at 0 4.435094)
			(size 3.2512 3.3782)
			(layers "F.Cu" "F.Mask" "F.Paste")
			(net "P5V_STBY")
		)
	)
	(footprint ""
		(layer "F.Cu")
		(at 94.6658 -124.587 180)
		(property "Reference" "U46"
			(at 0 0 180)
			(layer "F.SilkS")
			(hide yes)
			(effects
				(font
					(size 1.27 1.27)
				)
			)
		)
		(property "Value" "SN74LVC1G08DCKR-GP"
			(at -2.3368 -8.6868 180)
			(unlocked yes)
			(layer "F.Fab")
			(hide yes)
			(effects
				(font
					(size 1.016 1.016)
					(thickness 0.1524)
				)
			)
		)
		(property "Device Type" "SC70-5H44"
			(at -2.3114 -10.414 180)
			(unlocked yes)
			(layer "F.Fab")
			(hide yes)
			(effects
				(font
					(size 1.016 1.016)
					(thickness 0.1524)
				)
			)
		)
		(duplicate_pad_numbers_are_jumpers no)
		(fp_line
			(start 1.3843 -1.8034)
			(end 1.3843 -1.1176)
			(stroke
				(width 0.3302)
				(type default)
			)
			(layer "F.SilkS")
		)
		(fp_line
			(start 1.27 1.7018)
			(end -1.27 1.7018)
			(stroke
				(width 0.1524)
				(type default)
			)
			(layer "F.SilkS")
		)
		(fp_line
			(start 1.27 -1.7018)
			(end 1.27 1.7018)
			(stroke
				(width 0.1524)
				(type default)
			)
			(layer "F.SilkS")
		)
		(fp_line
			(start 0.6604 -1.8034)
			(end 1.3843 -1.8034)
			(stroke
				(width 0.3302)
				(type default)
			)
			(layer "F.SilkS")
		)
		(fp_line
			(start -1.27 1.7018)
			(end -1.27 -1.7018)
			(stroke
				(width 0.1524)
				(type default)
			)
			(layer "F.SilkS")
		)
		(fp_line
			(start -1.27 -1.7018)
			(end 1.27 -1.7018)
			(stroke
				(width 0.1524)
				(type default)
			)
			(layer "F.SilkS")
		)
		(fp_rect
			(start -1.524 1.9558)
			(end 1.524 -1.9558)
			(stroke
				(width 0)
				(type default)
			)
			(fill no)
			(layer "F.CrtYd")
		)
		(fp_poly
			(pts
				(xy -1.524 -1.9558) (xy 1.524 -1.9558) (xy 1.524 1.9558) (xy -1.524 1.9558)
			)
			(stroke
				(width 0)
				(type default)
			)
			(fill no)
			(layer "F.Fab")
		)
		(pad "1" smd rect
			(at 0.65024 -0.8255 180)
			(size 0.4064 1.2192)
			(layers "F.Cu" "F.Mask" "F.Paste")
			(net "UART_COMP_IN_R_RX")
		)
		(pad "2" smd rect
			(at 0 -0.8255 180)
			(size 0.4064 1.2192)
			(layers "F.Cu" "F.Mask" "F.Paste")
			(net "UART_BMC_COMP_IN_RX_R")
		)
		(pad "3" smd rect
			(at -0.65024 -0.8255 180)
			(size 0.4064 1.2192)
			(layers "F.Cu" "F.Mask" "F.Paste")
			(net "GND")
		)
		(pad "4" smd rect
			(at -0.65024 0.8255 180)
			(size 0.4064 1.2192)
			(layers "F.Cu" "F.Mask" "F.Paste")
			(net "UART_COMP_IN_RX_AND")
		)
		(pad "5" smd rect
			(at 0.65024 0.8255 180)
			(size 0.4064 1.2192)
			(layers "F.Cu" "F.Mask" "F.Paste")
			(net "P3V3_STBY")
		)
	)
	(footprint ""
		(layer "F.Cu")
		(at 48.6156 -128.0414 180)
		(property "Reference" "R88"
			(at 0 0 180)
			(layer "F.SilkS")
			(hide yes)
			(effects
				(font
					(size 1.27 1.27)
				)
			)
		)
		(property "Value" "100KR2F-L1-GP"
			(at 0.064008 -3.993896 180)
			(unlocked yes)
			(layer "F.Fab")
			(hide yes)
			(effects
				(font
					(size 1.016 1.016)
					(thickness 0.1524)
				)
			)
		)
		(property "Device Type" "R402H16"
			(at 0.064008 -5.517896 180)
			(unlocked yes)
			(layer "F.Fab")
			(hide yes)
			(effects
				(font
					(size 1.016 1.016)
					(thickness 0.1524)
				)
			)
		)
		(duplicate_pad_numbers_are_jumpers no)
		(fp_line
			(start 0.508 -0.9398)
			(end -0.508 -0.9398)
			(stroke
				(width 0.1524)
				(type default)
			)
			(layer "F.SilkS")
		)
		(fp_line
			(start -0.508 -0.9398)
			(end -0.508 0.9398)
			(stroke
				(width 0.1524)
				(type default)
			)
			(layer "F.SilkS")
		)
		(fp_rect
			(start -0.508 0.9398)
			(end 0.508 -0.9398)
			(stroke
				(width 0)
				(type default)
			)
			(fill no)
			(layer "F.CrtYd")
		)
		(fp_rect
			(start -0.508 0.9398)
			(end 0.508 -0.9398)
			(stroke
				(width 0)
				(type default)
			)
			(fill no)
			(layer "F.Fab")
		)
		(pad "1" smd custom
			(at 0 -0.4445 180)
			(size 0.1397 0.1397)
			(layers "F.Cu" "F.Mask" "F.Paste")
			(net "SCC_LOC_FULL_PWR_EN")
			(options
				(clearance outline)
				(anchor circle)
			)
			(primitives
				(gr_poly
					(pts
						(arc
							(start -0.1778 -0.2794)
							(mid -0.249642 -0.249642)
							(end -0.2794 -0.1778)
						)
						(arc
							(start -0.2794 0.1778)
							(mid -0.249642 0.249642)
							(end -0.1778 0.2794)
						)
						(arc
							(start 0.1778 0.2794)
							(mid 0.249642 0.249642)
							(end 0.2794 0.1778)
						)
						(arc
							(start 0.2794 -0.1778)
							(mid 0.249642 -0.249642)
							(end 0.1778 -0.2794)
						)
					)
					(width 0)
					(fill yes)
				)
			)
		)
		(pad "2" smd custom
			(at 0 0.4445 180)
			(size 0.1397 0.1397)
			(layers "F.Cu" "F.Mask" "F.Paste")
			(net "GND")
			(options
				(clearance outline)
				(anchor circle)
			)
			(primitives
				(gr_poly
					(pts
						(arc
							(start -0.1778 -0.2794)
							(mid -0.249642 -0.249642)
							(end -0.2794 -0.1778)
						)
						(arc
							(start -0.2794 0.1778)
							(mid -0.249642 0.249642)
							(end -0.1778 0.2794)
						)
						(arc
							(start 0.1778 0.2794)
							(mid 0.249642 0.249642)
							(end 0.2794 0.1778)
						)
						(arc
							(start 0.2794 -0.1778)
							(mid 0.249642 -0.249642)
							(end 0.1778 -0.2794)
						)
					)
					(width 0)
					(fill yes)
				)
			)
		)
	)
	(footprint ""
		(layer "F.Cu")
		(at 81.28 -136.017 180)
		(property "Reference" "R39"
			(at 0 0 180)
			(layer "F.SilkS")
			(hide yes)
			(effects
				(font
					(size 1.27 1.27)
				)
			)
		)
		(property "Value" "0R2J-2-GP"
			(at 0.064008 -3.993896 180)
			(unlocked yes)
			(layer "F.Fab")
			(hide yes)
			(effects
				(font
					(size 1.016 1.016)
					(thickness 0.1524)
				)
			)
		)
		(property "Device Type" "R402H16"
			(at 0.064008 -5.517896 180)
			(unlocked yes)
			(layer "F.Fab")
			(hide yes)
			(effects
				(font
					(size 1.016 1.016)
					(thickness 0.1524)
				)
			)
		)
		(duplicate_pad_numbers_are_jumpers no)
		(fp_line
			(start 0.508 -0.9398)
			(end -0.508 -0.9398)
			(stroke
				(width 0.1524)
				(type default)
			)
			(layer "F.SilkS")
		)
		(fp_line
			(start -0.508 -0.9398)
			(end -0.508 0.9398)
			(stroke
				(width 0.1524)
				(type default)
			)
			(layer "F.SilkS")
		)
		(fp_rect
			(start -0.508 0.9398)
			(end 0.508 -0.9398)
			(stroke
				(width 0)
				(type default)
			)
			(fill no)
			(layer "F.CrtYd")
		)
		(fp_rect
			(start -0.508 0.9398)
			(end 0.508 -0.9398)
			(stroke
				(width 0)
				(type default)
			)
			(fill no)
			(layer "F.Fab")
		)
		(pad "1" smd custom
			(at 0 -0.4445 180)
			(size 0.1397 0.1397)
			(layers "F.Cu" "F.Mask" "F.Paste")
			(net "D_FLIP_D")
			(options
				(clearance outline)
				(anchor circle)
			)
			(primitives
				(gr_poly
					(pts
						(arc
							(start -0.1778 -0.2794)
							(mid -0.249642 -0.249642)
							(end -0.2794 -0.1778)
						)
						(arc
							(start -0.2794 0.1778)
							(mid -0.249642 0.249642)
							(end -0.1778 0.2794)
						)
						(arc
							(start 0.1778 0.2794)
							(mid 0.249642 0.249642)
							(end 0.2794 0.1778)
						)
						(arc
							(start 0.2794 -0.1778)
							(mid 0.249642 -0.249642)
							(end 0.1778 -0.2794)
						)
					)
					(width 0)
					(fill yes)
				)
			)
		)
		(pad "2" smd custom
			(at 0 0.4445 180)
			(size 0.1397 0.1397)
			(layers "F.Cu" "F.Mask" "F.Paste")
			(net "D_FLIP_Q#")
			(options
				(clearance outline)
				(anchor circle)
			)
			(primitives
				(gr_poly
					(pts
						(arc
							(start -0.1778 -0.2794)
							(mid -0.249642 -0.249642)
							(end -0.2794 -0.1778)
						)
						(arc
							(start -0.2794 0.1778)
							(mid -0.249642 0.249642)
							(end -0.1778 0.2794)
						)
						(arc
							(start 0.1778 0.2794)
							(mid 0.249642 0.249642)
							(end 0.2794 0.1778)
						)
						(arc
							(start 0.2794 -0.1778)
							(mid 0.249642 -0.249642)
							(end 0.1778 -0.2794)
						)
					)
					(width 0)
					(fill yes)
				)
			)
		)
	)
	(footprint ""
		(layer "F.Cu")
		(at 8.886698 -141.008862 90)
		(property "Reference" "R227"
			(at 0 0 90)
			(layer "F.SilkS")
			(hide yes)
			(effects
				(font
					(size 1.27 1.27)
				)
			)
		)
		(property "Value" "120R2F-GP"
			(at 0.064008 -3.993896 90)
			(unlocked yes)
			(layer "F.Fab")
			(hide yes)
			(effects
				(font
					(size 1.016 1.016)
					(thickness 0.1524)
				)
			)
		)
		(property "Device Type" "R402H16"
			(at 0.064008 -5.517896 90)
			(unlocked yes)
			(layer "F.Fab")
			(hide yes)
			(effects
				(font
					(size 1.016 1.016)
					(thickness 0.1524)
				)
			)
		)
		(duplicate_pad_numbers_are_jumpers no)
		(fp_line
			(start 0.508 -0.9398)
			(end -0.508 -0.9398)
			(stroke
				(width 0.1524)
				(type default)
			)
			(layer "F.SilkS")
		)
		(fp_line
			(start -0.508 -0.9398)
			(end -0.508 0.9398)
			(stroke
				(width 0.1524)
				(type default)
			)
			(layer "F.SilkS")
		)
		(fp_rect
			(start -0.508 0.9398)
			(end 0.508 -0.9398)
			(stroke
				(width 0)
				(type default)
			)
			(fill no)
			(layer "F.CrtYd")
		)
		(fp_rect
			(start -0.508 0.9398)
			(end 0.508 -0.9398)
			(stroke
				(width 0)
				(type default)
			)
			(fill no)
			(layer "F.Fab")
		)
		(pad "1" smd custom
			(at 0 -0.4445 90)
			(size 0.1397 0.1397)
			(layers "F.Cu" "F.Mask" "F.Paste")
			(net "GND")
			(options
				(clearance outline)
				(anchor circle)
			)
			(primitives
				(gr_poly
					(pts
						(arc
							(start -0.1778 -0.2794)
							(mid -0.249642 -0.249642)
							(end -0.2794 -0.1778)
						)
						(arc
							(start -0.2794 0.1778)
							(mid -0.249642 0.249642)
							(end -0.1778 0.2794)
						)
						(arc
							(start 0.1778 0.2794)
							(mid 0.249642 0.249642)
							(end 0.2794 0.1778)
						)
						(arc
							(start 0.2794 -0.1778)
							(mid 0.249642 -0.249642)
							(end 0.1778 -0.2794)
						)
					)
					(width 0)
					(fill yes)
				)
			)
		)
		(pad "2" smd custom
			(at 0 0.4445 90)
			(size 0.1397 0.1397)
			(layers "F.Cu" "F.Mask" "F.Paste")
			(net "MEMWEN")
			(options
				(clearance outline)
				(anchor circle)
			)
			(primitives
				(gr_poly
					(pts
						(arc
							(start -0.1778 -0.2794)
							(mid -0.249642 -0.249642)
							(end -0.2794 -0.1778)
						)
						(arc
							(start -0.2794 0.1778)
							(mid -0.249642 0.249642)
							(end -0.1778 0.2794)
						)
						(arc
							(start 0.1778 0.2794)
							(mid 0.249642 0.249642)
							(end 0.2794 0.1778)
						)
						(arc
							(start 0.2794 -0.1778)
							(mid 0.249642 -0.249642)
							(end 0.1778 -0.2794)
						)
					)
					(width 0)
					(fill yes)
				)
			)
		)
	)
	(footprint ""
		(layer "F.Cu")
		(at 16.691356 -169.1259 -90)
		(property "Reference" "PU10"
			(at 0 0 270)
			(layer "F.SilkS")
			(hide yes)
			(effects
				(font
					(size 1.27 1.27)
				)
			)
		)
		(property "Value" "TPS74801RGW-GP"
			(at -4.7244 -6.223 270)
			(unlocked yes)
			(layer "F.Fab")
			(hide yes)
			(effects
				(font
					(size 1.016 1.016)
					(thickness 0.1524)
				)
			)
		)
		(property "Device Type" "QFN20-1G3D15H40"
			(at -4.7244 -7.747 270)
			(unlocked yes)
			(layer "F.Fab")
			(hide yes)
			(effects
				(font
					(size 1.016 1.016)
					(thickness 0.1524)
				)
			)
		)
		(duplicate_pad_numbers_are_jumpers no)
		(fp_line
			(start -3.5179 3.5179)
			(end -2.2479 3.5179)
			(stroke
				(width 0.1524)
				(type default)
			)
			(layer "F.SilkS")
		)
		(fp_line
			(start 2.2479 3.5179)
			(end 3.5179 3.5179)
			(stroke
				(width 0.1524)
				(type default)
			)
			(layer "F.SilkS")
		)
		(fp_line
			(start 3.5179 3.5179)
			(end 3.5179 2.2479)
			(stroke
				(width 0.1524)
				(type default)
			)
			(layer "F.SilkS")
		)
		(fp_line
			(start 1.299972 3.160522)
			(end 1.299972 3.668522)
			(stroke
				(width 0.1524)
				(type default)
			)
			(layer "F.SilkS")
		)
		(fp_line
			(start -3.5179 2.2479)
			(end -3.5179 3.5179)
			(stroke
				(width 0.1524)
				(type default)
			)
			(layer "F.SilkS")
		)
		(fp_line
			(start -3.160522 1.299972)
			(end -3.922522 1.299972)
			(stroke
				(width 0.1524)
				(type default)
			)
			(layer "F.SilkS")
		)
		(fp_line
			(start 3.160522 -1.299972)
			(end 3.922522 -1.299972)
			(stroke
				(width 0.1524)
				(type default)
			)
			(layer "F.SilkS")
		)
		(fp_line
			(start -1.299972 -3.160522)
			(end -1.299972 -3.668522)
			(stroke
				(width 0.1524)
				(type default)
			)
			(layer "F.SilkS")
		)
		(fp_line
			(start -3.5179 -3.5179)
			(end -3.5179 -2.2479)
			(stroke
				(width 0.1524)
				(type default)
			)
			(layer "F.SilkS")
		)
		(fp_line
			(start -2.2479 -3.5179)
			(end -3.5179 -3.5179)
			(stroke
				(width 0.1524)
				(type default)
			)
			(layer "F.SilkS")
		)
		(fp_poly
			(pts
				(xy 3.5179 -3.5179) (xy 2.2479 -3.5179) (xy 3.5179 -2.2479)
			)
			(stroke
				(width 0)
				(type default)
			)
			(fill yes)
			(layer "F.SilkS")
		)
		(fp_rect
			(start -2.5019 2.5019)
			(end 2.5019 -2.5019)
			(stroke
				(width 0)
				(type default)
			)
			(fill no)
			(layer "F.CrtYd")
		)
		(fp_poly
			(pts
				(xy -3.5179 3.5179) (xy -3.5179 -3.5179) (xy 3.5179 -3.5179) (xy 3.5179 -2.5019) (xy -2.5019 -2.5019)
				(xy -2.5019 2.5019) (xy 2.5019 2.5019) (xy 2.5019 -2.49682) (xy 3.5179 -2.49682) (xy 3.5179 3.5179)
			)
			(stroke
				(width 0)
				(type default)
			)
			(fill no)
			(layer "F.CrtYd")
		)
		(fp_rect
			(start -3.5179 3.5179)
			(end 3.5179 -3.5179)
			(stroke
				(width 0)
				(type default)
			)
			(fill no)
			(layer "F.Fab")
		)
		(pad "1" smd rect
			(at 1.299972 -2.474722 270)
			(size 0.3556 1.0668)
			(layers "F.Cu" "F.Mask" "F.Paste")
			(net "TPS74801_P1V2_STBY_OUT")
		)
		(pad "2" smd rect
			(at 0.649986 -2.474722 270)
			(size 0.3556 1.0668)
			(layers "F.Cu" "F.Mask" "F.Paste")
			(net "GND")
		)
		(pad "3" smd rect
			(at 0 -2.474722 270)
			(size 0.3556 1.0668)
			(layers "F.Cu" "F.Mask" "F.Paste")
			(net "GND")
		)
		(pad "4" smd rect
			(at -0.649986 -2.474722 270)
			(size 0.3556 1.0668)
			(layers "F.Cu" "F.Mask" "F.Paste")
			(net "GND")
		)
		(pad "5" smd rect
			(at -1.299972 -2.474722 270)
			(size 0.3556 1.0668)
			(layers "F.Cu" "F.Mask" "F.Paste")
			(net "P1V8_STBY")
		)
		(pad "6" smd rect
			(at -2.474722 -1.299972 270)
			(size 1.0668 0.3556)
			(layers "F.Cu" "F.Mask" "F.Paste")
			(net "P1V8_STBY")
		)
		(pad "7" smd rect
			(at -2.474722 -0.649986 270)
			(size 1.0668 0.3556)
			(layers "F.Cu" "F.Mask" "F.Paste")
			(net "P1V8_STBY")
		)
		(pad "8" smd rect
			(at -2.474722 0 270)
			(size 1.0668 0.3556)
			(layers "F.Cu" "F.Mask" "F.Paste")
			(net "P1V8_STBY")
		)
		(pad "9" smd rect
			(at -2.474722 0.649986 270)
			(size 1.0668 0.3556)
			(layers "F.Cu" "F.Mask" "F.Paste")
			(net "PWRGD_P1V2_STBY")
		)
		(pad "10" smd rect
			(at -2.474722 1.299972 270)
			(size 1.0668 0.3556)
			(layers "F.Cu" "F.Mask" "F.Paste")
			(net "TPS74801_P1V2_STBY_BIAS")
		)
		(pad "11" smd rect
			(at -1.299972 2.474722 270)
			(size 0.3556 1.0668)
			(layers "F.Cu" "F.Mask" "F.Paste")
			(net "TPS74801_P1V2_STBY_EN")
		)
		(pad "12" smd rect
			(at -0.649986 2.474722 270)
			(size 0.3556 1.0668)
			(layers "F.Cu" "F.Mask" "F.Paste")
			(net "GND")
		)
		(pad "13" smd rect
			(at 0 2.474722 270)
			(size 0.3556 1.0668)
			(layers "F.Cu" "F.Mask" "F.Paste")
			(net "GND")
		)
		(pad "14" smd rect
			(at 0.649986 2.474722 270)
			(size 0.3556 1.0668)
			(layers "F.Cu" "F.Mask" "F.Paste")
			(net "GND")
		)
		(pad "15" smd rect
			(at 1.299972 2.474722 270)
			(size 0.3556 1.0668)
			(layers "F.Cu" "F.Mask" "F.Paste")
			(net "TPS74801_P1V2_STBY_SS")
		)
		(pad "16" smd rect
			(at 2.474722 1.299972 270)
			(size 1.0668 0.3556)
			(layers "F.Cu" "F.Mask" "F.Paste")
			(net "TPS74801_P1V2_STBY_FB")
		)
		(pad "17" smd rect
			(at 2.474722 0.649986 270)
			(size 1.0668 0.3556)
			(layers "F.Cu" "F.Mask" "F.Paste")
			(net "GND")
		)
		(pad "18" smd rect
			(at 2.474722 0 270)
			(size 1.0668 0.3556)
			(layers "F.Cu" "F.Mask" "F.Paste")
			(net "TPS74801_P1V2_STBY_OUT")
		)
		(pad "19" smd rect
			(at 2.474722 -0.649986 270)
			(size 1.0668 0.3556)
			(layers "F.Cu" "F.Mask" "F.Paste")
			(net "TPS74801_P1V2_STBY_OUT")
		)
		(pad "20" smd rect
			(at 2.474722 -1.299972 270)
			(size 1.0668 0.3556)
			(layers "F.Cu" "F.Mask" "F.Paste")
			(net "TPS74801_P1V2_STBY_OUT")
		)
		(pad "21" smd rect
			(at 0 0 270)
			(size 3.2512 3.2512)
			(layers "F.Cu" "F.Mask" "F.Paste")
			(net "GND")
		)
	)
	(footprint ""
		(layer "F.Cu")
		(at 125.23089 -12.054078 -90)
		(property "Reference" "P1"
			(at 0 0 270)
			(layer "F.SilkS")
			(hide yes)
			(effects
				(font
					(size 1.27 1.27)
				)
			)
		)
		(property "Value" "0R0603-PAD-2-GP-U"
			(at 2.1209 -0.1397 270)
			(unlocked yes)
			(layer "F.Fab")
			(hide yes)
			(effects
				(font
					(size 1.016 1.016)
					(thickness 0.1524)
				)
			)
		)
		(property "Device Type" "0R0603-PAD-1-U"
			(at 2.1209 -1.6637 270)
			(unlocked yes)
			(layer "F.Fab")
			(hide yes)
			(effects
				(font
					(size 1.016 1.016)
					(thickness 0.1524)
				)
			)
		)
		(duplicate_pad_numbers_are_jumpers no)
		(fp_rect
			(start -0.5842 1.3335)
			(end 0.5842 -1.3335)
			(stroke
				(width 0)
				(type default)
			)
			(fill no)
			(layer "F.CrtYd")
		)
		(fp_rect
			(start -0.5842 1.3335)
			(end 0.5842 -1.3335)
			(stroke
				(width 0)
				(type default)
			)
			(fill no)
			(layer "F.Fab")
		)
		(pad "1" smd custom
			(at 0 -0.762 270)
			(size 0.2159 0.2159)
			(layers "F.Cu" "F.Mask" "F.Paste")
			(net "AGND_CURRENT_MON")
			(options
				(clearance outline)
				(anchor circle)
			)
			(primitives
				(gr_poly
					(pts
						(arc
							(start -0.3302 -0.5842)
							(mid -0.402042 -0.554442)
							(end -0.4318 -0.4826)
						)
						(arc
							(start -0.4318 0.4826)
							(mid -0.402042 0.554442)
							(end -0.3302 0.5842)
						)
						(arc
							(start 0.3302 0.5842)
							(mid 0.402042 0.554442)
							(end 0.4318 0.4826)
						)
						(arc
							(start 0.4318 -0.4826)
							(mid 0.402042 -0.554442)
							(end 0.3302 -0.5842)
						)
					)
					(width 0)
					(fill yes)
				)
			)
		)
		(pad "2" smd custom
			(at 0 0.762 270)
			(size 0.2159 0.2159)
			(layers "F.Cu" "F.Mask" "F.Paste")
			(net "GND")
			(options
				(clearance outline)
				(anchor circle)
			)
			(primitives
				(gr_poly
					(pts
						(arc
							(start -0.4318 0.4826)
							(mid -0.402042 0.554442)
							(end -0.3302 0.5842)
						)
						(arc
							(start 0.3302 0.5842)
							(mid 0.402042 0.554442)
							(end 0.4318 0.4826)
						)
						(arc
							(start 0.4318 -0.4826)
							(mid 0.402042 -0.554442)
							(end 0.3302 -0.5842)
						)
						(arc
							(start -0.3302 -0.5842)
							(mid -0.402042 -0.554442)
							(end -0.4318 -0.4826)
						)
					)
					(width 0)
					(fill yes)
				)
			)
		)
	)
	(footprint ""
		(layer "F.Cu")
		(at 23.756874 -125.638814 180)
		(property "Reference" "R346"
			(at 0 0 180)
			(layer "F.SilkS")
			(hide yes)
			(effects
				(font
					(size 1.27 1.27)
				)
			)
		)
		(property "Value" "150R2F-1-GP"
			(at 0.064008 -3.993896 180)
			(unlocked yes)
			(layer "F.Fab")
			(hide yes)
			(effects
				(font
					(size 1.016 1.016)
					(thickness 0.1524)
				)
			)
		)
		(property "Device Type" "R402H16"
			(at 0.064008 -5.517896 180)
			(unlocked yes)
			(layer "F.Fab")
			(hide yes)
			(effects
				(font
					(size 1.016 1.016)
					(thickness 0.1524)
				)
			)
		)
		(duplicate_pad_numbers_are_jumpers no)
		(fp_line
			(start 0.508 -0.9398)
			(end -0.508 -0.9398)
			(stroke
				(width 0.1524)
				(type default)
			)
			(layer "F.SilkS")
		)
		(fp_line
			(start -0.508 -0.9398)
			(end -0.508 0.9398)
			(stroke
				(width 0.1524)
				(type default)
			)
			(layer "F.SilkS")
		)
		(fp_rect
			(start -0.508 0.9398)
			(end 0.508 -0.9398)
			(stroke
				(width 0)
				(type default)
			)
			(fill no)
			(layer "F.CrtYd")
		)
		(fp_rect
			(start -0.508 0.9398)
			(end 0.508 -0.9398)
			(stroke
				(width 0)
				(type default)
			)
			(fill no)
			(layer "F.Fab")
		)
		(pad "1" smd custom
			(at 0 -0.4445 180)
			(size 0.1397 0.1397)
			(layers "F.Cu" "F.Mask" "F.Paste")
			(net "P3V3_STBY")
			(options
				(clearance outline)
				(anchor circle)
			)
			(primitives
				(gr_poly
					(pts
						(arc
							(start -0.1778 -0.2794)
							(mid -0.249642 -0.249642)
							(end -0.2794 -0.1778)
						)
						(arc
							(start -0.2794 0.1778)
							(mid -0.249642 0.249642)
							(end -0.1778 0.2794)
						)
						(arc
							(start 0.1778 0.2794)
							(mid 0.249642 0.249642)
							(end 0.2794 0.1778)
						)
						(arc
							(start 0.2794 -0.1778)
							(mid 0.249642 -0.249642)
							(end 0.1778 -0.2794)
						)
					)
					(width 0)
					(fill yes)
				)
			)
		)
		(pad "2" smd custom
			(at 0 0.4445 180)
			(size 0.1397 0.1397)
			(layers "F.Cu" "F.Mask" "F.Paste")
			(net "BMC_HBLED_R")
			(options
				(clearance outline)
				(anchor circle)
			)
			(primitives
				(gr_poly
					(pts
						(arc
							(start -0.1778 -0.2794)
							(mid -0.249642 -0.249642)
							(end -0.2794 -0.1778)
						)
						(arc
							(start -0.2794 0.1778)
							(mid -0.249642 0.249642)
							(end -0.1778 0.2794)
						)
						(arc
							(start 0.1778 0.2794)
							(mid 0.249642 0.249642)
							(end 0.2794 0.1778)
						)
						(arc
							(start 0.2794 -0.1778)
							(mid 0.249642 -0.249642)
							(end 0.1778 -0.2794)
						)
					)
					(width 0)
					(fill yes)
				)
			)
		)
	)
	(footprint ""
		(layer "F.Cu")
		(at 134.441438 -12.737592 -90)
		(property "Reference" "R443"
			(at 0 0 270)
			(layer "F.SilkS")
			(hide yes)
			(effects
				(font
					(size 1.27 1.27)
				)
			)
		)
		(property "Value" "10R2F-L-GP"
			(at 0.064008 -3.993896 270)
			(unlocked yes)
			(layer "F.Fab")
			(hide yes)
			(effects
				(font
					(size 1.016 1.016)
					(thickness 0.1524)
				)
			)
		)
		(property "Device Type" "R402H14"
			(at 0.064008 -5.517896 270)
			(unlocked yes)
			(layer "F.Fab")
			(hide yes)
			(effects
				(font
					(size 1.016 1.016)
					(thickness 0.1524)
				)
			)
		)
		(duplicate_pad_numbers_are_jumpers no)
		(fp_line
			(start -0.508 -0.9398)
			(end -0.508 0.9398)
			(stroke
				(width 0.1524)
				(type default)
			)
			(layer "F.SilkS")
		)
		(fp_line
			(start 0.508 -0.9398)
			(end -0.508 -0.9398)
			(stroke
				(width 0.1524)
				(type default)
			)
			(layer "F.SilkS")
		)
		(fp_rect
			(start -0.508 0.9398)
			(end 0.508 -0.9398)
			(stroke
				(width 0)
				(type default)
			)
			(fill no)
			(layer "F.CrtYd")
		)
		(fp_rect
			(start -0.508 0.9398)
			(end 0.508 -0.9398)
			(stroke
				(width 0)
				(type default)
			)
			(fill no)
			(layer "F.Fab")
		)
		(pad "1" smd custom
			(at 0 -0.4445 270)
			(size 0.1397 0.1397)
			(layers "F.Cu" "F.Mask" "F.Paste")
			(net "MB0_CM_SENSE_R1_N")
			(options
				(clearance outline)
				(anchor circle)
			)
			(primitives
				(gr_poly
					(pts
						(arc
							(start -0.1778 -0.2794)
							(mid -0.249642 -0.249642)
							(end -0.2794 -0.1778)
						)
						(arc
							(start -0.2794 0.1778)
							(mid -0.249642 0.249642)
							(end -0.1778 0.2794)
						)
						(arc
							(start 0.1778 0.2794)
							(mid 0.249642 0.249642)
							(end 0.2794 0.1778)
						)
						(arc
							(start 0.2794 -0.1778)
							(mid 0.249642 -0.249642)
							(end 0.1778 -0.2794)
						)
					)
					(width 0)
					(fill yes)
				)
			)
		)
		(pad "2" smd custom
			(at 0 0.4445 270)
			(size 0.1397 0.1397)
			(layers "F.Cu" "F.Mask" "F.Paste")
			(net "ADM1278_HS_N")
			(options
				(clearance outline)
				(anchor circle)
			)
			(primitives
				(gr_poly
					(pts
						(arc
							(start -0.1778 -0.2794)
							(mid -0.249642 -0.249642)
							(end -0.2794 -0.1778)
						)
						(arc
							(start -0.2794 0.1778)
							(mid -0.249642 0.249642)
							(end -0.1778 0.2794)
						)
						(arc
							(start 0.1778 0.2794)
							(mid 0.249642 0.249642)
							(end 0.2794 0.1778)
						)
						(arc
							(start 0.2794 -0.1778)
							(mid 0.249642 -0.249642)
							(end 0.1778 -0.2794)
						)
					)
					(width 0)
					(fill yes)
				)
			)
		)
	)
	(footprint ""
		(layer "F.Cu")
		(at 37.589968 -132.000244 90)
		(property "Reference" "R379"
			(at 0 0 90)
			(layer "F.SilkS")
			(hide yes)
			(effects
				(font
					(size 1.27 1.27)
				)
			)
		)
		(property "Value" "4K7R2F-GP"
			(at 0.064008 -3.993896 90)
			(unlocked yes)
			(layer "F.Fab")
			(hide yes)
			(effects
				(font
					(size 1.016 1.016)
					(thickness 0.1524)
				)
			)
		)
		(property "Device Type" "R402H16"
			(at 0.064008 -5.517896 90)
			(unlocked yes)
			(layer "F.Fab")
			(hide yes)
			(effects
				(font
					(size 1.016 1.016)
					(thickness 0.1524)
				)
			)
		)
		(duplicate_pad_numbers_are_jumpers no)
		(fp_line
			(start 0.508 -0.9398)
			(end -0.508 -0.9398)
			(stroke
				(width 0.1524)
				(type default)
			)
			(layer "F.SilkS")
		)
		(fp_line
			(start -0.508 -0.9398)
			(end -0.508 0.9398)
			(stroke
				(width 0.1524)
				(type default)
			)
			(layer "F.SilkS")
		)
		(fp_rect
			(start -0.508 0.9398)
			(end 0.508 -0.9398)
			(stroke
				(width 0)
				(type default)
			)
			(fill no)
			(layer "F.CrtYd")
		)
		(fp_rect
			(start -0.508 0.9398)
			(end 0.508 -0.9398)
			(stroke
				(width 0)
				(type default)
			)
			(fill no)
			(layer "F.Fab")
		)
		(pad "1" smd custom
			(at 0 -0.4445 90)
			(size 0.1397 0.1397)
			(layers "F.Cu" "F.Mask" "F.Paste")
			(net "P3V3_STBY")
			(options
				(clearance outline)
				(anchor circle)
			)
			(primitives
				(gr_poly
					(pts
						(arc
							(start -0.1778 -0.2794)
							(mid -0.249642 -0.249642)
							(end -0.2794 -0.1778)
						)
						(arc
							(start -0.2794 0.1778)
							(mid -0.249642 0.249642)
							(end -0.1778 0.2794)
						)
						(arc
							(start 0.1778 0.2794)
							(mid 0.249642 0.249642)
							(end 0.2794 0.1778)
						)
						(arc
							(start 0.2794 -0.1778)
							(mid 0.249642 -0.249642)
							(end 0.1778 -0.2794)
						)
					)
					(width 0)
					(fill yes)
				)
			)
		)
		(pad "2" smd custom
			(at 0 0.4445 90)
			(size 0.1397 0.1397)
			(layers "F.Cu" "F.Mask" "F.Paste")
			(net "BMC_GPIOZ7")
			(options
				(clearance outline)
				(anchor circle)
			)
			(primitives
				(gr_poly
					(pts
						(arc
							(start -0.1778 -0.2794)
							(mid -0.249642 -0.249642)
							(end -0.2794 -0.1778)
						)
						(arc
							(start -0.2794 0.1778)
							(mid -0.249642 0.249642)
							(end -0.1778 0.2794)
						)
						(arc
							(start 0.1778 0.2794)
							(mid 0.249642 0.249642)
							(end 0.2794 0.1778)
						)
						(arc
							(start 0.2794 -0.1778)
							(mid 0.249642 -0.249642)
							(end 0.1778 -0.2794)
						)
					)
					(width 0)
					(fill yes)
				)
			)
		)
	)
	(footprint ""
		(layer "F.Cu")
		(at 207.8736 -108.1532 90)
		(property "Reference" "R550"
			(at 0 0 90)
			(layer "F.SilkS")
			(hide yes)
			(effects
				(font
					(size 1.27 1.27)
				)
			)
		)
		(property "Value" "4K7R2F-GP"
			(at 0.064008 -3.993896 90)
			(unlocked yes)
			(layer "F.Fab")
			(hide yes)
			(effects
				(font
					(size 1.016 1.016)
					(thickness 0.1524)
				)
			)
		)
		(property "Device Type" "R402H16"
			(at 0.064008 -5.517896 90)
			(unlocked yes)
			(layer "F.Fab")
			(hide yes)
			(effects
				(font
					(size 1.016 1.016)
					(thickness 0.1524)
				)
			)
		)
		(duplicate_pad_numbers_are_jumpers no)
		(fp_line
			(start 0.508 -0.9398)
			(end -0.508 -0.9398)
			(stroke
				(width 0.1524)
				(type default)
			)
			(layer "F.SilkS")
		)
		(fp_line
			(start -0.508 -0.9398)
			(end -0.508 0.9398)
			(stroke
				(width 0.1524)
				(type default)
			)
			(layer "F.SilkS")
		)
		(fp_rect
			(start -0.508 0.9398)
			(end 0.508 -0.9398)
			(stroke
				(width 0)
				(type default)
			)
			(fill no)
			(layer "F.CrtYd")
		)
		(fp_rect
			(start -0.508 0.9398)
			(end 0.508 -0.9398)
			(stroke
				(width 0)
				(type default)
			)
			(fill no)
			(layer "F.Fab")
		)
		(pad "1" smd custom
			(at 0 -0.4445 90)
			(size 0.1397 0.1397)
			(layers "F.Cu" "F.Mask" "F.Paste")
			(net "TEMP_2_A2")
			(options
				(clearance outline)
				(anchor circle)
			)
			(primitives
				(gr_poly
					(pts
						(arc
							(start -0.1778 -0.2794)
							(mid -0.249642 -0.249642)
							(end -0.2794 -0.1778)
						)
						(arc
							(start -0.2794 0.1778)
							(mid -0.249642 0.249642)
							(end -0.1778 0.2794)
						)
						(arc
							(start 0.1778 0.2794)
							(mid 0.249642 0.249642)
							(end 0.2794 0.1778)
						)
						(arc
							(start 0.2794 -0.1778)
							(mid 0.249642 -0.249642)
							(end 0.1778 -0.2794)
						)
					)
					(width 0)
					(fill yes)
				)
			)
		)
		(pad "2" smd custom
			(at 0 0.4445 90)
			(size 0.1397 0.1397)
			(layers "F.Cu" "F.Mask" "F.Paste")
			(net "GND")
			(options
				(clearance outline)
				(anchor circle)
			)
			(primitives
				(gr_poly
					(pts
						(arc
							(start -0.1778 -0.2794)
							(mid -0.249642 -0.249642)
							(end -0.2794 -0.1778)
						)
						(arc
							(start -0.2794 0.1778)
							(mid -0.249642 0.249642)
							(end -0.1778 0.2794)
						)
						(arc
							(start 0.1778 0.2794)
							(mid 0.249642 0.249642)
							(end 0.2794 0.1778)
						)
						(arc
							(start 0.2794 -0.1778)
							(mid 0.249642 -0.249642)
							(end 0.1778 -0.2794)
						)
					)
					(width 0)
					(fill yes)
				)
			)
		)
	)
	(footprint ""
		(layer "F.Cu")
		(at 160.472374 -15.293594)
		(property "Reference" "C207"
			(at 0 0 0)
			(layer "F.SilkS")
			(hide yes)
			(effects
				(font
					(size 1.27 1.27)
				)
			)
		)
		(property "Value" "SCD1U50V3KX-GP"
			(at 0 -2.8194 0)
			(unlocked yes)
			(layer "F.Fab")
			(hide yes)
			(effects
				(font
					(size 1.016 1.016)
					(thickness 0.1524)
				)
			)
		)
		(property "Device Type" "C603H36"
			(at 0 -4.3434 0)
			(unlocked yes)
			(layer "F.Fab")
			(hide yes)
			(effects
				(font
					(size 1.016 1.016)
					(thickness 0.1524)
				)
			)
		)
		(duplicate_pad_numbers_are_jumpers no)
		(fp_line
			(start 0.508 0)
			(end -0.508 0)
			(stroke
				(width 0.2032)
				(type default)
			)
			(layer "F.SilkS")
		)
		(fp_rect
			(start -0.5842 1.3335)
			(end 0.5842 -1.3335)
			(stroke
				(width 0)
				(type default)
			)
			(fill no)
			(layer "F.CrtYd")
		)
		(fp_rect
			(start -0.5842 1.3335)
			(end 0.5842 -1.3335)
			(stroke
				(width 0)
				(type default)
			)
			(fill no)
			(layer "F.Fab")
		)
		(pad "1" smd custom
			(at 0 -0.762)
			(size 0.2159 0.2159)
			(layers "F.Cu" "F.Mask" "F.Paste")
			(net "P1V8_STBY_VBST_RR")
			(options
				(clearance outline)
				(anchor circle)
			)
			(primitives
				(gr_poly
					(pts
						(arc
							(start -0.3302 -0.4318)
							(mid -0.402042 -0.402042)
							(end -0.4318 -0.3302)
						)
						(arc
							(start -0.4318 0.3302)
							(mid -0.402042 0.402042)
							(end -0.3302 0.4318)
						)
						(arc
							(start 0.3302 0.4318)
							(mid 0.402042 0.402042)
							(end 0.4318 0.3302)
						)
						(arc
							(start 0.4318 -0.3302)
							(mid 0.402042 -0.402042)
							(end 0.3302 -0.4318)
						)
					)
					(width 0)
					(fill yes)
				)
			)
		)
		(pad "2" smd custom
			(at 0 0.762)
			(size 0.2159 0.2159)
			(layers "F.Cu" "F.Mask" "F.Paste")
			(net "P1V8_STBY_SW")
			(options
				(clearance outline)
				(anchor circle)
			)
			(primitives
				(gr_poly
					(pts
						(arc
							(start -0.3302 -0.4318)
							(mid -0.402042 -0.402042)
							(end -0.4318 -0.3302)
						)
						(arc
							(start -0.4318 0.3302)
							(mid -0.402042 0.402042)
							(end -0.3302 0.4318)
						)
						(arc
							(start 0.3302 0.4318)
							(mid 0.402042 0.402042)
							(end 0.4318 0.3302)
						)
						(arc
							(start 0.4318 -0.3302)
							(mid 0.402042 -0.402042)
							(end 0.3302 -0.4318)
						)
					)
					(width 0)
					(fill yes)
				)
			)
		)
	)
	(footprint ""
		(layer "F.Cu")
		(at 54.713124 -162.481768 180)
		(property "Reference" "C118"
			(at 0 0 180)
			(layer "F.SilkS")
			(hide yes)
			(effects
				(font
					(size 1.27 1.27)
				)
			)
		)
		(property "Value" "SCD1U25V2KX-2-GP"
			(at 1.1811 -2.7051 180)
			(unlocked yes)
			(layer "F.Fab")
			(hide yes)
			(effects
				(font
					(size 1.016 1.016)
					(thickness 0.1524)
				)
			)
		)
		(property "Device Type" "C402H22"
			(at 1.1811 -4.2291 180)
			(unlocked yes)
			(layer "F.Fab")
			(hide yes)
			(effects
				(font
					(size 1.016 1.016)
					(thickness 0.1524)
				)
			)
		)
		(duplicate_pad_numbers_are_jumpers no)
		(fp_rect
			(start -0.4318 0.9525)
			(end 0.4318 -0.9525)
			(stroke
				(width 0)
				(type default)
			)
			(fill no)
			(layer "F.CrtYd")
		)
		(fp_rect
			(start -0.4318 0.9525)
			(end 0.4318 -0.9525)
			(stroke
				(width 0)
				(type default)
			)
			(fill no)
			(layer "F.Fab")
		)
		(pad "1" smd custom
			(at 0 -0.4445 180)
			(size 0.1524 0.1524)
			(layers "F.Cu" "F.Mask" "F.Paste")
			(net "ADC_P1V8_STBY")
			(options
				(clearance outline)
				(anchor circle)
			)
			(primitives
				(gr_poly
					(pts
						(arc
							(start 0.3048 -0.2032)
							(mid 0.275042 -0.275042)
							(end 0.2032 -0.3048)
						)
						(arc
							(start -0.2032 -0.3048)
							(mid -0.275042 -0.275042)
							(end -0.3048 -0.2032)
						)
						(arc
							(start -0.3048 0.2032)
							(mid -0.275042 0.275042)
							(end -0.2032 0.3048)
						)
						(arc
							(start 0.2032 0.3048)
							(mid 0.275042 0.275042)
							(end 0.3048 0.2032)
						)
					)
					(width 0)
					(fill yes)
				)
			)
		)
		(pad "2" smd custom
			(at 0 0.4445 180)
			(size 0.1524 0.1524)
			(layers "F.Cu" "F.Mask" "F.Paste")
			(net "GND")
			(options
				(clearance outline)
				(anchor circle)
			)
			(primitives
				(gr_poly
					(pts
						(arc
							(start 0.3048 -0.2032)
							(mid 0.275042 -0.275042)
							(end 0.2032 -0.3048)
						)
						(arc
							(start -0.2032 -0.3048)
							(mid -0.275042 -0.275042)
							(end -0.3048 -0.2032)
						)
						(arc
							(start -0.3048 0.2032)
							(mid -0.275042 0.275042)
							(end -0.2032 0.3048)
						)
						(arc
							(start 0.2032 0.3048)
							(mid 0.275042 0.275042)
							(end 0.3048 0.2032)
						)
					)
					(width 0)
					(fill yes)
				)
			)
		)
	)
	(footprint ""
		(layer "F.Cu")
		(at 87.6554 -136.6266 180)
		(property "Reference" "R133"
			(at 0 0 180)
			(layer "F.SilkS")
			(hide yes)
			(effects
				(font
					(size 1.27 1.27)
				)
			)
		)
		(property "Value" "8K2R2J-3-GP"
			(at 0.064008 -3.993896 180)
			(unlocked yes)
			(layer "F.Fab")
			(hide yes)
			(effects
				(font
					(size 1.016 1.016)
					(thickness 0.1524)
				)
			)
		)
		(property "Device Type" "R402H16"
			(at 0.064008 -5.517896 180)
			(unlocked yes)
			(layer "F.Fab")
			(hide yes)
			(effects
				(font
					(size 1.016 1.016)
					(thickness 0.1524)
				)
			)
		)
		(duplicate_pad_numbers_are_jumpers no)
		(fp_line
			(start 0.508 -0.9398)
			(end -0.508 -0.9398)
			(stroke
				(width 0.1524)
				(type default)
			)
			(layer "F.SilkS")
		)
		(fp_line
			(start -0.508 -0.9398)
			(end -0.508 0.9398)
			(stroke
				(width 0.1524)
				(type default)
			)
			(layer "F.SilkS")
		)
		(fp_rect
			(start -0.508 0.9398)
			(end 0.508 -0.9398)
			(stroke
				(width 0)
				(type default)
			)
			(fill no)
			(layer "F.CrtYd")
		)
		(fp_rect
			(start -0.508 0.9398)
			(end 0.508 -0.9398)
			(stroke
				(width 0)
				(type default)
			)
			(fill no)
			(layer "F.Fab")
		)
		(pad "1" smd custom
			(at 0 -0.4445 180)
			(size 0.1397 0.1397)
			(layers "F.Cu" "F.Mask" "F.Paste")
			(net "P3V3_STBY")
			(options
				(clearance outline)
				(anchor circle)
			)
			(primitives
				(gr_poly
					(pts
						(arc
							(start -0.1778 -0.2794)
							(mid -0.249642 -0.249642)
							(end -0.2794 -0.1778)
						)
						(arc
							(start -0.2794 0.1778)
							(mid -0.249642 0.249642)
							(end -0.1778 0.2794)
						)
						(arc
							(start 0.1778 0.2794)
							(mid 0.249642 0.249642)
							(end 0.2794 0.1778)
						)
						(arc
							(start 0.2794 -0.1778)
							(mid 0.249642 -0.249642)
							(end 0.1778 -0.2794)
						)
					)
					(width 0)
					(fill yes)
				)
			)
		)
		(pad "2" smd custom
			(at 0 0.4445 180)
			(size 0.1397 0.1397)
			(layers "F.Cu" "F.Mask" "F.Paste")
			(net "EEPROM_A0")
			(options
				(clearance outline)
				(anchor circle)
			)
			(primitives
				(gr_poly
					(pts
						(arc
							(start -0.1778 -0.2794)
							(mid -0.249642 -0.249642)
							(end -0.2794 -0.1778)
						)
						(arc
							(start -0.2794 0.1778)
							(mid -0.249642 0.249642)
							(end -0.1778 0.2794)
						)
						(arc
							(start 0.1778 0.2794)
							(mid 0.249642 0.249642)
							(end 0.2794 0.1778)
						)
						(arc
							(start 0.2794 -0.1778)
							(mid 0.249642 -0.249642)
							(end 0.1778 -0.2794)
						)
					)
					(width 0)
					(fill yes)
				)
			)
		)
	)
	(footprint ""
		(layer "F.Cu")
		(at 82.94116 -157.3276 90)
		(property "Reference" "C238"
			(at 0 0 90)
			(layer "F.SilkS")
			(hide yes)
			(effects
				(font
					(size 1.27 1.27)
				)
			)
		)
		(property "Value" "SC10U6D3V5KX-4GP"
			(at -0.0762 -6.1214 90)
			(unlocked yes)
			(layer "F.Fab")
			(hide yes)
			(effects
				(font
					(size 1.016 1.016)
					(thickness 0.1524)
				)
			)
		)
		(property "Device Type" "C805H58"
			(at -0.0762 -8.1534 90)
			(unlocked yes)
			(layer "F.Fab")
			(hide yes)
			(effects
				(font
					(size 1.016 1.016)
					(thickness 0.1524)
				)
			)
		)
		(duplicate_pad_numbers_are_jumpers no)
		(fp_line
			(start 0.635 0)
			(end -0.635 0)
			(stroke
				(width 0.508)
				(type default)
			)
			(layer "F.SilkS")
		)
		(fp_rect
			(start -0.9652 1.778)
			(end 0.9652 -1.778)
			(stroke
				(width 0)
				(type default)
			)
			(fill no)
			(layer "F.CrtYd")
		)
		(fp_poly
			(pts
				(xy -0.9652 -1.778) (xy 0.9652 -1.778) (xy 0.9652 1.778) (xy -0.9652 1.778)
			)
			(stroke
				(width 0)
				(type default)
			)
			(fill no)
			(layer "F.Fab")
		)
		(pad "1" smd rect
			(at 0 -0.9652 90)
			(size 1.397 1.143)
			(layers "F.Cu" "F.Mask" "F.Paste")
			(net "TPS74801_P1V15_STBY_OUT")
		)
		(pad "2" smd rect
			(at 0 0.9652 90)
			(size 1.397 1.143)
			(layers "F.Cu" "F.Mask" "F.Paste")
			(net "GND")
		)
	)
	(footprint ""
		(layer "F.Cu")
		(at 52.8066 -162.4838 180)
		(property "Reference" "C122"
			(at 0 0 180)
			(layer "F.SilkS")
			(hide yes)
			(effects
				(font
					(size 1.27 1.27)
				)
			)
		)
		(property "Value" "SCD1U25V2KX-2-GP"
			(at 1.1811 -2.7051 180)
			(unlocked yes)
			(layer "F.Fab")
			(hide yes)
			(effects
				(font
					(size 1.016 1.016)
					(thickness 0.1524)
				)
			)
		)
		(property "Device Type" "C402H22"
			(at 1.1811 -4.2291 180)
			(unlocked yes)
			(layer "F.Fab")
			(hide yes)
			(effects
				(font
					(size 1.016 1.016)
					(thickness 0.1524)
				)
			)
		)
		(duplicate_pad_numbers_are_jumpers no)
		(fp_rect
			(start -0.4318 0.9525)
			(end 0.4318 -0.9525)
			(stroke
				(width 0)
				(type default)
			)
			(fill no)
			(layer "F.CrtYd")
		)
		(fp_rect
			(start -0.4318 0.9525)
			(end 0.4318 -0.9525)
			(stroke
				(width 0)
				(type default)
			)
			(fill no)
			(layer "F.Fab")
		)
		(pad "1" smd custom
			(at 0 -0.4445 180)
			(size 0.1524 0.1524)
			(layers "F.Cu" "F.Mask" "F.Paste")
			(net "ADC_P3V3")
			(options
				(clearance outline)
				(anchor circle)
			)
			(primitives
				(gr_poly
					(pts
						(arc
							(start 0.3048 -0.2032)
							(mid 0.275042 -0.275042)
							(end 0.2032 -0.3048)
						)
						(arc
							(start -0.2032 -0.3048)
							(mid -0.275042 -0.275042)
							(end -0.3048 -0.2032)
						)
						(arc
							(start -0.3048 0.2032)
							(mid -0.275042 0.275042)
							(end -0.2032 0.3048)
						)
						(arc
							(start 0.2032 0.3048)
							(mid 0.275042 0.275042)
							(end 0.3048 0.2032)
						)
					)
					(width 0)
					(fill yes)
				)
			)
		)
		(pad "2" smd custom
			(at 0 0.4445 180)
			(size 0.1524 0.1524)
			(layers "F.Cu" "F.Mask" "F.Paste")
			(net "GND")
			(options
				(clearance outline)
				(anchor circle)
			)
			(primitives
				(gr_poly
					(pts
						(arc
							(start 0.3048 -0.2032)
							(mid 0.275042 -0.275042)
							(end 0.2032 -0.3048)
						)
						(arc
							(start -0.2032 -0.3048)
							(mid -0.275042 -0.275042)
							(end -0.3048 -0.2032)
						)
						(arc
							(start -0.3048 0.2032)
							(mid -0.275042 0.275042)
							(end -0.2032 0.3048)
						)
						(arc
							(start 0.2032 0.3048)
							(mid 0.275042 0.275042)
							(end 0.3048 0.2032)
						)
					)
					(width 0)
					(fill yes)
				)
			)
		)
	)
	(footprint ""
		(layer "F.Cu")
		(at 37.299646 -173.66361 90)
		(property "Reference" "R496"
			(at 0 0 90)
			(layer "F.SilkS")
			(hide yes)
			(effects
				(font
					(size 1.27 1.27)
				)
			)
		)
		(property "Value" "44K2R2F-1-GP"
			(at 0.064008 -3.993896 90)
			(unlocked yes)
			(layer "F.Fab")
			(hide yes)
			(effects
				(font
					(size 1.016 1.016)
					(thickness 0.1524)
				)
			)
		)
		(property "Device Type" "R402H16"
			(at 0.064008 -5.517896 90)
			(unlocked yes)
			(layer "F.Fab")
			(hide yes)
			(effects
				(font
					(size 1.016 1.016)
					(thickness 0.1524)
				)
			)
		)
		(duplicate_pad_numbers_are_jumpers no)
		(fp_line
			(start 0.508 -0.9398)
			(end -0.508 -0.9398)
			(stroke
				(width 0.1524)
				(type default)
			)
			(layer "F.SilkS")
		)
		(fp_line
			(start -0.508 -0.9398)
			(end -0.508 0.9398)
			(stroke
				(width 0.1524)
				(type default)
			)
			(layer "F.SilkS")
		)
		(fp_rect
			(start -0.508 0.9398)
			(end 0.508 -0.9398)
			(stroke
				(width 0)
				(type default)
			)
			(fill no)
			(layer "F.CrtYd")
		)
		(fp_rect
			(start -0.508 0.9398)
			(end 0.508 -0.9398)
			(stroke
				(width 0)
				(type default)
			)
			(fill no)
			(layer "F.Fab")
		)
		(pad "1" smd custom
			(at 0 -0.4445 90)
			(size 0.1397 0.1397)
			(layers "F.Cu" "F.Mask" "F.Paste")
			(net "P3V3_STBY_VFB")
			(options
				(clearance outline)
				(anchor circle)
			)
			(primitives
				(gr_poly
					(pts
						(arc
							(start -0.1778 -0.2794)
							(mid -0.249642 -0.249642)
							(end -0.2794 -0.1778)
						)
						(arc
							(start -0.2794 0.1778)
							(mid -0.249642 0.249642)
							(end -0.1778 0.2794)
						)
						(arc
							(start 0.1778 0.2794)
							(mid 0.249642 0.249642)
							(end 0.2794 0.1778)
						)
						(arc
							(start 0.2794 -0.1778)
							(mid 0.249642 -0.249642)
							(end 0.1778 -0.2794)
						)
					)
					(width 0)
					(fill yes)
				)
			)
		)
		(pad "2" smd custom
			(at 0 0.4445 90)
			(size 0.1397 0.1397)
			(layers "F.Cu" "F.Mask" "F.Paste")
			(net "P3V3_STBY_VFB_R")
			(options
				(clearance outline)
				(anchor circle)
			)
			(primitives
				(gr_poly
					(pts
						(arc
							(start -0.1778 -0.2794)
							(mid -0.249642 -0.249642)
							(end -0.2794 -0.1778)
						)
						(arc
							(start -0.2794 0.1778)
							(mid -0.249642 0.249642)
							(end -0.1778 0.2794)
						)
						(arc
							(start 0.1778 0.2794)
							(mid 0.249642 0.249642)
							(end 0.2794 0.1778)
						)
						(arc
							(start 0.2794 -0.1778)
							(mid 0.249642 -0.249642)
							(end 0.1778 -0.2794)
						)
					)
					(width 0)
					(fill yes)
				)
			)
		)
	)
	(footprint ""
		(layer "F.Cu")
		(at 33.1216 -131.5212)
		(property "Reference" "OSC1"
			(at 0 0 0)
			(layer "F.SilkS")
			(hide yes)
			(effects
				(font
					(size 1.27 1.27)
				)
			)
		)
		(property "Value" "OSC-24MHZ-18-GP"
			(at 0.0127 -2.7686 0)
			(unlocked yes)
			(layer "F.Fab")
			(hide yes)
			(effects
				(font
					(size 1.016 1.016)
					(thickness 0.1524)
				)
			)
		)
		(property "Device Type" "OSC-3225-4P-3H48"
			(at 0.0127 -4.2926 0)
			(unlocked yes)
			(layer "F.Fab")
			(hide yes)
			(effects
				(font
					(size 1.016 1.016)
					(thickness 0.1524)
				)
			)
		)
		(duplicate_pad_numbers_are_jumpers no)
		(fp_line
			(start -2.2352 1.6256)
			(end -2.2352 0.635)
			(stroke
				(width 0.3302)
				(type default)
			)
			(layer "F.SilkS")
		)
		(fp_line
			(start -2.1209 -1.5367)
			(end 2.1209 -1.5367)
			(stroke
				(width 0.1524)
				(type default)
			)
			(layer "F.SilkS")
		)
		(fp_line
			(start -2.1209 1.5367)
			(end -2.1209 -1.5367)
			(stroke
				(width 0.1524)
				(type default)
			)
			(layer "F.SilkS")
		)
		(fp_line
			(start -1.3208 1.6256)
			(end -2.2352 1.6256)
			(stroke
				(width 0.3302)
				(type default)
			)
			(layer "F.SilkS")
		)
		(fp_line
			(start 2.1209 -1.5367)
			(end 2.1209 1.5367)
			(stroke
				(width 0.1524)
				(type default)
			)
			(layer "F.SilkS")
		)
		(fp_line
			(start 2.1209 1.5367)
			(end -2.1209 1.5367)
			(stroke
				(width 0.1524)
				(type default)
			)
			(layer "F.SilkS")
		)
		(fp_poly
			(pts
				(xy -3.7211 1.840992) (xy -3.7211 0.570992) (xy -3.0861 1.205992)
			)
			(stroke
				(width 0)
				(type default)
			)
			(fill yes)
			(layer "F.SilkS")
		)
		(fp_rect
			(start -1.6002 1.2446)
			(end 1.6002 -1.2446)
			(stroke
				(width 0)
				(type default)
			)
			(fill no)
			(layer "F.CrtYd")
		)
		(fp_poly
			(pts
				(xy -2.3749 1.7907) (xy -2.3749 -1.7907) (xy 2.3749 -1.7907) (xy 2.3749 1.7907) (xy 1.6002 1.7907)
				(xy 1.6002 -1.2446) (xy -1.6002 -1.2446) (xy -1.6002 1.2446) (xy 1.59512 1.2446) (xy 1.59512 1.7907)
			)
			(stroke
				(width 0)
				(type default)
			)
			(fill no)
			(layer "F.CrtYd")
		)
		(fp_rect
			(start -2.3749 1.7907)
			(end 2.3749 -1.7907)
			(stroke
				(width 0)
				(type default)
			)
			(fill no)
			(layer "F.Fab")
		)
		(pad "1" smd rect
			(at -1.171448 0.824992)
			(size 1.397 0.9144)
			(layers "F.Cu" "F.Mask" "F.Paste")
			(net "OSC_OE")
		)
		(pad "2" smd rect
			(at 1.171448 0.824992)
			(size 1.397 0.9144)
			(layers "F.Cu" "F.Mask" "F.Paste")
			(net "GND")
		)
		(pad "3" smd rect
			(at 1.171448 -0.824992)
			(size 1.397 0.9144)
			(layers "F.Cu" "F.Mask" "F.Paste")
			(net "OSC_OUT")
		)
		(pad "4" smd rect
			(at -1.171448 -0.824992)
			(size 1.397 0.9144)
			(layers "F.Cu" "F.Mask" "F.Paste")
			(net "P3V3_STBY")
		)
		(zone
			(layer "F.Cu")
			(hatch none 0.5)
			(connect_pads
				(clearance 0)
			)
			(min_thickness 0.25)
			(keepout
				(tracks not_allowed)
				(vias allowed)
				(pads allowed)
				(copperpour not_allowed)
				(footprints allowed)
			)
			(placement
				(enabled no)
				(sheetname "")
			)
			(fill
				(thermal_gap 0.5)
				(thermal_bridge_width 0.5)
				(island_removal_mode 0)
			)
			(polygon
				(pts
					(xy 32.973772 -131.478528) (xy 33.269428 -131.478528) (xy 33.269428 -131.563872) (xy 32.973772 -131.563872)
				)
			)
		)
		(zone
			(layer "F.Cu")
			(hatch none 0.5)
			(connect_pads
				(clearance 0)
			)
			(min_thickness 0.25)
			(keepout
				(tracks allowed)
				(vias not_allowed)
				(pads allowed)
				(copperpour not_allowed)
				(footprints allowed)
			)
			(placement
				(enabled no)
				(sheetname "")
			)
			(fill
				(thermal_gap 0.5)
				(thermal_bridge_width 0.5)
				(island_removal_mode 0)
			)
			(polygon
				(pts
					(xy 32.648652 -130.239008) (xy 32.648652 -131.153408) (xy 31.251652 -131.153408) (xy 31.251652 -131.888992)
					(xy 32.648652 -131.888992) (xy 32.648652 -132.803392) (xy 33.594548 -132.803392) (xy 33.594548 -131.888992)
					(xy 34.991548 -131.888992) (xy 34.991548 -131.153408) (xy 33.594548 -131.153408) (xy 33.594548 -130.239008)
				)
			)
		)
	)
	(footprint ""
		(layer "F.Cu")
		(at 199.1868 -7.5692 -90)
		(property "Reference" "R817"
			(at 0 0 270)
			(layer "F.SilkS")
			(hide yes)
			(effects
				(font
					(size 1.27 1.27)
				)
			)
		)
		(property "Value" "130R3F-GP"
			(at -0.0254 -2.5146 270)
			(unlocked yes)
			(layer "F.Fab")
			(hide yes)
			(effects
				(font
					(size 1.016 1.016)
					(thickness 0.1524)
				)
			)
		)
		(property "Device Type" "R603H22"
			(at -0.0254 -4.0386 270)
			(unlocked yes)
			(layer "F.Fab")
			(hide yes)
			(effects
				(font
					(size 1.016 1.016)
					(thickness 0.1524)
				)
			)
		)
		(duplicate_pad_numbers_are_jumpers no)
		(fp_line
			(start -0.4826 0)
			(end -0.2032 0)
			(stroke
				(width 0.2032)
				(type default)
			)
			(layer "F.SilkS")
		)
		(fp_line
			(start 0.2032 0)
			(end 0.4826 0)
			(stroke
				(width 0.2032)
				(type default)
			)
			(layer "F.SilkS")
		)
		(fp_rect
			(start -0.5842 1.3335)
			(end 0.5842 -1.3335)
			(stroke
				(width 0)
				(type default)
			)
			(fill no)
			(layer "F.CrtYd")
		)
		(fp_rect
			(start -0.5842 1.3335)
			(end 0.5842 -1.3335)
			(stroke
				(width 0)
				(type default)
			)
			(fill no)
			(layer "F.Fab")
		)
		(pad "1" smd custom
			(at 0 -0.762 270)
			(size 0.2159 0.2159)
			(layers "F.Cu" "F.Mask" "F.Paste")
			(net "ML_PWR_BLUE_LED_R")
			(options
				(clearance outline)
				(anchor circle)
			)
			(primitives
				(gr_poly
					(pts
						(arc
							(start -0.3302 -0.4318)
							(mid -0.402042 -0.402042)
							(end -0.4318 -0.3302)
						)
						(arc
							(start -0.4318 0.3302)
							(mid -0.402042 0.402042)
							(end -0.3302 0.4318)
						)
						(arc
							(start 0.3302 0.4318)
							(mid 0.402042 0.402042)
							(end 0.4318 0.3302)
						)
						(arc
							(start 0.4318 -0.3302)
							(mid 0.402042 -0.402042)
							(end 0.3302 -0.4318)
						)
					)
					(width 0)
					(fill yes)
				)
			)
		)
		(pad "2" smd custom
			(at 0 0.762 270)
			(size 0.2159 0.2159)
			(layers "F.Cu" "F.Mask" "F.Paste")
			(net "ML_PWR_BLUE_LED")
			(options
				(clearance outline)
				(anchor circle)
			)
			(primitives
				(gr_poly
					(pts
						(arc
							(start -0.3302 -0.4318)
							(mid -0.402042 -0.402042)
							(end -0.4318 -0.3302)
						)
						(arc
							(start -0.4318 0.3302)
							(mid -0.402042 0.402042)
							(end -0.3302 0.4318)
						)
						(arc
							(start 0.3302 0.4318)
							(mid 0.402042 0.402042)
							(end 0.4318 0.3302)
						)
						(arc
							(start 0.4318 -0.3302)
							(mid 0.402042 -0.402042)
							(end 0.3302 -0.4318)
						)
					)
					(width 0)
					(fill yes)
				)
			)
		)
	)
	(footprint ""
		(layer "F.Cu")
		(at 137.73023 -12.991592 180)
		(property "Reference" "R444"
			(at 0 0 180)
			(layer "F.SilkS")
			(hide yes)
			(effects
				(font
					(size 1.27 1.27)
				)
			)
		)
		(property "Value" "D002RL3115F-L-GP"
			(at 3.2258 1.2954 180)
			(unlocked yes)
			(layer "F.Fab")
			(hide yes)
			(effects
				(font
					(size 1.016 1.016)
					(thickness 0.1524)
				)
			)
		)
		(property "Device Type" "RL3115-4PH45"
			(at 3.2258 -0.2286 180)
			(unlocked yes)
			(layer "F.Fab")
			(hide yes)
			(effects
				(font
					(size 1.016 1.016)
					(thickness 0.1524)
				)
			)
		)
		(duplicate_pad_numbers_are_jumpers no)
		(fp_line
			(start 1.9685 1.651)
			(end -1.9685 1.651)
			(stroke
				(width 0.1524)
				(type default)
			)
			(layer "F.SilkS")
		)
		(fp_line
			(start 1.9685 -1.651)
			(end 1.9685 1.651)
			(stroke
				(width 0.1524)
				(type default)
			)
			(layer "F.SilkS")
		)
		(fp_line
			(start -0.5334 -1.7653)
			(end -2.0574 -1.7653)
			(stroke
				(width 0.3302)
				(type default)
			)
			(layer "F.SilkS")
		)
		(fp_line
			(start -1.9685 1.651)
			(end -1.9685 -1.651)
			(stroke
				(width 0.1524)
				(type default)
			)
			(layer "F.SilkS")
		)
		(fp_line
			(start -1.9685 -1.651)
			(end 1.9685 -1.651)
			(stroke
				(width 0.1524)
				(type default)
			)
			(layer "F.SilkS")
		)
		(fp_line
			(start -2.0574 -1.7653)
			(end -2.0574 -0.4064)
			(stroke
				(width 0.3302)
				(type default)
			)
			(layer "F.SilkS")
		)
		(fp_poly
			(pts
				(xy -2.29997 -1.016) (xy -2.80797 -1.524) (xy -2.80797 -0.508)
			)
			(stroke
				(width 0)
				(type default)
			)
			(fill yes)
			(layer "F.SilkS")
		)
		(fp_rect
			(start -1.524 0.7493)
			(end 1.524 -0.7493)
			(stroke
				(width 0)
				(type default)
			)
			(fill no)
			(layer "F.CrtYd")
		)
		(fp_poly
			(pts
				(xy -2.2225 1.905) (xy -2.2225 -1.905) (xy 2.2225 -1.905) (xy 2.2225 -0.7493) (xy -1.524 -0.7493)
				(xy -1.524 0.7493) (xy 1.524 0.7493) (xy 1.524 -0.7366) (xy 2.2225 -0.7366) (xy 2.2225 1.905)
			)
			(stroke
				(width 0)
				(type default)
			)
			(fill no)
			(layer "F.CrtYd")
		)
		(fp_rect
			(start -2.2225 1.905)
			(end 2.2225 -1.905)
			(stroke
				(width 0)
				(type default)
			)
			(fill no)
			(layer "F.Fab")
		)
		(pad "1" smd rect
			(at -0.5715 -0.813562 180)
			(size 2.286 1.143)
			(layers "F.Cu" "F.Mask" "F.Paste")
			(net "MB0_P12V_MAIN_R")
		)
		(pad "2" smd rect
			(at -0.5715 0.813562 180)
			(size 2.286 1.143)
			(layers "F.Cu" "F.Mask" "F.Paste")
			(net "P12V_IOM")
		)
		(pad "3" smd rect
			(at 1.334008 -0.813562 180)
			(size 0.762 1.143)
			(layers "F.Cu" "F.Mask" "F.Paste")
			(net "MB0_CM_SENSE_R1_N")
		)
		(pad "4" smd rect
			(at 1.334008 0.813562 180)
			(size 0.762 1.143)
			(layers "F.Cu" "F.Mask" "F.Paste")
			(net "MB0_CM_SENSE_R1_P")
		)
		(zone
			(layer "F.Cu")
			(hatch none 0.5)
			(connect_pads
				(clearance 0)
			)
			(min_thickness 0.25)
			(keepout
				(tracks not_allowed)
				(vias allowed)
				(pads allowed)
				(copperpour not_allowed)
				(footprints allowed)
			)
			(placement
				(enabled no)
				(sheetname "")
			)
			(fill
				(thermal_gap 0.5)
				(thermal_bridge_width 0.5)
				(island_removal_mode 0)
			)
			(polygon
				(pts
					(xy 137.15873 -13.740892) (xy 136.777222 -13.740892) (xy 136.777222 -13.233654) (xy 137.15873 -13.233654)
				)
			)
		)
		(zone
			(layer "F.Cu")
			(hatch none 0.5)
			(connect_pads
				(clearance 0)
			)
			(min_thickness 0.25)
			(keepout
				(tracks allowed)
				(vias not_allowed)
				(pads allowed)
				(copperpour not_allowed)
				(footprints allowed)
			)
			(placement
				(enabled no)
				(sheetname "")
			)
			(fill
				(thermal_gap 0.5)
				(thermal_bridge_width 0.5)
				(island_removal_mode 0)
			)
			(polygon
				(pts
					(xy 137.15873 -13.740892) (xy 136.777222 -13.740892) (xy 136.777222 -13.233654) (xy 137.15873 -13.233654)
				)
			)
		)
		(zone
			(layer "F.Cu")
			(hatch none 0.5)
			(connect_pads
				(clearance 0)
			)
			(min_thickness 0.25)
			(keepout
				(tracks not_allowed)
				(vias allowed)
				(pads allowed)
				(copperpour not_allowed)
				(footprints allowed)
			)
			(placement
				(enabled no)
				(sheetname "")
			)
			(fill
				(thermal_gap 0.5)
				(thermal_bridge_width 0.5)
				(island_removal_mode 0)
			)
			(polygon
				(pts
					(xy 137.15873 -12.74953) (xy 136.777222 -12.74953) (xy 136.777222 -12.242292) (xy 137.15873 -12.242292)
				)
			)
		)
		(zone
			(layer "F.Cu")
			(hatch none 0.5)
			(connect_pads
				(clearance 0)
			)
			(min_thickness 0.25)
			(keepout
				(tracks allowed)
				(vias not_allowed)
				(pads allowed)
				(copperpour not_allowed)
				(footprints allowed)
			)
			(placement
				(enabled no)
				(sheetname "")
			)
			(fill
				(thermal_gap 0.5)
				(thermal_bridge_width 0.5)
				(island_removal_mode 0)
			)
			(polygon
				(pts
					(xy 137.15873 -12.74953) (xy 136.777222 -12.74953) (xy 136.777222 -12.242292) (xy 137.15873 -12.242292)
				)
			)
		)
	)
	(footprint ""
		(layer "F.Cu")
		(at 179.2986 -107.6452 -90)
		(property "Reference" "C601"
			(at 0 0 270)
			(layer "F.SilkS")
			(hide yes)
			(effects
				(font
					(size 1.27 1.27)
				)
			)
		)
		(property "Value" "SCD1U16V2KX-3GP"
			(at 1.1811 -2.7051 270)
			(unlocked yes)
			(layer "F.Fab")
			(hide yes)
			(effects
				(font
					(size 1.016 1.016)
					(thickness 0.1524)
				)
			)
		)
		(property "Device Type" "C402H22"
			(at 1.1811 -4.2291 270)
			(unlocked yes)
			(layer "F.Fab")
			(hide yes)
			(effects
				(font
					(size 1.016 1.016)
					(thickness 0.1524)
				)
			)
		)
		(duplicate_pad_numbers_are_jumpers no)
		(fp_rect
			(start -0.4318 0.9525)
			(end 0.4318 -0.9525)
			(stroke
				(width 0)
				(type default)
			)
			(fill no)
			(layer "F.CrtYd")
		)
		(fp_rect
			(start -0.4318 0.9525)
			(end 0.4318 -0.9525)
			(stroke
				(width 0)
				(type default)
			)
			(fill no)
			(layer "F.Fab")
		)
		(pad "1" smd custom
			(at 0 -0.4445 270)
			(size 0.1524 0.1524)
			(layers "F.Cu" "F.Mask" "F.Paste")
			(net "P3V3_STBY")
			(options
				(clearance outline)
				(anchor circle)
			)
			(primitives
				(gr_poly
					(pts
						(arc
							(start 0.3048 -0.2032)
							(mid 0.275042 -0.275042)
							(end 0.2032 -0.3048)
						)
						(arc
							(start -0.2032 -0.3048)
							(mid -0.275042 -0.275042)
							(end -0.3048 -0.2032)
						)
						(arc
							(start -0.3048 0.2032)
							(mid -0.275042 0.275042)
							(end -0.2032 0.3048)
						)
						(arc
							(start 0.2032 0.3048)
							(mid 0.275042 0.275042)
							(end 0.3048 0.2032)
						)
					)
					(width 0)
					(fill yes)
				)
			)
		)
		(pad "2" smd custom
			(at 0 0.4445 270)
			(size 0.1524 0.1524)
			(layers "F.Cu" "F.Mask" "F.Paste")
			(net "GND")
			(options
				(clearance outline)
				(anchor circle)
			)
			(primitives
				(gr_poly
					(pts
						(arc
							(start 0.3048 -0.2032)
							(mid 0.275042 -0.275042)
							(end 0.2032 -0.3048)
						)
						(arc
							(start -0.2032 -0.3048)
							(mid -0.275042 -0.275042)
							(end -0.3048 -0.2032)
						)
						(arc
							(start -0.3048 0.2032)
							(mid -0.275042 0.275042)
							(end -0.2032 0.3048)
						)
						(arc
							(start 0.2032 0.3048)
							(mid 0.275042 0.275042)
							(end 0.3048 0.2032)
						)
					)
					(width 0)
					(fill yes)
				)
			)
		)
	)
	(footprint ""
		(layer "F.Cu")
		(at 44.3738 -161.417 180)
		(property "Reference" "R187"
			(at 0 0 180)
			(layer "F.SilkS")
			(hide yes)
			(effects
				(font
					(size 1.27 1.27)
				)
			)
		)
		(property "Value" "2K2R2F-GP"
			(at 0.064008 -3.993896 180)
			(unlocked yes)
			(layer "F.Fab")
			(hide yes)
			(effects
				(font
					(size 1.016 1.016)
					(thickness 0.1524)
				)
			)
		)
		(property "Device Type" "R402H16"
			(at 0.064008 -5.517896 180)
			(unlocked yes)
			(layer "F.Fab")
			(hide yes)
			(effects
				(font
					(size 1.016 1.016)
					(thickness 0.1524)
				)
			)
		)
		(duplicate_pad_numbers_are_jumpers no)
		(fp_line
			(start 0.508 -0.9398)
			(end -0.508 -0.9398)
			(stroke
				(width 0.1524)
				(type default)
			)
			(layer "F.SilkS")
		)
		(fp_line
			(start -0.508 -0.9398)
			(end -0.508 0.9398)
			(stroke
				(width 0.1524)
				(type default)
			)
			(layer "F.SilkS")
		)
		(fp_rect
			(start -0.508 0.9398)
			(end 0.508 -0.9398)
			(stroke
				(width 0)
				(type default)
			)
			(fill no)
			(layer "F.CrtYd")
		)
		(fp_rect
			(start -0.508 0.9398)
			(end 0.508 -0.9398)
			(stroke
				(width 0)
				(type default)
			)
			(fill no)
			(layer "F.Fab")
		)
		(pad "1" smd custom
			(at 0 -0.4445 180)
			(size 0.1397 0.1397)
			(layers "F.Cu" "F.Mask" "F.Paste")
			(net "I2C_M2_1_SCL")
			(options
				(clearance outline)
				(anchor circle)
			)
			(primitives
				(gr_poly
					(pts
						(arc
							(start -0.1778 -0.2794)
							(mid -0.249642 -0.249642)
							(end -0.2794 -0.1778)
						)
						(arc
							(start -0.2794 0.1778)
							(mid -0.249642 0.249642)
							(end -0.1778 0.2794)
						)
						(arc
							(start 0.1778 0.2794)
							(mid 0.249642 0.249642)
							(end 0.2794 0.1778)
						)
						(arc
							(start 0.2794 -0.1778)
							(mid 0.249642 -0.249642)
							(end 0.1778 -0.2794)
						)
					)
					(width 0)
					(fill yes)
				)
			)
		)
		(pad "2" smd custom
			(at 0 0.4445 180)
			(size 0.1397 0.1397)
			(layers "F.Cu" "F.Mask" "F.Paste")
			(net "P3V3_STBY")
			(options
				(clearance outline)
				(anchor circle)
			)
			(primitives
				(gr_poly
					(pts
						(arc
							(start -0.1778 -0.2794)
							(mid -0.249642 -0.249642)
							(end -0.2794 -0.1778)
						)
						(arc
							(start -0.2794 0.1778)
							(mid -0.249642 0.249642)
							(end -0.1778 0.2794)
						)
						(arc
							(start 0.1778 0.2794)
							(mid 0.249642 0.249642)
							(end 0.2794 0.1778)
						)
						(arc
							(start 0.2794 -0.1778)
							(mid 0.249642 -0.249642)
							(end 0.1778 -0.2794)
						)
					)
					(width 0)
					(fill yes)
				)
			)
		)
	)
	(footprint ""
		(layer "F.Cu")
		(at 181.8894 -111.0234 180)
		(property "Reference" "R551"
			(at 0 0 180)
			(layer "F.SilkS")
			(hide yes)
			(effects
				(font
					(size 1.27 1.27)
				)
			)
		)
		(property "Value" "4K7R2F-GP"
			(at 0.064008 -3.993896 180)
			(unlocked yes)
			(layer "F.Fab")
			(hide yes)
			(effects
				(font
					(size 1.016 1.016)
					(thickness 0.1524)
				)
			)
		)
		(property "Device Type" "R402H16"
			(at 0.064008 -5.517896 180)
			(unlocked yes)
			(layer "F.Fab")
			(hide yes)
			(effects
				(font
					(size 1.016 1.016)
					(thickness 0.1524)
				)
			)
		)
		(duplicate_pad_numbers_are_jumpers no)
		(fp_line
			(start 0.508 -0.9398)
			(end -0.508 -0.9398)
			(stroke
				(width 0.1524)
				(type default)
			)
			(layer "F.SilkS")
		)
		(fp_line
			(start -0.508 -0.9398)
			(end -0.508 0.9398)
			(stroke
				(width 0.1524)
				(type default)
			)
			(layer "F.SilkS")
		)
		(fp_rect
			(start -0.508 0.9398)
			(end 0.508 -0.9398)
			(stroke
				(width 0)
				(type default)
			)
			(fill no)
			(layer "F.CrtYd")
		)
		(fp_rect
			(start -0.508 0.9398)
			(end 0.508 -0.9398)
			(stroke
				(width 0)
				(type default)
			)
			(fill no)
			(layer "F.Fab")
		)
		(pad "1" smd custom
			(at 0 -0.4445 180)
			(size 0.1397 0.1397)
			(layers "F.Cu" "F.Mask" "F.Paste")
			(net "TEMP_1_A0")
			(options
				(clearance outline)
				(anchor circle)
			)
			(primitives
				(gr_poly
					(pts
						(arc
							(start -0.1778 -0.2794)
							(mid -0.249642 -0.249642)
							(end -0.2794 -0.1778)
						)
						(arc
							(start -0.2794 0.1778)
							(mid -0.249642 0.249642)
							(end -0.1778 0.2794)
						)
						(arc
							(start 0.1778 0.2794)
							(mid 0.249642 0.249642)
							(end 0.2794 0.1778)
						)
						(arc
							(start 0.2794 -0.1778)
							(mid 0.249642 -0.249642)
							(end 0.1778 -0.2794)
						)
					)
					(width 0)
					(fill yes)
				)
			)
		)
		(pad "2" smd custom
			(at 0 0.4445 180)
			(size 0.1397 0.1397)
			(layers "F.Cu" "F.Mask" "F.Paste")
			(net "GND")
			(options
				(clearance outline)
				(anchor circle)
			)
			(primitives
				(gr_poly
					(pts
						(arc
							(start -0.1778 -0.2794)
							(mid -0.249642 -0.249642)
							(end -0.2794 -0.1778)
						)
						(arc
							(start -0.2794 0.1778)
							(mid -0.249642 0.249642)
							(end -0.1778 0.2794)
						)
						(arc
							(start 0.1778 0.2794)
							(mid 0.249642 0.249642)
							(end 0.2794 0.1778)
						)
						(arc
							(start 0.2794 -0.1778)
							(mid 0.249642 -0.249642)
							(end 0.1778 -0.2794)
						)
					)
					(width 0)
					(fill yes)
				)
			)
		)
	)
	(footprint ""
		(layer "F.Cu")
		(at 25.844246 -186.56681 180)
		(property "Reference" "C170"
			(at 0 0 180)
			(layer "F.SilkS")
			(hide yes)
			(effects
				(font
					(size 1.27 1.27)
				)
			)
		)
		(property "Value" "SC10U16V5KX-7-GP-U"
			(at -0.0762 -6.1214 180)
			(unlocked yes)
			(layer "F.Fab")
			(hide yes)
			(effects
				(font
					(size 1.016 1.016)
					(thickness 0.1524)
				)
			)
		)
		(property "Device Type" "C805H58"
			(at -0.0762 -8.1534 180)
			(unlocked yes)
			(layer "F.Fab")
			(hide yes)
			(effects
				(font
					(size 1.016 1.016)
					(thickness 0.1524)
				)
			)
		)
		(duplicate_pad_numbers_are_jumpers no)
		(fp_line
			(start 0.635 0)
			(end -0.635 0)
			(stroke
				(width 0.508)
				(type default)
			)
			(layer "F.SilkS")
		)
		(fp_rect
			(start -0.9652 1.778)
			(end 0.9652 -1.778)
			(stroke
				(width 0)
				(type default)
			)
			(fill no)
			(layer "F.CrtYd")
		)
		(fp_poly
			(pts
				(xy -0.9652 -1.778) (xy 0.9652 -1.778) (xy 0.9652 1.778) (xy -0.9652 1.778)
			)
			(stroke
				(width 0)
				(type default)
			)
			(fill no)
			(layer "F.Fab")
		)
		(pad "1" smd rect
			(at 0 -0.9652 180)
			(size 1.397 1.143)
			(layers "F.Cu" "F.Mask" "F.Paste")
			(net "P12V_STBY_VIN_PU2")
		)
		(pad "2" smd rect
			(at 0 0.9652 180)
			(size 1.397 1.143)
			(layers "F.Cu" "F.Mask" "F.Paste")
			(net "GND")
		)
	)
	(footprint ""
		(layer "F.Cu")
		(at 8.636 -13.081 180)
		(property "Reference" "C31"
			(at 0 0 180)
			(layer "F.SilkS")
			(hide yes)
			(effects
				(font
					(size 1.27 1.27)
				)
			)
		)
		(property "Value" "SC1U16V3KX-5GP"
			(at 0 -2.8194 180)
			(unlocked yes)
			(layer "F.Fab")
			(hide yes)
			(effects
				(font
					(size 1.016 1.016)
					(thickness 0.1524)
				)
			)
		)
		(property "Device Type" "C603H36"
			(at 0 -4.3434 180)
			(unlocked yes)
			(layer "F.Fab")
			(hide yes)
			(effects
				(font
					(size 1.016 1.016)
					(thickness 0.1524)
				)
			)
		)
		(duplicate_pad_numbers_are_jumpers no)
		(fp_line
			(start 0.508 0)
			(end -0.508 0)
			(stroke
				(width 0.2032)
				(type default)
			)
			(layer "F.SilkS")
		)
		(fp_rect
			(start -0.5842 1.3335)
			(end 0.5842 -1.3335)
			(stroke
				(width 0)
				(type default)
			)
			(fill no)
			(layer "F.CrtYd")
		)
		(fp_rect
			(start -0.5842 1.3335)
			(end 0.5842 -1.3335)
			(stroke
				(width 0)
				(type default)
			)
			(fill no)
			(layer "F.Fab")
		)
		(pad "1" smd custom
			(at 0 -0.762 180)
			(size 0.2159 0.2159)
			(layers "F.Cu" "F.Mask" "F.Paste")
			(net "SYS_RST_BTN_IN_N")
			(options
				(clearance outline)
				(anchor circle)
			)
			(primitives
				(gr_poly
					(pts
						(arc
							(start -0.3302 -0.4318)
							(mid -0.402042 -0.402042)
							(end -0.4318 -0.3302)
						)
						(arc
							(start -0.4318 0.3302)
							(mid -0.402042 0.402042)
							(end -0.3302 0.4318)
						)
						(arc
							(start 0.3302 0.4318)
							(mid 0.402042 0.402042)
							(end 0.4318 0.3302)
						)
						(arc
							(start 0.4318 -0.3302)
							(mid 0.402042 -0.402042)
							(end 0.3302 -0.4318)
						)
					)
					(width 0)
					(fill yes)
				)
			)
		)
		(pad "2" smd custom
			(at 0 0.762 180)
			(size 0.2159 0.2159)
			(layers "F.Cu" "F.Mask" "F.Paste")
			(net "GND")
			(options
				(clearance outline)
				(anchor circle)
			)
			(primitives
				(gr_poly
					(pts
						(arc
							(start -0.3302 -0.4318)
							(mid -0.402042 -0.402042)
							(end -0.4318 -0.3302)
						)
						(arc
							(start -0.4318 0.3302)
							(mid -0.402042 0.402042)
							(end -0.3302 0.4318)
						)
						(arc
							(start 0.3302 0.4318)
							(mid 0.402042 0.402042)
							(end 0.4318 0.3302)
						)
						(arc
							(start 0.4318 -0.3302)
							(mid 0.402042 -0.402042)
							(end 0.3302 -0.4318)
						)
					)
					(width 0)
					(fill yes)
				)
			)
		)
	)
	(footprint ""
		(layer "F.Cu")
		(at 10.922 -13.081)
		(property "Reference" "D3"
			(at 0 0 0)
			(layer "F.SilkS")
			(hide yes)
			(effects
				(font
					(size 1.27 1.27)
				)
			)
		)
		(property "Value" "PESD5V0X1UAB-GP"
			(at 0 -4.690618 0)
			(unlocked yes)
			(layer "F.Fab")
			(hide yes)
			(effects
				(font
					(size 1.016 1.016)
					(thickness 0.1524)
				)
			)
		)
		(property "Device Type" "SOD523AKH26"
			(at 0 -6.214618 0)
			(unlocked yes)
			(layer "F.Fab")
			(hide yes)
			(effects
				(font
					(size 1.016 1.016)
					(thickness 0.1524)
				)
			)
		)
		(duplicate_pad_numbers_are_jumpers no)
		(fp_line
			(start -0.5334 -1.4478)
			(end 0.5334 -1.4478)
			(stroke
				(width 0.1524)
				(type default)
			)
			(layer "F.SilkS")
		)
		(fp_line
			(start -0.5334 1.524)
			(end -0.5334 -1.4478)
			(stroke
				(width 0.1524)
				(type default)
			)
			(layer "F.SilkS")
		)
		(fp_line
			(start 0.4064 1.651)
			(end -0.4064 1.651)
			(stroke
				(width 0.4064)
				(type default)
			)
			(layer "F.SilkS")
		)
		(fp_line
			(start 0.5334 -1.4478)
			(end 0.5334 1.524)
			(stroke
				(width 0.1524)
				(type default)
			)
			(layer "F.SilkS")
		)
		(fp_line
			(start 0.5334 1.524)
			(end -0.5334 1.524)
			(stroke
				(width 0.1524)
				(type default)
			)
			(layer "F.SilkS")
		)
		(fp_rect
			(start -0.6096 1.8542)
			(end 0.6096 -1.524)
			(stroke
				(width 0)
				(type default)
			)
			(fill no)
			(layer "F.CrtYd")
		)
		(fp_poly
			(pts
				(xy -0.6096 -1.524) (xy 0.6096 -1.524) (xy 0.6096 1.8542) (xy -0.6096 1.8542)
			)
			(stroke
				(width 0)
				(type default)
			)
			(fill no)
			(layer "F.Fab")
		)
		(pad "A" smd rect
			(at 0 -0.762)
			(size 0.5588 1.016)
			(layers "F.Cu" "F.Mask" "F.Paste")
			(net "GND")
		)
		(pad "K" smd rect
			(at 0 0.762)
			(size 0.5588 1.016)
			(layers "F.Cu" "F.Mask" "F.Paste")
			(net "SYS_RST_BTN_IN_N")
		)
	)
	(footprint ""
		(layer "F.Cu")
		(at 53.371242 -166.953184)
		(property "Reference" "R778"
			(at 0 0 0)
			(layer "F.SilkS")
			(hide yes)
			(effects
				(font
					(size 1.27 1.27)
				)
			)
		)
		(property "Value" "866R2F-GP"
			(at 0.064008 -3.993896 0)
			(unlocked yes)
			(layer "F.Fab")
			(hide yes)
			(effects
				(font
					(size 1.016 1.016)
					(thickness 0.1524)
				)
			)
		)
		(property "Device Type" "R402H16"
			(at 0.064008 -5.517896 0)
			(unlocked yes)
			(layer "F.Fab")
			(hide yes)
			(effects
				(font
					(size 1.016 1.016)
					(thickness 0.1524)
				)
			)
		)
		(duplicate_pad_numbers_are_jumpers no)
		(fp_line
			(start -0.508 -0.9398)
			(end -0.508 0.9398)
			(stroke
				(width 0.1524)
				(type default)
			)
			(layer "F.SilkS")
		)
		(fp_line
			(start 0.508 -0.9398)
			(end -0.508 -0.9398)
			(stroke
				(width 0.1524)
				(type default)
			)
			(layer "F.SilkS")
		)
		(fp_rect
			(start -0.508 0.9398)
			(end 0.508 -0.9398)
			(stroke
				(width 0)
				(type default)
			)
			(fill no)
			(layer "F.CrtYd")
		)
		(fp_rect
			(start -0.508 0.9398)
			(end 0.508 -0.9398)
			(stroke
				(width 0)
				(type default)
			)
			(fill no)
			(layer "F.Fab")
		)
		(pad "1" smd custom
			(at 0 -0.4445)
			(size 0.1397 0.1397)
			(layers "F.Cu" "F.Mask" "F.Paste")
			(net "P2V5_STBY")
			(options
				(clearance outline)
				(anchor circle)
			)
			(primitives
				(gr_poly
					(pts
						(arc
							(start -0.1778 -0.2794)
							(mid -0.249642 -0.249642)
							(end -0.2794 -0.1778)
						)
						(arc
							(start -0.2794 0.1778)
							(mid -0.249642 0.249642)
							(end -0.1778 0.2794)
						)
						(arc
							(start 0.1778 0.2794)
							(mid 0.249642 0.249642)
							(end 0.2794 0.1778)
						)
						(arc
							(start 0.2794 -0.1778)
							(mid 0.249642 -0.249642)
							(end 0.1778 -0.2794)
						)
					)
					(width 0)
					(fill yes)
				)
			)
		)
		(pad "2" smd custom
			(at 0 0.4445)
			(size 0.1397 0.1397)
			(layers "F.Cu" "F.Mask" "F.Paste")
			(net "ADC_P2V5_STBY")
			(options
				(clearance outline)
				(anchor circle)
			)
			(primitives
				(gr_poly
					(pts
						(arc
							(start -0.1778 -0.2794)
							(mid -0.249642 -0.249642)
							(end -0.2794 -0.1778)
						)
						(arc
							(start -0.2794 0.1778)
							(mid -0.249642 0.249642)
							(end -0.1778 0.2794)
						)
						(arc
							(start 0.1778 0.2794)
							(mid 0.249642 0.249642)
							(end 0.2794 0.1778)
						)
						(arc
							(start 0.2794 -0.1778)
							(mid 0.249642 -0.249642)
							(end 0.1778 -0.2794)
						)
					)
					(width 0)
					(fill yes)
				)
			)
		)
	)
	(footprint ""
		(layer "F.Cu")
		(at 153.925016 -11.421618 90)
		(property "Reference" "PU4"
			(at 0 0 90)
			(layer "F.SilkS")
			(hide yes)
			(effects
				(font
					(size 1.27 1.27)
				)
			)
		)
		(property "Value" "TPS53312RGTR-GP"
			(at 4.9784 -6.9342 90)
			(unlocked yes)
			(layer "F.Fab")
			(hide yes)
			(effects
				(font
					(size 1.016 1.016)
					(thickness 0.1524)
				)
			)
		)
		(property "Device Type" "QFN16G3-G1D7H40"
			(at 4.9784 -8.4582 90)
			(unlocked yes)
			(layer "F.Fab")
			(hide yes)
			(effects
				(font
					(size 1.016 1.016)
					(thickness 0.1524)
				)
			)
		)
		(duplicate_pad_numbers_are_jumpers no)
		(fp_line
			(start -1.2446 -2.5146)
			(end -2.5146 -2.5146)
			(stroke
				(width 0.1524)
				(type default)
			)
			(layer "F.SilkS")
		)
		(fp_line
			(start -2.5146 -2.5146)
			(end -2.5146 -1.2446)
			(stroke
				(width 0.1524)
				(type default)
			)
			(layer "F.SilkS")
		)
		(fp_line
			(start -2.262124 -0.750062)
			(end -2.770124 -0.750062)
			(stroke
				(width 0.1524)
				(type default)
			)
			(layer "F.SilkS")
		)
		(fp_line
			(start 2.262124 -0.249936)
			(end 2.770124 -0.249936)
			(stroke
				(width 0.1524)
				(type default)
			)
			(layer "F.SilkS")
		)
		(fp_line
			(start -2.5146 1.2446)
			(end -2.5146 2.5146)
			(stroke
				(width 0.1524)
				(type default)
			)
			(layer "F.SilkS")
		)
		(fp_line
			(start -0.249936 2.262124)
			(end -0.249936 3.024124)
			(stroke
				(width 0.1524)
				(type default)
			)
			(layer "F.SilkS")
		)
		(fp_line
			(start 2.5146 2.5146)
			(end 2.5146 1.2446)
			(stroke
				(width 0.1524)
				(type default)
			)
			(layer "F.SilkS")
		)
		(fp_line
			(start 1.2446 2.5146)
			(end 2.5146 2.5146)
			(stroke
				(width 0.1524)
				(type default)
			)
			(layer "F.SilkS")
		)
		(fp_line
			(start -2.5146 2.5146)
			(end -1.2446 2.5146)
			(stroke
				(width 0.1524)
				(type default)
			)
			(layer "F.SilkS")
		)
		(fp_poly
			(pts
				(xy 2.5146 -2.5146) (xy 1.2446 -2.5146) (xy 2.5146 -1.2446)
			)
			(stroke
				(width 0)
				(type default)
			)
			(fill yes)
			(layer "F.SilkS")
		)
		(fp_rect
			(start -1.4986 1.4986)
			(end 1.4986 -1.4986)
			(stroke
				(width 0)
				(type default)
			)
			(fill no)
			(layer "F.CrtYd")
		)
		(fp_poly
			(pts
				(xy 2.5146 -1.4986) (xy -1.4986 -1.4986) (xy -1.4986 1.4986) (xy 1.4986 1.4986) (xy 1.4986 -1.4859)
				(xy 2.5146 -1.4859) (xy 2.5146 2.5146) (xy -2.5146 2.5146) (xy -2.5146 -2.5146) (xy 2.5146 -2.5146)
			)
			(stroke
				(width 0)
				(type default)
			)
			(fill no)
			(layer "F.CrtYd")
		)
		(fp_rect
			(start -2.5146 2.5146)
			(end 2.5146 -2.5146)
			(stroke
				(width 0)
				(type default)
			)
			(fill no)
			(layer "F.Fab")
		)
		(pad "1" smd rect
			(at 0.750062 -1.550924 90)
			(size 0.3048 0.9144)
			(layers "F.Cu" "F.Mask" "F.Paste")
			(net "P1V8_STBY_VFB")
		)
		(pad "2" smd rect
			(at 0.249936 -1.538224 90)
			(size 0.3048 0.9398)
			(layers "F.Cu" "F.Mask" "F.Paste")
			(net "P1V8_STBY_VRG5")
		)
		(pad "3" smd rect
			(at -0.249936 -1.538224 90)
			(size 0.3048 0.9398)
			(layers "F.Cu" "F.Mask" "F.Paste")
			(net "P1V8_STBY_SS")
		)
		(pad "4" smd rect
			(at -0.750062 -1.550924 90)
			(size 0.3048 0.9144)
			(layers "F.Cu" "F.Mask" "F.Paste")
			(net "AGND_P1V8_STBY")
		)
		(pad "5" smd rect
			(at -1.550924 -0.750062 90)
			(size 0.9144 0.3048)
			(layers "F.Cu" "F.Mask" "F.Paste")
			(net "PWRGD_P1V8_STBY")
		)
		(pad "6" smd rect
			(at -1.538224 -0.249936 90)
			(size 0.9398 0.3048)
			(layers "F.Cu" "F.Mask" "F.Paste")
			(net "P1V8_STBY_EN_R")
		)
		(pad "7" smd rect
			(at -1.538224 0.249936 90)
			(size 0.9398 0.3048)
			(layers "F.Cu" "F.Mask" "F.Paste")
			(net "GND")
		)
		(pad "8" smd rect
			(at -1.550924 0.750062 90)
			(size 0.9144 0.3048)
			(layers "F.Cu" "F.Mask" "F.Paste")
			(net "GND")
		)
		(pad "9" smd rect
			(at -0.750062 1.550924 90)
			(size 0.3048 0.9144)
			(layers "F.Cu" "F.Mask" "F.Paste")
			(net "P1V8_STBY_SW")
		)
		(pad "10" smd rect
			(at -0.249936 1.538224 90)
			(size 0.3048 0.9398)
			(layers "F.Cu" "F.Mask" "F.Paste")
			(net "P1V8_STBY_SW")
		)
		(pad "11" smd rect
			(at 0.249936 1.538224 90)
			(size 0.3048 0.9398)
			(layers "F.Cu" "F.Mask" "F.Paste")
			(net "P1V8_STBY_SW")
		)
		(pad "12" smd rect
			(at 0.750062 1.550924 90)
			(size 0.3048 0.9144)
			(layers "F.Cu" "F.Mask" "F.Paste")
			(net "P1V8_STBY_VBST")
		)
		(pad "13" smd rect
			(at 1.550924 0.750062 90)
			(size 0.9144 0.3048)
			(layers "F.Cu" "F.Mask" "F.Paste")
			(net "P12V_STBY_VIN_PU4")
		)
		(pad "14" smd rect
			(at 1.538224 0.249936 90)
			(size 0.9398 0.3048)
			(layers "F.Cu" "F.Mask" "F.Paste")
			(net "P12V_STBY_VIN_PU4")
		)
		(pad "15" smd rect
			(at 1.538224 -0.249936 90)
			(size 0.9398 0.3048)
			(layers "F.Cu" "F.Mask" "F.Paste")
			(net "P12V_STBY_VCC_PU4")
		)
		(pad "16" smd rect
			(at 1.550924 -0.750062 90)
			(size 0.9144 0.3048)
			(layers "F.Cu" "F.Mask" "F.Paste")
			(net "P1V8_STBY_VO")
		)
		(pad "17" smd rect
			(at 0 0 90)
			(size 1.6764 1.6764)
			(layers "F.Cu" "F.Mask" "F.Paste")
			(net "GND")
		)
	)
	(footprint ""
		(layer "F.Cu")
		(at 23.88108 -186.560714 180)
		(property "Reference" "C171"
			(at 0 0 180)
			(layer "F.SilkS")
			(hide yes)
			(effects
				(font
					(size 1.27 1.27)
				)
			)
		)
		(property "Value" "SC10U16V5KX-7-GP-U"
			(at -0.0762 -6.1214 180)
			(unlocked yes)
			(layer "F.Fab")
			(hide yes)
			(effects
				(font
					(size 1.016 1.016)
					(thickness 0.1524)
				)
			)
		)
		(property "Device Type" "C805H58"
			(at -0.0762 -8.1534 180)
			(unlocked yes)
			(layer "F.Fab")
			(hide yes)
			(effects
				(font
					(size 1.016 1.016)
					(thickness 0.1524)
				)
			)
		)
		(duplicate_pad_numbers_are_jumpers no)
		(fp_line
			(start 0.635 0)
			(end -0.635 0)
			(stroke
				(width 0.508)
				(type default)
			)
			(layer "F.SilkS")
		)
		(fp_rect
			(start -0.9652 1.778)
			(end 0.9652 -1.778)
			(stroke
				(width 0)
				(type default)
			)
			(fill no)
			(layer "F.CrtYd")
		)
		(fp_poly
			(pts
				(xy -0.9652 -1.778) (xy 0.9652 -1.778) (xy 0.9652 1.778) (xy -0.9652 1.778)
			)
			(stroke
				(width 0)
				(type default)
			)
			(fill no)
			(layer "F.Fab")
		)
		(pad "1" smd rect
			(at 0 -0.9652 180)
			(size 1.397 1.143)
			(layers "F.Cu" "F.Mask" "F.Paste")
			(net "P12V_STBY_VIN_PU2")
		)
		(pad "2" smd rect
			(at 0 0.9652 180)
			(size 1.397 1.143)
			(layers "F.Cu" "F.Mask" "F.Paste")
			(net "GND")
		)
	)
	(footprint ""
		(layer "F.Cu")
		(at 92.548456 -161.52368 90)
		(property "Reference" "R27"
			(at 0 0 90)
			(layer "F.SilkS")
			(hide yes)
			(effects
				(font
					(size 1.27 1.27)
				)
			)
		)
		(property "Value" "1MR2F-GP"
			(at 0.064008 -3.993896 90)
			(unlocked yes)
			(layer "F.Fab")
			(hide yes)
			(effects
				(font
					(size 1.016 1.016)
					(thickness 0.1524)
				)
			)
		)
		(property "Device Type" "R402H16"
			(at 0.064008 -5.517896 90)
			(unlocked yes)
			(layer "F.Fab")
			(hide yes)
			(effects
				(font
					(size 1.016 1.016)
					(thickness 0.1524)
				)
			)
		)
		(duplicate_pad_numbers_are_jumpers no)
		(fp_line
			(start 0.508 -0.9398)
			(end -0.508 -0.9398)
			(stroke
				(width 0.1524)
				(type default)
			)
			(layer "F.SilkS")
		)
		(fp_line
			(start -0.508 -0.9398)
			(end -0.508 0.9398)
			(stroke
				(width 0.1524)
				(type default)
			)
			(layer "F.SilkS")
		)
		(fp_rect
			(start -0.508 0.9398)
			(end 0.508 -0.9398)
			(stroke
				(width 0)
				(type default)
			)
			(fill no)
			(layer "F.CrtYd")
		)
		(fp_rect
			(start -0.508 0.9398)
			(end 0.508 -0.9398)
			(stroke
				(width 0)
				(type default)
			)
			(fill no)
			(layer "F.Fab")
		)
		(pad "1" smd custom
			(at 0 -0.4445 90)
			(size 0.1397 0.1397)
			(layers "F.Cu" "F.Mask" "F.Paste")
			(net "USB_HUB_XTAL_IN")
			(options
				(clearance outline)
				(anchor circle)
			)
			(primitives
				(gr_poly
					(pts
						(arc
							(start -0.1778 -0.2794)
							(mid -0.249642 -0.249642)
							(end -0.2794 -0.1778)
						)
						(arc
							(start -0.2794 0.1778)
							(mid -0.249642 0.249642)
							(end -0.1778 0.2794)
						)
						(arc
							(start 0.1778 0.2794)
							(mid 0.249642 0.249642)
							(end 0.2794 0.1778)
						)
						(arc
							(start 0.2794 -0.1778)
							(mid 0.249642 -0.249642)
							(end 0.1778 -0.2794)
						)
					)
					(width 0)
					(fill yes)
				)
			)
		)
		(pad "2" smd custom
			(at 0 0.4445 90)
			(size 0.1397 0.1397)
			(layers "F.Cu" "F.Mask" "F.Paste")
			(net "USB_HUB_XTAL_OUT")
			(options
				(clearance outline)
				(anchor circle)
			)
			(primitives
				(gr_poly
					(pts
						(arc
							(start -0.1778 -0.2794)
							(mid -0.249642 -0.249642)
							(end -0.2794 -0.1778)
						)
						(arc
							(start -0.2794 0.1778)
							(mid -0.249642 0.249642)
							(end -0.1778 0.2794)
						)
						(arc
							(start 0.1778 0.2794)
							(mid 0.249642 0.249642)
							(end 0.2794 0.1778)
						)
						(arc
							(start 0.2794 -0.1778)
							(mid 0.249642 -0.249642)
							(end 0.1778 -0.2794)
						)
					)
					(width 0)
					(fill yes)
				)
			)
		)
	)
	(footprint ""
		(layer "F.Cu")
		(at 92.954094 -120.774714 90)
		(property "Reference" "R797"
			(at 0 0 90)
			(layer "F.SilkS")
			(hide yes)
			(effects
				(font
					(size 1.27 1.27)
				)
			)
		)
		(property "Value" "0R2J-2-GP"
			(at 0.064008 -3.993896 90)
			(unlocked yes)
			(layer "F.Fab")
			(hide yes)
			(effects
				(font
					(size 1.016 1.016)
					(thickness 0.1524)
				)
			)
		)
		(property "Device Type" "R402H16"
			(at 0.064008 -5.517896 90)
			(unlocked yes)
			(layer "F.Fab")
			(hide yes)
			(effects
				(font
					(size 1.016 1.016)
					(thickness 0.1524)
				)
			)
		)
		(duplicate_pad_numbers_are_jumpers no)
		(fp_line
			(start 0.508 -0.9398)
			(end -0.508 -0.9398)
			(stroke
				(width 0.1524)
				(type default)
			)
			(layer "F.SilkS")
		)
		(fp_line
			(start -0.508 -0.9398)
			(end -0.508 0.9398)
			(stroke
				(width 0.1524)
				(type default)
			)
			(layer "F.SilkS")
		)
		(fp_rect
			(start -0.508 0.9398)
			(end 0.508 -0.9398)
			(stroke
				(width 0)
				(type default)
			)
			(fill no)
			(layer "F.CrtYd")
		)
		(fp_rect
			(start -0.508 0.9398)
			(end 0.508 -0.9398)
			(stroke
				(width 0)
				(type default)
			)
			(fill no)
			(layer "F.Fab")
		)
		(pad "1" smd custom
			(at 0 -0.4445 90)
			(size 0.1397 0.1397)
			(layers "F.Cu" "F.Mask" "F.Paste")
			(net "UART_BMC_COMP_IN_RX")
			(options
				(clearance outline)
				(anchor circle)
			)
			(primitives
				(gr_poly
					(pts
						(arc
							(start -0.1778 -0.2794)
							(mid -0.249642 -0.249642)
							(end -0.2794 -0.1778)
						)
						(arc
							(start -0.2794 0.1778)
							(mid -0.249642 0.249642)
							(end -0.1778 0.2794)
						)
						(arc
							(start 0.1778 0.2794)
							(mid 0.249642 0.249642)
							(end 0.2794 0.1778)
						)
						(arc
							(start 0.2794 -0.1778)
							(mid 0.249642 -0.249642)
							(end 0.1778 -0.2794)
						)
					)
					(width 0)
					(fill yes)
				)
			)
		)
		(pad "2" smd custom
			(at 0 0.4445 90)
			(size 0.1397 0.1397)
			(layers "F.Cu" "F.Mask" "F.Paste")
			(net "UART_BMC_COMP_IN_RX_R")
			(options
				(clearance outline)
				(anchor circle)
			)
			(primitives
				(gr_poly
					(pts
						(arc
							(start -0.1778 -0.2794)
							(mid -0.249642 -0.249642)
							(end -0.2794 -0.1778)
						)
						(arc
							(start -0.2794 0.1778)
							(mid -0.249642 0.249642)
							(end -0.1778 0.2794)
						)
						(arc
							(start 0.1778 0.2794)
							(mid 0.249642 0.249642)
							(end 0.2794 0.1778)
						)
						(arc
							(start 0.2794 -0.1778)
							(mid 0.249642 -0.249642)
							(end 0.1778 -0.2794)
						)
					)
					(width 0)
					(fill yes)
				)
			)
		)
	)
	(footprint ""
		(layer "F.Cu")
		(at 30.506162 -155.909772 90)
		(property "Reference" "R331"
			(at 0 0 90)
			(layer "F.SilkS")
			(hide yes)
			(effects
				(font
					(size 1.27 1.27)
				)
			)
		)
		(property "Value" "4K7R2F-GP"
			(at 0.064008 -3.993896 90)
			(unlocked yes)
			(layer "F.Fab")
			(hide yes)
			(effects
				(font
					(size 1.016 1.016)
					(thickness 0.1524)
				)
			)
		)
		(property "Device Type" "R402H16"
			(at 0.064008 -5.517896 90)
			(unlocked yes)
			(layer "F.Fab")
			(hide yes)
			(effects
				(font
					(size 1.016 1.016)
					(thickness 0.1524)
				)
			)
		)
		(duplicate_pad_numbers_are_jumpers no)
		(fp_line
			(start 0.508 -0.9398)
			(end -0.508 -0.9398)
			(stroke
				(width 0.1524)
				(type default)
			)
			(layer "F.SilkS")
		)
		(fp_line
			(start -0.508 -0.9398)
			(end -0.508 0.9398)
			(stroke
				(width 0.1524)
				(type default)
			)
			(layer "F.SilkS")
		)
		(fp_rect
			(start -0.508 0.9398)
			(end 0.508 -0.9398)
			(stroke
				(width 0)
				(type default)
			)
			(fill no)
			(layer "F.CrtYd")
		)
		(fp_rect
			(start -0.508 0.9398)
			(end 0.508 -0.9398)
			(stroke
				(width 0)
				(type default)
			)
			(fill no)
			(layer "F.Fab")
		)
		(pad "1" smd custom
			(at 0 -0.4445 90)
			(size 0.1397 0.1397)
			(layers "F.Cu" "F.Mask" "F.Paste")
			(net "P3V3_STBY")
			(options
				(clearance outline)
				(anchor circle)
			)
			(primitives
				(gr_poly
					(pts
						(arc
							(start -0.1778 -0.2794)
							(mid -0.249642 -0.249642)
							(end -0.2794 -0.1778)
						)
						(arc
							(start -0.2794 0.1778)
							(mid -0.249642 0.249642)
							(end -0.1778 0.2794)
						)
						(arc
							(start 0.1778 0.2794)
							(mid 0.249642 0.249642)
							(end 0.2794 0.1778)
						)
						(arc
							(start 0.2794 -0.1778)
							(mid 0.249642 -0.249642)
							(end 0.1778 -0.2794)
						)
					)
					(width 0)
					(fill yes)
				)
			)
		)
		(pad "2" smd custom
			(at 0 0.4445 90)
			(size 0.1397 0.1397)
			(layers "F.Cu" "F.Mask" "F.Paste")
			(net "COMP_POWER_FAIL_N")
			(options
				(clearance outline)
				(anchor circle)
			)
			(primitives
				(gr_poly
					(pts
						(arc
							(start -0.1778 -0.2794)
							(mid -0.249642 -0.249642)
							(end -0.2794 -0.1778)
						)
						(arc
							(start -0.2794 0.1778)
							(mid -0.249642 0.249642)
							(end -0.1778 0.2794)
						)
						(arc
							(start 0.1778 0.2794)
							(mid 0.249642 0.249642)
							(end 0.2794 0.1778)
						)
						(arc
							(start 0.2794 -0.1778)
							(mid 0.249642 -0.249642)
							(end 0.1778 -0.2794)
						)
					)
					(width 0)
					(fill yes)
				)
			)
		)
	)
	(footprint ""
		(layer "F.Cu")
		(at 40.220646 -179.12461 180)
		(property "Reference" "R487"
			(at 0 0 180)
			(layer "F.SilkS")
			(hide yes)
			(effects
				(font
					(size 1.27 1.27)
				)
			)
		)
		(property "Value" "10KR2F-2-GP"
			(at 0.064008 -3.993896 180)
			(unlocked yes)
			(layer "F.Fab")
			(hide yes)
			(effects
				(font
					(size 1.016 1.016)
					(thickness 0.1524)
				)
			)
		)
		(property "Device Type" "R402H16"
			(at 0.064008 -5.517896 180)
			(unlocked yes)
			(layer "F.Fab")
			(hide yes)
			(effects
				(font
					(size 1.016 1.016)
					(thickness 0.1524)
				)
			)
		)
		(duplicate_pad_numbers_are_jumpers no)
		(fp_line
			(start 0.508 -0.9398)
			(end -0.508 -0.9398)
			(stroke
				(width 0.1524)
				(type default)
			)
			(layer "F.SilkS")
		)
		(fp_line
			(start -0.508 -0.9398)
			(end -0.508 0.9398)
			(stroke
				(width 0.1524)
				(type default)
			)
			(layer "F.SilkS")
		)
		(fp_rect
			(start -0.508 0.9398)
			(end 0.508 -0.9398)
			(stroke
				(width 0)
				(type default)
			)
			(fill no)
			(layer "F.CrtYd")
		)
		(fp_rect
			(start -0.508 0.9398)
			(end 0.508 -0.9398)
			(stroke
				(width 0)
				(type default)
			)
			(fill no)
			(layer "F.Fab")
		)
		(pad "1" smd custom
			(at 0 -0.4445 180)
			(size 0.1397 0.1397)
			(layers "F.Cu" "F.Mask" "F.Paste")
			(net "P3V3_STBY_VREG")
			(options
				(clearance outline)
				(anchor circle)
			)
			(primitives
				(gr_poly
					(pts
						(arc
							(start -0.1778 -0.2794)
							(mid -0.249642 -0.249642)
							(end -0.2794 -0.1778)
						)
						(arc
							(start -0.2794 0.1778)
							(mid -0.249642 0.249642)
							(end -0.1778 0.2794)
						)
						(arc
							(start 0.1778 0.2794)
							(mid 0.249642 0.249642)
							(end 0.2794 0.1778)
						)
						(arc
							(start 0.2794 -0.1778)
							(mid 0.249642 -0.249642)
							(end 0.1778 -0.2794)
						)
					)
					(width 0)
					(fill yes)
				)
			)
		)
		(pad "2" smd custom
			(at 0 0.4445 180)
			(size 0.1397 0.1397)
			(layers "F.Cu" "F.Mask" "F.Paste")
			(net "PWRGD_P3V3_STBY")
			(options
				(clearance outline)
				(anchor circle)
			)
			(primitives
				(gr_poly
					(pts
						(arc
							(start -0.1778 -0.2794)
							(mid -0.249642 -0.249642)
							(end -0.2794 -0.1778)
						)
						(arc
							(start -0.2794 0.1778)
							(mid -0.249642 0.249642)
							(end -0.1778 0.2794)
						)
						(arc
							(start 0.1778 0.2794)
							(mid 0.249642 0.249642)
							(end 0.2794 0.1778)
						)
						(arc
							(start 0.2794 -0.1778)
							(mid 0.249642 -0.249642)
							(end 0.1778 -0.2794)
						)
					)
					(width 0)
					(fill yes)
				)
			)
		)
	)
	(footprint ""
		(layer "F.Cu")
		(at 63.443358 -143.019272 90)
		(property "Reference" "R198"
			(at 0 0 90)
			(layer "F.SilkS")
			(hide yes)
			(effects
				(font
					(size 1.27 1.27)
				)
			)
		)
		(property "Value" "1KR2F-3-GP"
			(at 0.064008 -3.993896 90)
			(unlocked yes)
			(layer "F.Fab")
			(hide yes)
			(effects
				(font
					(size 1.016 1.016)
					(thickness 0.1524)
				)
			)
		)
		(property "Device Type" "R402H16"
			(at 0.064008 -5.517896 90)
			(unlocked yes)
			(layer "F.Fab")
			(hide yes)
			(effects
				(font
					(size 1.016 1.016)
					(thickness 0.1524)
				)
			)
		)
		(duplicate_pad_numbers_are_jumpers no)
		(fp_line
			(start 0.508 -0.9398)
			(end -0.508 -0.9398)
			(stroke
				(width 0.1524)
				(type default)
			)
			(layer "F.SilkS")
		)
		(fp_line
			(start -0.508 -0.9398)
			(end -0.508 0.9398)
			(stroke
				(width 0.1524)
				(type default)
			)
			(layer "F.SilkS")
		)
		(fp_rect
			(start -0.508 0.9398)
			(end 0.508 -0.9398)
			(stroke
				(width 0)
				(type default)
			)
			(fill no)
			(layer "F.CrtYd")
		)
		(fp_rect
			(start -0.508 0.9398)
			(end 0.508 -0.9398)
			(stroke
				(width 0)
				(type default)
			)
			(fill no)
			(layer "F.Fab")
		)
		(pad "1" smd custom
			(at 0 -0.4445 90)
			(size 0.1397 0.1397)
			(layers "F.Cu" "F.Mask" "F.Paste")
			(net "I2C_EXP_RMT_SCL_OUT")
			(options
				(clearance outline)
				(anchor circle)
			)
			(primitives
				(gr_poly
					(pts
						(arc
							(start -0.1778 -0.2794)
							(mid -0.249642 -0.249642)
							(end -0.2794 -0.1778)
						)
						(arc
							(start -0.2794 0.1778)
							(mid -0.249642 0.249642)
							(end -0.1778 0.2794)
						)
						(arc
							(start 0.1778 0.2794)
							(mid 0.249642 0.249642)
							(end 0.2794 0.1778)
						)
						(arc
							(start 0.2794 -0.1778)
							(mid 0.249642 -0.249642)
							(end 0.1778 -0.2794)
						)
					)
					(width 0)
					(fill yes)
				)
			)
		)
		(pad "2" smd custom
			(at 0 0.4445 90)
			(size 0.1397 0.1397)
			(layers "F.Cu" "F.Mask" "F.Paste")
			(net "P3V3_STBY")
			(options
				(clearance outline)
				(anchor circle)
			)
			(primitives
				(gr_poly
					(pts
						(arc
							(start -0.1778 -0.2794)
							(mid -0.249642 -0.249642)
							(end -0.2794 -0.1778)
						)
						(arc
							(start -0.2794 0.1778)
							(mid -0.249642 0.249642)
							(end -0.1778 0.2794)
						)
						(arc
							(start 0.1778 0.2794)
							(mid 0.249642 0.249642)
							(end 0.2794 0.1778)
						)
						(arc
							(start 0.2794 -0.1778)
							(mid 0.249642 -0.249642)
							(end 0.1778 -0.2794)
						)
					)
					(width 0)
					(fill yes)
				)
			)
		)
	)
	(footprint ""
		(layer "F.Cu")
		(at 215.80475 -45.587158 180)
		(property "Reference" "C162"
			(at 0 0 180)
			(layer "F.SilkS")
			(hide yes)
			(effects
				(font
					(size 1.27 1.27)
				)
			)
		)
		(property "Value" "SC1KP50V2KX-1GP"
			(at 1.1811 -2.7051 180)
			(unlocked yes)
			(layer "F.Fab")
			(hide yes)
			(effects
				(font
					(size 1.016 1.016)
					(thickness 0.1524)
				)
			)
		)
		(property "Device Type" "C402H22"
			(at 1.1811 -4.2291 180)
			(unlocked yes)
			(layer "F.Fab")
			(hide yes)
			(effects
				(font
					(size 1.016 1.016)
					(thickness 0.1524)
				)
			)
		)
		(duplicate_pad_numbers_are_jumpers no)
		(fp_rect
			(start -0.4318 0.9525)
			(end 0.4318 -0.9525)
			(stroke
				(width 0)
				(type default)
			)
			(fill no)
			(layer "F.CrtYd")
		)
		(fp_rect
			(start -0.4318 0.9525)
			(end 0.4318 -0.9525)
			(stroke
				(width 0)
				(type default)
			)
			(fill no)
			(layer "F.Fab")
		)
		(pad "1" smd custom
			(at 0 -0.4445 180)
			(size 0.1524 0.1524)
			(layers "F.Cu" "F.Mask" "F.Paste")
			(net "P5V_LL_R")
			(options
				(clearance outline)
				(anchor circle)
			)
			(primitives
				(gr_poly
					(pts
						(arc
							(start 0.3048 -0.2032)
							(mid 0.275042 -0.275042)
							(end 0.2032 -0.3048)
						)
						(arc
							(start -0.2032 -0.3048)
							(mid -0.275042 -0.275042)
							(end -0.3048 -0.2032)
						)
						(arc
							(start -0.3048 0.2032)
							(mid -0.275042 0.275042)
							(end -0.2032 0.3048)
						)
						(arc
							(start 0.2032 0.3048)
							(mid 0.275042 0.275042)
							(end 0.3048 0.2032)
						)
					)
					(width 0)
					(fill yes)
				)
			)
		)
		(pad "2" smd custom
			(at 0 0.4445 180)
			(size 0.1524 0.1524)
			(layers "F.Cu" "F.Mask" "F.Paste")
			(net "P5V_VFB")
			(options
				(clearance outline)
				(anchor circle)
			)
			(primitives
				(gr_poly
					(pts
						(arc
							(start 0.3048 -0.2032)
							(mid 0.275042 -0.275042)
							(end 0.2032 -0.3048)
						)
						(arc
							(start -0.2032 -0.3048)
							(mid -0.275042 -0.275042)
							(end -0.3048 -0.2032)
						)
						(arc
							(start -0.3048 0.2032)
							(mid -0.275042 0.275042)
							(end -0.2032 0.3048)
						)
						(arc
							(start 0.2032 0.3048)
							(mid 0.275042 0.275042)
							(end 0.3048 0.2032)
						)
					)
					(width 0)
					(fill yes)
				)
			)
		)
	)
	(footprint ""
		(layer "F.Cu")
		(at 77.283818 -86.954868 90)
		(property "Reference" "VIA6"
			(at 0 0 90)
			(layer "F.SilkS")
			(hide yes)
			(effects
				(font
					(size 1.27 1.27)
				)
			)
		)
		(property "Value" "85OHM-8L-1D6MM-L16L18-GP"
			(at 4.064 0.6096 90)
			(unlocked yes)
			(layer "F.Fab")
			(hide yes)
			(effects
				(font
					(size 1.016 1.016)
					(thickness 0.1524)
				)
			)
		)
		(property "Device Type" "VIA-PCIE-4P-368076"
			(at 4.064 -0.9144 90)
			(unlocked yes)
			(layer "F.Fab")
			(hide yes)
			(effects
				(font
					(size 1.016 1.016)
					(thickness 0.1524)
				)
			)
		)
		(duplicate_pad_numbers_are_jumpers no)
		(fp_rect
			(start -1.8415 0.381)
			(end 1.8415 -0.381)
			(stroke
				(width 0)
				(type default)
			)
			(fill no)
			(layer "F.CrtYd")
		)
		(fp_rect
			(start -1.8415 0.381)
			(end 1.8415 -0.381)
			(stroke
				(width 0)
				(type default)
			)
			(fill no)
			(layer "F.Fab")
		)
		(pad "1" thru_hole circle
			(at -1.4605 0 90)
			(size 0.508 0.508)
			(drill 0.254)
			(layers "*.Cu" "*.Mask")
			(remove_unused_layers no)
			(net "GND")
			(clearance 0.127)
			(thermal_gap 0.127)
		)
		(pad "2" thru_hole circle
			(at -0.4445 0 90)
			(size 0.508 0.508)
			(drill 0.254)
			(layers "*.Cu" "*.Mask")
			(remove_unused_layers no)
			(net "PCIE_COMP_TO_IOM_21_DP")
			(clearance 0.127)
			(thermal_gap 0.127)
		)
		(pad "3" thru_hole circle
			(at 0.4445 0 90)
			(size 0.508 0.508)
			(drill 0.254)
			(layers "*.Cu" "*.Mask")
			(remove_unused_layers no)
			(net "PCIE_COMP_TO_IOM_21_DN")
			(clearance 0.127)
			(thermal_gap 0.127)
		)
		(pad "4" thru_hole circle
			(at 1.4605 0 90)
			(size 0.508 0.508)
			(drill 0.254)
			(layers "*.Cu" "*.Mask")
			(remove_unused_layers no)
			(net "GND")
			(clearance 0.127)
			(thermal_gap 0.127)
		)
	)
	(footprint ""
		(layer "F.Cu")
		(at 19.880072 -15.68577)
		(property "Reference" "R48"
			(at 0 0 0)
			(layer "F.SilkS")
			(hide yes)
			(effects
				(font
					(size 1.27 1.27)
				)
			)
		)
		(property "Value" "4K7R2F-GP"
			(at 0.064008 -3.993896 0)
			(unlocked yes)
			(layer "F.Fab")
			(hide yes)
			(effects
				(font
					(size 1.016 1.016)
					(thickness 0.1524)
				)
			)
		)
		(property "Device Type" "R402H16"
			(at 0.064008 -5.517896 0)
			(unlocked yes)
			(layer "F.Fab")
			(hide yes)
			(effects
				(font
					(size 1.016 1.016)
					(thickness 0.1524)
				)
			)
		)
		(duplicate_pad_numbers_are_jumpers no)
		(fp_line
			(start -0.508 -0.9398)
			(end -0.508 0.9398)
			(stroke
				(width 0.1524)
				(type default)
			)
			(layer "F.SilkS")
		)
		(fp_line
			(start 0.508 -0.9398)
			(end -0.508 -0.9398)
			(stroke
				(width 0.1524)
				(type default)
			)
			(layer "F.SilkS")
		)
		(fp_rect
			(start -0.508 0.9398)
			(end 0.508 -0.9398)
			(stroke
				(width 0)
				(type default)
			)
			(fill no)
			(layer "F.CrtYd")
		)
		(fp_rect
			(start -0.508 0.9398)
			(end 0.508 -0.9398)
			(stroke
				(width 0)
				(type default)
			)
			(fill no)
			(layer "F.Fab")
		)
		(pad "1" smd custom
			(at 0 -0.4445)
			(size 0.1397 0.1397)
			(layers "F.Cu" "F.Mask" "F.Paste")
			(net "P3V3_STBY")
			(options
				(clearance outline)
				(anchor circle)
			)
			(primitives
				(gr_poly
					(pts
						(arc
							(start -0.1778 -0.2794)
							(mid -0.249642 -0.249642)
							(end -0.2794 -0.1778)
						)
						(arc
							(start -0.2794 0.1778)
							(mid -0.249642 0.249642)
							(end -0.1778 0.2794)
						)
						(arc
							(start 0.1778 0.2794)
							(mid 0.249642 0.249642)
							(end 0.2794 0.1778)
						)
						(arc
							(start 0.2794 -0.1778)
							(mid 0.249642 -0.249642)
							(end 0.1778 -0.2794)
						)
					)
					(width 0)
					(fill yes)
				)
			)
		)
		(pad "2" smd custom
			(at 0 0.4445)
			(size 0.1397 0.1397)
			(layers "F.Cu" "F.Mask" "F.Paste")
			(net "FP_PWR_BTN_N")
			(options
				(clearance outline)
				(anchor circle)
			)
			(primitives
				(gr_poly
					(pts
						(arc
							(start -0.1778 -0.2794)
							(mid -0.249642 -0.249642)
							(end -0.2794 -0.1778)
						)
						(arc
							(start -0.2794 0.1778)
							(mid -0.249642 0.249642)
							(end -0.1778 0.2794)
						)
						(arc
							(start 0.1778 0.2794)
							(mid 0.249642 0.249642)
							(end 0.2794 0.1778)
						)
						(arc
							(start 0.2794 -0.1778)
							(mid 0.249642 -0.249642)
							(end 0.1778 -0.2794)
						)
					)
					(width 0)
					(fill yes)
				)
			)
		)
	)
	(footprint ""
		(layer "F.Cu")
		(at 59.944 -162.7886)
		(property "Reference" "R407"
			(at 0 0 0)
			(layer "F.SilkS")
			(hide yes)
			(effects
				(font
					(size 1.27 1.27)
				)
			)
		)
		(property "Value" "1K4R2F-1-GP"
			(at 0.064008 -3.993896 0)
			(unlocked yes)
			(layer "F.Fab")
			(hide yes)
			(effects
				(font
					(size 1.016 1.016)
					(thickness 0.1524)
				)
			)
		)
		(property "Device Type" "R402H16"
			(at 0.064008 -5.517896 0)
			(unlocked yes)
			(layer "F.Fab")
			(hide yes)
			(effects
				(font
					(size 1.016 1.016)
					(thickness 0.1524)
				)
			)
		)
		(duplicate_pad_numbers_are_jumpers no)
		(fp_line
			(start -0.508 -0.9398)
			(end -0.508 0.9398)
			(stroke
				(width 0.1524)
				(type default)
			)
			(layer "F.SilkS")
		)
		(fp_line
			(start 0.508 -0.9398)
			(end -0.508 -0.9398)
			(stroke
				(width 0.1524)
				(type default)
			)
			(layer "F.SilkS")
		)
		(fp_rect
			(start -0.508 0.9398)
			(end 0.508 -0.9398)
			(stroke
				(width 0)
				(type default)
			)
			(fill no)
			(layer "F.CrtYd")
		)
		(fp_rect
			(start -0.508 0.9398)
			(end 0.508 -0.9398)
			(stroke
				(width 0)
				(type default)
			)
			(fill no)
			(layer "F.Fab")
		)
		(pad "1" smd custom
			(at 0 -0.4445)
			(size 0.1397 0.1397)
			(layers "F.Cu" "F.Mask" "F.Paste")
			(net "P3V3_STBY")
			(options
				(clearance outline)
				(anchor circle)
			)
			(primitives
				(gr_poly
					(pts
						(arc
							(start -0.1778 -0.2794)
							(mid -0.249642 -0.249642)
							(end -0.2794 -0.1778)
						)
						(arc
							(start -0.2794 0.1778)
							(mid -0.249642 0.249642)
							(end -0.1778 0.2794)
						)
						(arc
							(start 0.1778 0.2794)
							(mid 0.249642 0.249642)
							(end 0.2794 0.1778)
						)
						(arc
							(start 0.2794 -0.1778)
							(mid 0.249642 -0.249642)
							(end 0.1778 -0.2794)
						)
					)
					(width 0)
					(fill yes)
				)
			)
		)
		(pad "2" smd custom
			(at 0 0.4445)
			(size 0.1397 0.1397)
			(layers "F.Cu" "F.Mask" "F.Paste")
			(net "ADC_P3V3_STBY")
			(options
				(clearance outline)
				(anchor circle)
			)
			(primitives
				(gr_poly
					(pts
						(arc
							(start -0.1778 -0.2794)
							(mid -0.249642 -0.249642)
							(end -0.2794 -0.1778)
						)
						(arc
							(start -0.2794 0.1778)
							(mid -0.249642 0.249642)
							(end -0.1778 0.2794)
						)
						(arc
							(start 0.1778 0.2794)
							(mid 0.249642 0.249642)
							(end 0.2794 0.1778)
						)
						(arc
							(start 0.2794 -0.1778)
							(mid 0.249642 -0.249642)
							(end 0.1778 -0.2794)
						)
					)
					(width 0)
					(fill yes)
				)
			)
		)
	)
	(footprint ""
		(layer "F.Cu")
		(at 77.700124 -72.55002 -90)
		(property "Reference" "MEZZ1"
			(at 0 0 270)
			(layer "F.SilkS")
			(hide yes)
			(effects
				(font
					(size 1.27 1.27)
				)
			)
		)
		(property "Value" "FCI-CONN120-GP-U1"
			(at -28.2321 -1.7018 270)
			(unlocked yes)
			(layer "F.Fab")
			(hide yes)
			(effects
				(font
					(size 1.016 1.016)
					(thickness 0.1524)
				)
			)
		)
		(property "Device Type" "61082-121402LF-U1"
			(at -28.2321 -3.2258 270)
			(unlocked yes)
			(layer "F.Fab")
			(hide yes)
			(effects
				(font
					(size 1.016 1.016)
					(thickness 0.1524)
				)
			)
		)
		(duplicate_pad_numbers_are_jumpers no)
		(fp_line
			(start -27.1526 3.5052)
			(end 27.1526 3.5052)
			(stroke
				(width 0.1524)
				(type default)
			)
			(layer "F.SilkS")
		)
		(fp_line
			(start 27.1526 3.5052)
			(end 27.1526 -3.5052)
			(stroke
				(width 0.1524)
				(type default)
			)
			(layer "F.SilkS")
		)
		(fp_line
			(start -27.1526 -3.5052)
			(end -27.1526 3.5052)
			(stroke
				(width 0.1524)
				(type default)
			)
			(layer "F.SilkS")
		)
		(fp_line
			(start 27.1526 -3.5052)
			(end -27.1526 -3.5052)
			(stroke
				(width 0.1524)
				(type default)
			)
			(layer "F.SilkS")
		)
		(fp_line
			(start 23.34895 -3.5941)
			(end 23.85695 -3.5941)
			(stroke
				(width 0.3302)
				(type default)
			)
			(layer "F.SilkS")
		)
		(fp_poly
			(pts
				(xy 23.597108 -3.578098) (xy 24.105108 -4.086098) (xy 23.089108 -4.086098)
			)
			(stroke
				(width 0)
				(type default)
			)
			(fill yes)
			(layer "F.SilkS")
		)
		(fp_poly
			(pts
				(xy -23.853902 0.99314) (xy 23.853902 0.99314) (xy 23.853902 -0.99314) (xy -23.853902 -0.99314)
			)
			(stroke
				(width 0)
				(type default)
			)
			(fill yes)
			(layer "F.SilkS")
		)
		(fp_rect
			(start -26.8986 2.9972)
			(end 26.8986 -2.9972)
			(stroke
				(width 0)
				(type default)
			)
			(fill no)
			(layer "F.CrtYd")
		)
		(fp_poly
			(pts
				(xy 27.4066 -2.9972) (xy -26.8986 -2.9972) (xy -26.8986 2.9972) (xy 26.8986 2.9972) (xy 26.8986 -2.9845)
				(xy 27.4066 -2.9845) (xy 27.4066 3.7592) (xy -27.4066 3.7592) (xy -27.4066 -3.7592) (xy 27.4066 -3.7592)
			)
			(stroke
				(width 0)
				(type default)
			)
			(fill no)
			(layer "F.CrtYd")
		)
		(fp_rect
			(start -27.4066 3.7592)
			(end 27.4066 -3.7592)
			(stroke
				(width 0)
				(type default)
			)
			(fill no)
			(layer "F.Fab")
		)
		(pad "" np_thru_hole circle
			(at -26.100024 0 270)
			(size 0.254 0.254)
			(drill 0.8636)
			(layers "*.Cu" "*.Mask")
			(clearance 0.6604)
			(thermal_gap 0.6604)
		)
		(pad "" np_thru_hole circle
			(at 26.100024 0 270)
			(size 0.254 0.254)
			(drill 1.2192)
			(layers "*.Cu" "*.Mask")
			(clearance 0.8382)
			(thermal_gap 0.8382)
		)
		(pad "1" smd rect
			(at 23.599902 -2.22504 270)
			(size 0.508 2.0574)
			(layers "F.Cu" "F.Mask" "F.Paste")
			(net "MEZZA_PRSNT1_N")
		)
		(pad "2" smd rect
			(at 22.800056 -2.22504 270)
			(size 0.508 2.0574)
			(layers "F.Cu" "F.Mask" "F.Paste")
			(net "P5V_STBY")
		)
		(pad "3" smd rect
			(at 21.999956 -2.22504 270)
			(size 0.508 2.0574)
			(layers "F.Cu" "F.Mask" "F.Paste")
			(net "P5V_STBY")
		)
		(pad "4" smd rect
			(at 21.20011 -2.22504 270)
			(size 0.508 2.0574)
			(layers "F.Cu" "F.Mask" "F.Paste")
			(net "P5V_STBY")
		)
		(pad "5" smd rect
			(at 20.40001 -2.22504 270)
			(size 0.508 2.0574)
			(layers "F.Cu" "F.Mask" "F.Paste")
			(net "GND")
		)
		(pad "6" smd rect
			(at 19.59991 -2.22504 270)
			(size 0.508 2.0574)
			(layers "F.Cu" "F.Mask" "F.Paste")
			(net "GND")
		)
		(pad "7" smd rect
			(at 18.800064 -2.22504 270)
			(size 0.508 2.0574)
			(layers "F.Cu" "F.Mask" "F.Paste")
			(net "P3V3_STBY")
		)
		(pad "8" smd rect
			(at 17.999964 -2.22504 270)
			(size 0.508 2.0574)
			(layers "F.Cu" "F.Mask" "F.Paste")
			(net "GND")
		)
		(pad "9" smd rect
			(at 17.200118 -2.22504 270)
			(size 0.508 2.0574)
			(layers "F.Cu" "F.Mask" "F.Paste")
			(net "GND")
		)
		(pad "10" smd rect
			(at 16.400018 -2.22504 270)
			(size 0.508 2.0574)
			(layers "F.Cu" "F.Mask" "F.Paste")
			(net "P3V3")
		)
		(pad "11" smd rect
			(at 15.599918 -2.22504 270)
			(size 0.508 2.0574)
			(layers "F.Cu" "F.Mask" "F.Paste")
			(net "P3V3")
		)
		(pad "12" smd rect
			(at 14.800072 -2.22504 270)
			(size 0.508 2.0574)
			(layers "F.Cu" "F.Mask" "F.Paste")
			(net "P3V3")
		)
		(pad "13" smd rect
			(at 13.999972 -2.22504 270)
			(size 0.508 2.0574)
			(layers "F.Cu" "F.Mask" "F.Paste")
			(net "P3V3")
		)
		(pad "14" smd rect
			(at 13.200126 -2.22504 270)
			(size 0.508 2.0574)
			(layers "F.Cu" "F.Mask" "F.Paste")
			(net "NCSI_RCSDV_R")
		)
		(pad "15" smd rect
			(at 12.400026 -2.22504 270)
			(size 0.508 2.0574)
			(layers "F.Cu" "F.Mask" "F.Paste")
			(net "NCSI_RCLK")
		)
		(pad "16" smd rect
			(at 11.599926 -2.22504 270)
			(size 0.508 2.0574)
			(layers "F.Cu" "F.Mask" "F.Paste")
			(net "NCSI_TXEN_R")
		)
		(pad "17" smd rect
			(at 10.80008 -2.22504 270)
			(size 0.508 2.0574)
			(layers "F.Cu" "F.Mask" "F.Paste")
			(net "PCIE_COMP_TO_IOM_RST_4_R")
		)
		(pad "18" smd rect
			(at 9.99998 -2.22504 270)
			(size 0.508 2.0574)
			(layers "F.Cu" "F.Mask" "F.Paste")
			(net "I2C_MEZZ_OOB_SCL")
		)
		(pad "19" smd rect
			(at 9.19988 -2.22504 270)
			(size 0.508 2.0574)
			(layers "F.Cu" "F.Mask" "F.Paste")
			(net "I2C_MEZZ_OOB_SDA")
		)
		(pad "20" smd rect
			(at 8.400034 -2.22504 270)
			(size 0.508 2.0574)
			(layers "F.Cu" "F.Mask" "F.Paste")
			(net "GND")
		)
		(pad "21" smd rect
			(at 7.599934 -2.22504 270)
			(size 0.508 2.0574)
			(layers "F.Cu" "F.Mask" "F.Paste")
			(net "GND")
		)
		(pad "22" smd rect
			(at 6.800088 -2.22504 270)
			(size 0.508 2.0574)
			(layers "F.Cu" "F.Mask" "F.Paste")
			(net "NCSI_RXD0_R")
		)
		(pad "23" smd rect
			(at 5.999988 -2.22504 270)
			(size 0.508 2.0574)
			(layers "F.Cu" "F.Mask" "F.Paste")
			(net "NCSI_RXD1_R")
		)
		(pad "24" smd rect
			(at 5.199888 -2.22504 270)
			(size 0.508 2.0574)
			(layers "F.Cu" "F.Mask" "F.Paste")
			(net "GND")
		)
		(pad "25" smd rect
			(at 4.400042 -2.22504 270)
			(size 0.508 2.0574)
			(layers "F.Cu" "F.Mask" "F.Paste")
			(net "GND")
		)
		(pad "26" smd rect
			(at 3.599942 -2.22504 270)
			(size 0.508 2.0574)
			(layers "F.Cu" "F.Mask" "F.Paste")
			(net "Net_31")
		)
		(pad "27" smd rect
			(at 2.800096 -2.22504 270)
			(size 0.508 2.0574)
			(layers "F.Cu" "F.Mask" "F.Paste")
			(net "Net_30")
		)
		(pad "28" smd rect
			(at 1.999996 -2.22504 270)
			(size 0.508 2.0574)
			(layers "F.Cu" "F.Mask" "F.Paste")
			(net "GND")
		)
		(pad "29" smd rect
			(at 1.199896 -2.22504 270)
			(size 0.508 2.0574)
			(layers "F.Cu" "F.Mask" "F.Paste")
			(net "GND")
		)
		(pad "30" smd rect
			(at 0.40005 -2.22504 270)
			(size 0.508 2.0574)
			(layers "F.Cu" "F.Mask" "F.Paste")
			(net "PCIE_IOM_TO_COMP_16_DP")
		)
		(pad "31" smd rect
			(at -0.40005 -2.22504 270)
			(size 0.508 2.0574)
			(layers "F.Cu" "F.Mask" "F.Paste")
			(net "PCIE_IOM_TO_COMP_16_DN")
		)
		(pad "32" smd rect
			(at -1.199896 -2.22504 270)
			(size 0.508 2.0574)
			(layers "F.Cu" "F.Mask" "F.Paste")
			(net "GND")
		)
		(pad "33" smd rect
			(at -1.999996 -2.22504 270)
			(size 0.508 2.0574)
			(layers "F.Cu" "F.Mask" "F.Paste")
			(net "GND")
		)
		(pad "34" smd rect
			(at -2.800096 -2.22504 270)
			(size 0.508 2.0574)
			(layers "F.Cu" "F.Mask" "F.Paste")
			(net "PCIE_IOM_TO_COMP_17_DP")
		)
		(pad "35" smd rect
			(at -3.599942 -2.22504 270)
			(size 0.508 2.0574)
			(layers "F.Cu" "F.Mask" "F.Paste")
			(net "PCIE_IOM_TO_COMP_17_DN")
		)
		(pad "36" smd rect
			(at -4.400042 -2.22504 270)
			(size 0.508 2.0574)
			(layers "F.Cu" "F.Mask" "F.Paste")
			(net "GND")
		)
		(pad "37" smd rect
			(at -5.199888 -2.22504 270)
			(size 0.508 2.0574)
			(layers "F.Cu" "F.Mask" "F.Paste")
			(net "GND")
		)
		(pad "38" smd rect
			(at -5.999988 -2.22504 270)
			(size 0.508 2.0574)
			(layers "F.Cu" "F.Mask" "F.Paste")
			(net "PCIE_IOM_TO_COMP_18_DP")
		)
		(pad "39" smd rect
			(at -6.800088 -2.22504 270)
			(size 0.508 2.0574)
			(layers "F.Cu" "F.Mask" "F.Paste")
			(net "PCIE_IOM_TO_COMP_18_DN")
		)
		(pad "40" smd rect
			(at -7.599934 -2.22504 270)
			(size 0.508 2.0574)
			(layers "F.Cu" "F.Mask" "F.Paste")
			(net "GND")
		)
		(pad "41" smd rect
			(at -8.400034 -2.22504 270)
			(size 0.508 2.0574)
			(layers "F.Cu" "F.Mask" "F.Paste")
			(net "GND")
		)
		(pad "42" smd rect
			(at -9.19988 -2.22504 270)
			(size 0.508 2.0574)
			(layers "F.Cu" "F.Mask" "F.Paste")
			(net "PCIE_IOM_TO_COMP_19_DP")
		)
		(pad "43" smd rect
			(at -9.99998 -2.22504 270)
			(size 0.508 2.0574)
			(layers "F.Cu" "F.Mask" "F.Paste")
			(net "PCIE_IOM_TO_COMP_19_DN")
		)
		(pad "44" smd rect
			(at -10.80008 -2.22504 270)
			(size 0.508 2.0574)
			(layers "F.Cu" "F.Mask" "F.Paste")
			(net "GND")
		)
		(pad "45" smd rect
			(at -11.599926 -2.22504 270)
			(size 0.508 2.0574)
			(layers "F.Cu" "F.Mask" "F.Paste")
			(net "GND")
		)
		(pad "46" smd rect
			(at -12.400026 -2.22504 270)
			(size 0.508 2.0574)
			(layers "F.Cu" "F.Mask" "F.Paste")
			(net "PCIE_IOM_TO_COMP_20_DP")
		)
		(pad "47" smd rect
			(at -13.200126 -2.22504 270)
			(size 0.508 2.0574)
			(layers "F.Cu" "F.Mask" "F.Paste")
			(net "PCIE_IOM_TO_COMP_20_DN")
		)
		(pad "48" smd rect
			(at -13.999972 -2.22504 270)
			(size 0.508 2.0574)
			(layers "F.Cu" "F.Mask" "F.Paste")
			(net "GND")
		)
		(pad "49" smd rect
			(at -14.800072 -2.22504 270)
			(size 0.508 2.0574)
			(layers "F.Cu" "F.Mask" "F.Paste")
			(net "GND")
		)
		(pad "50" smd rect
			(at -15.599918 -2.22504 270)
			(size 0.508 2.0574)
			(layers "F.Cu" "F.Mask" "F.Paste")
			(net "PCIE_IOM_TO_COMP_21_DP")
		)
		(pad "51" smd rect
			(at -16.400018 -2.22504 270)
			(size 0.508 2.0574)
			(layers "F.Cu" "F.Mask" "F.Paste")
			(net "PCIE_IOM_TO_COMP_21_DN")
		)
		(pad "52" smd rect
			(at -17.200118 -2.22504 270)
			(size 0.508 2.0574)
			(layers "F.Cu" "F.Mask" "F.Paste")
			(net "GND")
		)
		(pad "53" smd rect
			(at -17.999964 -2.22504 270)
			(size 0.508 2.0574)
			(layers "F.Cu" "F.Mask" "F.Paste")
			(net "GND")
		)
		(pad "54" smd rect
			(at -18.800064 -2.22504 270)
			(size 0.508 2.0574)
			(layers "F.Cu" "F.Mask" "F.Paste")
			(net "PCIE_IOM_TO_COMP_22_DP")
		)
		(pad "55" smd rect
			(at -19.59991 -2.22504 270)
			(size 0.508 2.0574)
			(layers "F.Cu" "F.Mask" "F.Paste")
			(net "PCIE_IOM_TO_COMP_22_DN")
		)
		(pad "56" smd rect
			(at -20.40001 -2.22504 270)
			(size 0.508 2.0574)
			(layers "F.Cu" "F.Mask" "F.Paste")
			(net "GND")
		)
		(pad "57" smd rect
			(at -21.20011 -2.22504 270)
			(size 0.508 2.0574)
			(layers "F.Cu" "F.Mask" "F.Paste")
			(net "GND")
		)
		(pad "58" smd rect
			(at -21.999956 -2.22504 270)
			(size 0.508 2.0574)
			(layers "F.Cu" "F.Mask" "F.Paste")
			(net "PCIE_IOM_TO_COMP_23_DP")
		)
		(pad "59" smd rect
			(at -22.800056 -2.22504 270)
			(size 0.508 2.0574)
			(layers "F.Cu" "F.Mask" "F.Paste")
			(net "PCIE_IOM_TO_COMP_23_DN")
		)
		(pad "60" smd rect
			(at -23.599902 -2.22504 270)
			(size 0.508 2.0574)
			(layers "F.Cu" "F.Mask" "F.Paste")
			(net "GND")
		)
		(pad "61" smd rect
			(at 23.599902 2.22504 270)
			(size 0.508 2.0574)
			(layers "F.Cu" "F.Mask" "F.Paste")
			(net "P12V_STBY")
		)
		(pad "62" smd rect
			(at 22.800056 2.22504 270)
			(size 0.508 2.0574)
			(layers "F.Cu" "F.Mask" "F.Paste")
			(net "P12V_STBY")
		)
		(pad "63" smd rect
			(at 21.999956 2.22504 270)
			(size 0.508 2.0574)
			(layers "F.Cu" "F.Mask" "F.Paste")
			(net "P12V_STBY")
		)
		(pad "64" smd rect
			(at 21.20011 2.22504 270)
			(size 0.508 2.0574)
			(layers "F.Cu" "F.Mask" "F.Paste")
			(net "GND")
		)
		(pad "65" smd rect
			(at 20.40001 2.22504 270)
			(size 0.508 2.0574)
			(layers "F.Cu" "F.Mask" "F.Paste")
			(net "GND")
		)
		(pad "66" smd rect
			(at 19.59991 2.22504 270)
			(size 0.508 2.0574)
			(layers "F.Cu" "F.Mask" "F.Paste")
			(net "P3V3_STBY")
		)
		(pad "67" smd rect
			(at 18.800064 2.22504 270)
			(size 0.508 2.0574)
			(layers "F.Cu" "F.Mask" "F.Paste")
			(net "GND")
		)
		(pad "68" smd rect
			(at 17.999964 2.22504 270)
			(size 0.508 2.0574)
			(layers "F.Cu" "F.Mask" "F.Paste")
			(net "GND")
		)
		(pad "69" smd rect
			(at 17.200118 2.22504 270)
			(size 0.508 2.0574)
			(layers "F.Cu" "F.Mask" "F.Paste")
			(net "P3V3")
		)
		(pad "70" smd rect
			(at 16.400018 2.22504 270)
			(size 0.508 2.0574)
			(layers "F.Cu" "F.Mask" "F.Paste")
			(net "P3V3")
		)
		(pad "71" smd rect
			(at 15.599918 2.22504 270)
			(size 0.508 2.0574)
			(layers "F.Cu" "F.Mask" "F.Paste")
			(net "P3V3")
		)
		(pad "72" smd rect
			(at 14.800072 2.22504 270)
			(size 0.508 2.0574)
			(layers "F.Cu" "F.Mask" "F.Paste")
			(net "P3V3")
		)
		(pad "73" smd rect
			(at 13.999972 2.22504 270)
			(size 0.508 2.0574)
			(layers "F.Cu" "F.Mask" "F.Paste")
			(net "GND")
		)
		(pad "74" smd rect
			(at 13.200126 2.22504 270)
			(size 0.508 2.0574)
			(layers "F.Cu" "F.Mask" "F.Paste")
			(net "I2C_MEZZ_ALERT_R_N")
		)
		(pad "75" smd rect
			(at 12.400026 2.22504 270)
			(size 0.508 2.0574)
			(layers "F.Cu" "F.Mask" "F.Paste")
			(net "I2C_MEZZ_FRU_SENSOR_SCL")
		)
		(pad "76" smd rect
			(at 11.599926 2.22504 270)
			(size 0.508 2.0574)
			(layers "F.Cu" "F.Mask" "F.Paste")
			(net "I2C_MEZZ_FRU_SENSOR_SDA")
		)
		(pad "77" smd rect
			(at 10.80008 2.22504 270)
			(size 0.508 2.0574)
			(layers "F.Cu" "F.Mask" "F.Paste")
			(net "PCIE_WAKE_N")
		)
		(pad "78" smd rect
			(at 9.99998 2.22504 270)
			(size 0.508 2.0574)
			(layers "F.Cu" "F.Mask" "F.Paste")
			(net "NCSI_RX_ER_R")
		)
		(pad "79" smd rect
			(at 9.19988 2.22504 270)
			(size 0.508 2.0574)
			(layers "F.Cu" "F.Mask" "F.Paste")
			(net "GND")
		)
		(pad "80" smd rect
			(at 8.400034 2.22504 270)
			(size 0.508 2.0574)
			(layers "F.Cu" "F.Mask" "F.Paste")
			(net "NCSI_TXD0")
		)
		(pad "81" smd rect
			(at 7.599934 2.22504 270)
			(size 0.508 2.0574)
			(layers "F.Cu" "F.Mask" "F.Paste")
			(net "NCSI_TXD1")
		)
		(pad "82" smd rect
			(at 6.800088 2.22504 270)
			(size 0.508 2.0574)
			(layers "F.Cu" "F.Mask" "F.Paste")
			(net "GND")
		)
		(pad "83" smd rect
			(at 5.999988 2.22504 270)
			(size 0.508 2.0574)
			(layers "F.Cu" "F.Mask" "F.Paste")
			(net "GND")
		)
		(pad "84" smd rect
			(at 5.199888 2.22504 270)
			(size 0.508 2.0574)
			(layers "F.Cu" "F.Mask" "F.Paste")
			(net "PCIE_COMP_TO_IOM_CLK_4_DP")
		)
		(pad "85" smd rect
			(at 4.400042 2.22504 270)
			(size 0.508 2.0574)
			(layers "F.Cu" "F.Mask" "F.Paste")
			(net "PCIE_COMP_TO_IOM_CLK_4_DN")
		)
		(pad "86" smd rect
			(at 3.599942 2.22504 270)
			(size 0.508 2.0574)
			(layers "F.Cu" "F.Mask" "F.Paste")
			(net "GND")
		)
		(pad "87" smd rect
			(at 2.800096 2.22504 270)
			(size 0.508 2.0574)
			(layers "F.Cu" "F.Mask" "F.Paste")
			(net "GND")
		)
		(pad "88" smd rect
			(at 1.999996 2.22504 270)
			(size 0.508 2.0574)
			(layers "F.Cu" "F.Mask" "F.Paste")
			(net "PCIE_COMP_TO_IOM_16_DP")
		)
		(pad "89" smd rect
			(at 1.199896 2.22504 270)
			(size 0.508 2.0574)
			(layers "F.Cu" "F.Mask" "F.Paste")
			(net "PCIE_COMP_TO_IOM_16_DN")
		)
		(pad "90" smd rect
			(at 0.40005 2.22504 270)
			(size 0.508 2.0574)
			(layers "F.Cu" "F.Mask" "F.Paste")
			(net "GND")
		)
		(pad "91" smd rect
			(at -0.40005 2.22504 270)
			(size 0.508 2.0574)
			(layers "F.Cu" "F.Mask" "F.Paste")
			(net "GND")
		)
		(pad "92" smd rect
			(at -1.199896 2.22504 270)
			(size 0.508 2.0574)
			(layers "F.Cu" "F.Mask" "F.Paste")
			(net "PCIE_COMP_TO_IOM_17_DP")
		)
		(pad "93" smd rect
			(at -1.999996 2.22504 270)
			(size 0.508 2.0574)
			(layers "F.Cu" "F.Mask" "F.Paste")
			(net "PCIE_COMP_TO_IOM_17_DN")
		)
		(pad "94" smd rect
			(at -2.800096 2.22504 270)
			(size 0.508 2.0574)
			(layers "F.Cu" "F.Mask" "F.Paste")
			(net "GND")
		)
		(pad "95" smd rect
			(at -3.599942 2.22504 270)
			(size 0.508 2.0574)
			(layers "F.Cu" "F.Mask" "F.Paste")
			(net "GND")
		)
		(pad "96" smd rect
			(at -4.400042 2.22504 270)
			(size 0.508 2.0574)
			(layers "F.Cu" "F.Mask" "F.Paste")
			(net "PCIE_COMP_TO_IOM_18_DP")
		)
		(pad "97" smd rect
			(at -5.199888 2.22504 270)
			(size 0.508 2.0574)
			(layers "F.Cu" "F.Mask" "F.Paste")
			(net "PCIE_COMP_TO_IOM_18_DN")
		)
		(pad "98" smd rect
			(at -5.999988 2.22504 270)
			(size 0.508 2.0574)
			(layers "F.Cu" "F.Mask" "F.Paste")
			(net "GND")
		)
		(pad "99" smd rect
			(at -6.800088 2.22504 270)
			(size 0.508 2.0574)
			(layers "F.Cu" "F.Mask" "F.Paste")
			(net "GND")
		)
		(pad "100" smd rect
			(at -7.599934 2.22504 270)
			(size 0.508 2.0574)
			(layers "F.Cu" "F.Mask" "F.Paste")
			(net "PCIE_COMP_TO_IOM_19_DP")
		)
		(pad "101" smd rect
			(at -8.400034 2.22504 270)
			(size 0.508 2.0574)
			(layers "F.Cu" "F.Mask" "F.Paste")
			(net "PCIE_COMP_TO_IOM_19_DN")
		)
		(pad "102" smd rect
			(at -9.19988 2.22504 270)
			(size 0.508 2.0574)
			(layers "F.Cu" "F.Mask" "F.Paste")
			(net "GND")
		)
		(pad "103" smd rect
			(at -9.99998 2.22504 270)
			(size 0.508 2.0574)
			(layers "F.Cu" "F.Mask" "F.Paste")
			(net "GND")
		)
		(pad "104" smd rect
			(at -10.80008 2.22504 270)
			(size 0.508 2.0574)
			(layers "F.Cu" "F.Mask" "F.Paste")
			(net "PCIE_COMP_TO_IOM_20_DP")
		)
		(pad "105" smd rect
			(at -11.599926 2.22504 270)
			(size 0.508 2.0574)
			(layers "F.Cu" "F.Mask" "F.Paste")
			(net "PCIE_COMP_TO_IOM_20_DN")
		)
		(pad "106" smd rect
			(at -12.400026 2.22504 270)
			(size 0.508 2.0574)
			(layers "F.Cu" "F.Mask" "F.Paste")
			(net "GND")
		)
		(pad "107" smd rect
			(at -13.200126 2.22504 270)
			(size 0.508 2.0574)
			(layers "F.Cu" "F.Mask" "F.Paste")
			(net "GND")
		)
		(pad "108" smd rect
			(at -13.999972 2.22504 270)
			(size 0.508 2.0574)
			(layers "F.Cu" "F.Mask" "F.Paste")
			(net "PCIE_COMP_TO_IOM_21_DP")
		)
		(pad "109" smd rect
			(at -14.800072 2.22504 270)
			(size 0.508 2.0574)
			(layers "F.Cu" "F.Mask" "F.Paste")
			(net "PCIE_COMP_TO_IOM_21_DN")
		)
		(pad "110" smd rect
			(at -15.599918 2.22504 270)
			(size 0.508 2.0574)
			(layers "F.Cu" "F.Mask" "F.Paste")
			(net "GND")
		)
		(pad "111" smd rect
			(at -16.400018 2.22504 270)
			(size 0.508 2.0574)
			(layers "F.Cu" "F.Mask" "F.Paste")
			(net "GND")
		)
		(pad "112" smd rect
			(at -17.200118 2.22504 270)
			(size 0.508 2.0574)
			(layers "F.Cu" "F.Mask" "F.Paste")
			(net "PCIE_COMP_TO_IOM_22_DP")
		)
		(pad "113" smd rect
			(at -17.999964 2.22504 270)
			(size 0.508 2.0574)
			(layers "F.Cu" "F.Mask" "F.Paste")
			(net "PCIE_COMP_TO_IOM_22_DN")
		)
		(pad "114" smd rect
			(at -18.800064 2.22504 270)
			(size 0.508 2.0574)
			(layers "F.Cu" "F.Mask" "F.Paste")
			(net "GND")
		)
		(pad "115" smd rect
			(at -19.59991 2.22504 270)
			(size 0.508 2.0574)
			(layers "F.Cu" "F.Mask" "F.Paste")
			(net "GND")
		)
		(pad "116" smd rect
			(at -20.40001 2.22504 270)
			(size 0.508 2.0574)
			(layers "F.Cu" "F.Mask" "F.Paste")
			(net "PCIE_COMP_TO_IOM_23_DP")
		)
		(pad "117" smd rect
			(at -21.20011 2.22504 270)
			(size 0.508 2.0574)
			(layers "F.Cu" "F.Mask" "F.Paste")
			(net "PCIE_COMP_TO_IOM_23_DN")
		)
		(pad "118" smd rect
			(at -21.999956 2.22504 270)
			(size 0.508 2.0574)
			(layers "F.Cu" "F.Mask" "F.Paste")
			(net "GND")
		)
		(pad "119" smd rect
			(at -22.800056 2.22504 270)
			(size 0.508 2.0574)
			(layers "F.Cu" "F.Mask" "F.Paste")
			(net "GND")
		)
		(pad "120" smd rect
			(at -23.599902 2.22504 270)
			(size 0.508 2.0574)
			(layers "F.Cu" "F.Mask" "F.Paste")
			(net "MEZZ_A_PRSNT_120_N")
		)
		(zone
			(layer "F.Cu")
			(hatch none 0.5)
			(connect_pads
				(clearance 0)
			)
			(min_thickness 0.25)
			(keepout
				(tracks allowed)
				(vias not_allowed)
				(pads allowed)
				(copperpour not_allowed)
				(footprints allowed)
			)
			(placement
				(enabled no)
				(sheetname "")
			)
			(fill
				(thermal_gap 0.5)
				(thermal_bridge_width 0.5)
				(island_removal_mode 0)
			)
			(polygon
				(pts
					(xy 76.503784 -96.403922) (xy 76.503784 -48.696118) (xy 77.308964 -48.696118) (xy 77.308964 -96.403922)
				)
			)
		)
		(zone
			(layer "F.Cu")
			(hatch none 0.5)
			(connect_pads
				(clearance 0)
			)
			(min_thickness 0.25)
			(keepout
				(tracks allowed)
				(vias not_allowed)
				(pads allowed)
				(copperpour not_allowed)
				(footprints allowed)
			)
			(placement
				(enabled no)
				(sheetname "")
			)
			(fill
				(thermal_gap 0.5)
				(thermal_bridge_width 0.5)
				(island_removal_mode 0)
			)
			(polygon
				(pts
					(xy 78.091284 -96.403922) (xy 78.091284 -48.696118) (xy 78.896464 -48.696118) (xy 78.896464 -96.403922)
				)
			)
		)
		(zone
			(layers "F.Cu" "B.Cu" "In1.Cu" "In2.Cu" "In3.Cu" "In4.Cu" "In5.Cu" "In6.Cu")
			(hatch none 0.5)
			(connect_pads
				(clearance 0)
			)
			(min_thickness 0.25)
			(keepout
				(tracks not_allowed)
				(vias allowed)
				(pads allowed)
				(copperpour not_allowed)
				(footprints allowed)
			)
			(placement
				(enabled no)
				(sheetname "")
			)
			(fill
				(thermal_gap 0.5)
				(thermal_bridge_width 0.5)
				(island_removal_mode 0)
			)
			(polygon
				(pts
					(arc
						(start 78.436724 -98.650044)
						(mid 76.963524 -98.650044)
						(end 78.436724 -98.650044)
					)
				)
			)
		)
		(zone
			(layers "F.Cu" "B.Cu" "In1.Cu" "In2.Cu" "In3.Cu" "In4.Cu" "In5.Cu" "In6.Cu")
			(hatch none 0.5)
			(connect_pads
				(clearance 0)
			)
			(min_thickness 0.25)
			(keepout
				(tracks not_allowed)
				(vias allowed)
				(pads allowed)
				(copperpour not_allowed)
				(footprints allowed)
			)
			(placement
				(enabled no)
				(sheetname "")
			)
			(fill
				(thermal_gap 0.5)
				(thermal_bridge_width 0.5)
				(island_removal_mode 0)
			)
			(polygon
				(pts
					(arc
						(start 78.614524 -46.449996)
						(mid 76.785724 -46.449996)
						(end 78.614524 -46.449996)
					)
				)
			)
		)
	)
	(footprint ""
		(layer "F.Cu")
		(at 24.042116 -162.3441 90)
		(property "Reference" "C225"
			(at 0 0 90)
			(layer "F.SilkS")
			(hide yes)
			(effects
				(font
					(size 1.27 1.27)
				)
			)
		)
		(property "Value" "SC10U6D3V5KX-4GP"
			(at -0.0762 -6.1214 90)
			(unlocked yes)
			(layer "F.Fab")
			(hide yes)
			(effects
				(font
					(size 1.016 1.016)
					(thickness 0.1524)
				)
			)
		)
		(property "Device Type" "C805H58"
			(at -0.0762 -8.1534 90)
			(unlocked yes)
			(layer "F.Fab")
			(hide yes)
			(effects
				(font
					(size 1.016 1.016)
					(thickness 0.1524)
				)
			)
		)
		(duplicate_pad_numbers_are_jumpers no)
		(fp_line
			(start 0.635 0)
			(end -0.635 0)
			(stroke
				(width 0.508)
				(type default)
			)
			(layer "F.SilkS")
		)
		(fp_rect
			(start -0.9652 1.778)
			(end 0.9652 -1.778)
			(stroke
				(width 0)
				(type default)
			)
			(fill no)
			(layer "F.CrtYd")
		)
		(fp_poly
			(pts
				(xy -0.9652 -1.778) (xy 0.9652 -1.778) (xy 0.9652 1.778) (xy -0.9652 1.778)
			)
			(stroke
				(width 0)
				(type default)
			)
			(fill no)
			(layer "F.Fab")
		)
		(pad "1" smd rect
			(at 0 -0.9652 90)
			(size 1.397 1.143)
			(layers "F.Cu" "F.Mask" "F.Paste")
			(net "TPS74801_P1V2_STBY_OUT")
		)
		(pad "2" smd rect
			(at 0 0.9652 90)
			(size 1.397 1.143)
			(layers "F.Cu" "F.Mask" "F.Paste")
			(net "GND")
		)
	)
	(footprint ""
		(layer "F.Cu")
		(at 93.748352 -134.716774 -90)
		(property "Reference" "U26"
			(at 0 0 270)
			(layer "F.SilkS")
			(hide yes)
			(effects
				(font
					(size 1.27 1.27)
				)
			)
		)
		(property "Value" "24LC64-I-SN-GP"
			(at -3.707384 -1.5367 270)
			(unlocked yes)
			(layer "F.Fab")
			(hide yes)
			(effects
				(font
					(size 1.016 1.016)
					(thickness 0.1524)
				)
			)
		)
		(property "Device Type" "SOIC8H69"
			(at -3.707384 -3.0607 270)
			(unlocked yes)
			(layer "F.Fab")
			(hide yes)
			(effects
				(font
					(size 1.016 1.016)
					(thickness 0.1524)
				)
			)
		)
		(duplicate_pad_numbers_are_jumpers no)
		(fp_line
			(start -2.6289 3.4417)
			(end -2.6289 1.4732)
			(stroke
				(width 0.381)
				(type default)
			)
			(layer "F.SilkS")
		)
		(fp_line
			(start -2.7432 1.4224)
			(end -2.6416 1.4224)
			(stroke
				(width 0.1524)
				(type default)
			)
			(layer "F.SilkS")
		)
		(fp_line
			(start -2.7432 1.4224)
			(end 2.1336 1.4224)
			(stroke
				(width 0.1524)
				(type default)
			)
			(layer "F.SilkS")
		)
		(fp_line
			(start 2.1336 1.4224)
			(end 2.1336 -1.4224)
			(stroke
				(width 0.1524)
				(type default)
			)
			(layer "F.SilkS")
		)
		(fp_line
			(start -2.1844 -0.0508)
			(end -2.7178 0.508)
			(stroke
				(width 0.1524)
				(type default)
			)
			(layer "F.SilkS")
		)
		(fp_line
			(start -2.7178 -0.508)
			(end -2.1844 -0.0508)
			(stroke
				(width 0.1524)
				(type default)
			)
			(layer "F.SilkS")
		)
		(fp_line
			(start -2.7432 -1.4224)
			(end -2.7432 1.4224)
			(stroke
				(width 0.1524)
				(type default)
			)
			(layer "F.SilkS")
		)
		(fp_line
			(start 2.1336 -1.4224)
			(end -2.7432 -1.4224)
			(stroke
				(width 0.1524)
				(type default)
			)
			(layer "F.SilkS")
		)
		(fp_poly
			(pts
				(xy -2.2098 -1.4224) (xy -2.2098 1.4224) (xy 2.2098 1.4224) (xy 2.2098 -1.4224)
			)
			(stroke
				(width 0)
				(type default)
			)
			(fill yes)
			(layer "F.SilkS")
		)
		(fp_rect
			(start -2.450084 2.999994)
			(end 2.450084 -2.999994)
			(stroke
				(width 0)
				(type default)
			)
			(fill no)
			(layer "F.CrtYd")
		)
		(fp_poly
			(pts
				(xy -2.8194 3.6322) (xy -2.8194 -3.6322) (xy 2.8194 -3.6322) (xy 2.8194 1.18364) (xy 2.450084 1.18364)
				(xy 2.450084 -2.999994) (xy -2.450084 -2.999994) (xy -2.450084 2.999994) (xy 2.450084 2.999994)
				(xy 2.450084 1.18618) (xy 2.8194 1.18618) (xy 2.8194 3.6322)
			)
			(stroke
				(width 0)
				(type default)
			)
			(fill no)
			(layer "F.CrtYd")
		)
		(fp_rect
			(start -2.8194 3.6322)
			(end 2.8194 -3.6322)
			(stroke
				(width 0)
				(type default)
			)
			(fill no)
			(layer "F.Fab")
		)
		(pad "1" smd rect
			(at -1.905 2.54 270)
			(size 0.635 1.651)
			(layers "F.Cu" "F.Mask" "F.Paste")
			(net "EEPROM_A0")
		)
		(pad "2" smd rect
			(at -0.635 2.54 270)
			(size 0.635 1.651)
			(layers "F.Cu" "F.Mask" "F.Paste")
			(net "EEPROM_A1")
		)
		(pad "3" smd rect
			(at 0.635 2.54 270)
			(size 0.635 1.651)
			(layers "F.Cu" "F.Mask" "F.Paste")
			(net "EEPROM_A2")
		)
		(pad "4" smd rect
			(at 1.905 2.54 270)
			(size 0.635 1.651)
			(layers "F.Cu" "F.Mask" "F.Paste")
			(net "GND")
		)
		(pad "5" smd rect
			(at 1.905 -2.54 270)
			(size 0.635 1.651)
			(layers "F.Cu" "F.Mask" "F.Paste")
			(net "I2C_IOM_SDA")
		)
		(pad "6" smd rect
			(at 0.635 -2.54 270)
			(size 0.635 1.651)
			(layers "F.Cu" "F.Mask" "F.Paste")
			(net "I2C_IOM_SCL")
		)
		(pad "7" smd rect
			(at -0.635 -2.54 270)
			(size 0.635 1.651)
			(layers "F.Cu" "F.Mask" "F.Paste")
			(net "EEPROM_WP")
		)
		(pad "8" smd rect
			(at -1.905 -2.54 270)
			(size 0.635 1.651)
			(layers "F.Cu" "F.Mask" "F.Paste")
			(net "P3V3_STBY")
		)
	)
	(footprint ""
		(layer "F.Cu")
		(at 85.46973 -143.202152 -90)
		(property "Reference" "R132"
			(at 0 0 270)
			(layer "F.SilkS")
			(hide yes)
			(effects
				(font
					(size 1.27 1.27)
				)
			)
		)
		(property "Value" "0R2J-2-GP"
			(at 0.064008 -3.993896 270)
			(unlocked yes)
			(layer "F.Fab")
			(hide yes)
			(effects
				(font
					(size 1.016 1.016)
					(thickness 0.1524)
				)
			)
		)
		(property "Device Type" "R402H16"
			(at 0.064008 -5.517896 270)
			(unlocked yes)
			(layer "F.Fab")
			(hide yes)
			(effects
				(font
					(size 1.016 1.016)
					(thickness 0.1524)
				)
			)
		)
		(duplicate_pad_numbers_are_jumpers no)
		(fp_line
			(start -0.508 -0.9398)
			(end -0.508 0.9398)
			(stroke
				(width 0.1524)
				(type default)
			)
			(layer "F.SilkS")
		)
		(fp_line
			(start 0.508 -0.9398)
			(end -0.508 -0.9398)
			(stroke
				(width 0.1524)
				(type default)
			)
			(layer "F.SilkS")
		)
		(fp_rect
			(start -0.508 0.9398)
			(end 0.508 -0.9398)
			(stroke
				(width 0)
				(type default)
			)
			(fill no)
			(layer "F.CrtYd")
		)
		(fp_rect
			(start -0.508 0.9398)
			(end 0.508 -0.9398)
			(stroke
				(width 0)
				(type default)
			)
			(fill no)
			(layer "F.Fab")
		)
		(pad "1" smd custom
			(at 0 -0.4445 270)
			(size 0.1397 0.1397)
			(layers "F.Cu" "F.Mask" "F.Paste")
			(net "I2C_SCC_SDA")
			(options
				(clearance outline)
				(anchor circle)
			)
			(primitives
				(gr_poly
					(pts
						(arc
							(start -0.1778 -0.2794)
							(mid -0.249642 -0.249642)
							(end -0.2794 -0.1778)
						)
						(arc
							(start -0.2794 0.1778)
							(mid -0.249642 0.249642)
							(end -0.1778 0.2794)
						)
						(arc
							(start 0.1778 0.2794)
							(mid 0.249642 0.249642)
							(end 0.2794 0.1778)
						)
						(arc
							(start 0.2794 -0.1778)
							(mid 0.249642 -0.249642)
							(end 0.1778 -0.2794)
						)
					)
					(width 0)
					(fill yes)
				)
			)
		)
		(pad "2" smd custom
			(at 0 0.4445 270)
			(size 0.1397 0.1397)
			(layers "F.Cu" "F.Mask" "F.Paste")
			(net "I2C_SCC_SDA_R")
			(options
				(clearance outline)
				(anchor circle)
			)
			(primitives
				(gr_poly
					(pts
						(arc
							(start -0.1778 -0.2794)
							(mid -0.249642 -0.249642)
							(end -0.2794 -0.1778)
						)
						(arc
							(start -0.2794 0.1778)
							(mid -0.249642 0.249642)
							(end -0.1778 0.2794)
						)
						(arc
							(start 0.1778 0.2794)
							(mid 0.249642 0.249642)
							(end 0.2794 0.1778)
						)
						(arc
							(start 0.2794 -0.1778)
							(mid 0.249642 -0.249642)
							(end 0.1778 -0.2794)
						)
					)
					(width 0)
					(fill yes)
				)
			)
		)
	)
	(footprint ""
		(layer "F.Cu")
		(at 35.58286 -157.740858)
		(property "Reference" "TP57"
			(at 0 0 0)
			(layer "F.SilkS")
			(hide yes)
			(effects
				(font
					(size 1.27 1.27)
				)
			)
		)
		(property "Value" "TPAD28-2-GP"
			(at -0.0127 -1.6637 0)
			(unlocked yes)
			(layer "F.Fab")
			(hide yes)
			(effects
				(font
					(size 1.016 1.016)
					(thickness 0.1524)
				)
			)
		)
		(property "Device Type" "TPAD28"
			(at -0.0127 -3.1877 0)
			(unlocked yes)
			(layer "F.Fab")
			(hide yes)
			(effects
				(font
					(size 1.016 1.016)
					(thickness 0.1524)
				)
			)
		)
		(duplicate_pad_numbers_are_jumpers no)
		(fp_poly
			(pts
				(arc
					(start 0.3556 0)
					(mid -0.3556 0)
					(end 0.3556 0)
				)
			)
			(stroke
				(width 0)
				(type default)
			)
			(fill no)
			(layer "F.CrtYd")
		)
		(fp_poly
			(pts
				(arc
					(start 0.6096 0)
					(mid -0.6096 0)
					(end 0.6096 0)
				)
			)
			(stroke
				(width 0)
				(type default)
			)
			(fill no)
			(layer "F.Fab")
		)
		(pad "1" smd circle
			(at 0 0)
			(size 0.7112 0.7112)
			(layers "F.Cu" "F.Mask" "F.Paste")
			(net "TP_BMC_GPION5")
		)
	)
	(footprint ""
		(layer "F.Cu")
		(at 74.442828 -175.754538 90)
		(property "Reference" "R506"
			(at 0 0 90)
			(layer "F.SilkS")
			(hide yes)
			(effects
				(font
					(size 1.27 1.27)
				)
			)
		)
		(property "Value" "1K69R2F-2-GP"
			(at 0.064008 -3.993896 90)
			(unlocked yes)
			(layer "F.Fab")
			(hide yes)
			(effects
				(font
					(size 1.016 1.016)
					(thickness 0.1524)
				)
			)
		)
		(property "Device Type" "R402H16"
			(at 0.064008 -5.517896 90)
			(unlocked yes)
			(layer "F.Fab")
			(hide yes)
			(effects
				(font
					(size 1.016 1.016)
					(thickness 0.1524)
				)
			)
		)
		(duplicate_pad_numbers_are_jumpers no)
		(fp_line
			(start 0.508 -0.9398)
			(end -0.508 -0.9398)
			(stroke
				(width 0.1524)
				(type default)
			)
			(layer "F.SilkS")
		)
		(fp_line
			(start -0.508 -0.9398)
			(end -0.508 0.9398)
			(stroke
				(width 0.1524)
				(type default)
			)
			(layer "F.SilkS")
		)
		(fp_rect
			(start -0.508 0.9398)
			(end 0.508 -0.9398)
			(stroke
				(width 0)
				(type default)
			)
			(fill no)
			(layer "F.CrtYd")
		)
		(fp_rect
			(start -0.508 0.9398)
			(end 0.508 -0.9398)
			(stroke
				(width 0)
				(type default)
			)
			(fill no)
			(layer "F.Fab")
		)
		(pad "1" smd custom
			(at 0 -0.4445 90)
			(size 0.1397 0.1397)
			(layers "F.Cu" "F.Mask" "F.Paste")
			(net "TPS74801_P2V5_STBY_FB")
			(options
				(clearance outline)
				(anchor circle)
			)
			(primitives
				(gr_poly
					(pts
						(arc
							(start -0.1778 -0.2794)
							(mid -0.249642 -0.249642)
							(end -0.2794 -0.1778)
						)
						(arc
							(start -0.2794 0.1778)
							(mid -0.249642 0.249642)
							(end -0.1778 0.2794)
						)
						(arc
							(start 0.1778 0.2794)
							(mid 0.249642 0.249642)
							(end 0.2794 0.1778)
						)
						(arc
							(start 0.2794 -0.1778)
							(mid 0.249642 -0.249642)
							(end 0.1778 -0.2794)
						)
					)
					(width 0)
					(fill yes)
				)
			)
		)
		(pad "2" smd custom
			(at 0 0.4445 90)
			(size 0.1397 0.1397)
			(layers "F.Cu" "F.Mask" "F.Paste")
			(net "GND")
			(options
				(clearance outline)
				(anchor circle)
			)
			(primitives
				(gr_poly
					(pts
						(arc
							(start -0.1778 -0.2794)
							(mid -0.249642 -0.249642)
							(end -0.2794 -0.1778)
						)
						(arc
							(start -0.2794 0.1778)
							(mid -0.249642 0.249642)
							(end -0.1778 0.2794)
						)
						(arc
							(start 0.1778 0.2794)
							(mid 0.249642 0.249642)
							(end 0.2794 0.1778)
						)
						(arc
							(start 0.2794 -0.1778)
							(mid 0.249642 -0.249642)
							(end 0.1778 -0.2794)
						)
					)
					(width 0)
					(fill yes)
				)
			)
		)
	)
	(footprint ""
		(layer "F.Cu")
		(at 47.491904 -161.231072 180)
		(property "Reference" "R204"
			(at 0 0 180)
			(layer "F.SilkS")
			(hide yes)
			(effects
				(font
					(size 1.27 1.27)
				)
			)
		)
		(property "Value" "2K2R2F-GP"
			(at 0.064008 -3.993896 180)
			(unlocked yes)
			(layer "F.Fab")
			(hide yes)
			(effects
				(font
					(size 1.016 1.016)
					(thickness 0.1524)
				)
			)
		)
		(property "Device Type" "R402H16"
			(at 0.064008 -5.517896 180)
			(unlocked yes)
			(layer "F.Fab")
			(hide yes)
			(effects
				(font
					(size 1.016 1.016)
					(thickness 0.1524)
				)
			)
		)
		(duplicate_pad_numbers_are_jumpers no)
		(fp_line
			(start 0.508 -0.9398)
			(end -0.508 -0.9398)
			(stroke
				(width 0.1524)
				(type default)
			)
			(layer "F.SilkS")
		)
		(fp_line
			(start -0.508 -0.9398)
			(end -0.508 0.9398)
			(stroke
				(width 0.1524)
				(type default)
			)
			(layer "F.SilkS")
		)
		(fp_rect
			(start -0.508 0.9398)
			(end 0.508 -0.9398)
			(stroke
				(width 0)
				(type default)
			)
			(fill no)
			(layer "F.CrtYd")
		)
		(fp_rect
			(start -0.508 0.9398)
			(end 0.508 -0.9398)
			(stroke
				(width 0)
				(type default)
			)
			(fill no)
			(layer "F.Fab")
		)
		(pad "1" smd custom
			(at 0 -0.4445 180)
			(size 0.1397 0.1397)
			(layers "F.Cu" "F.Mask" "F.Paste")
			(net "I2C_DPB_MISC_SDA_OUT")
			(options
				(clearance outline)
				(anchor circle)
			)
			(primitives
				(gr_poly
					(pts
						(arc
							(start -0.1778 -0.2794)
							(mid -0.249642 -0.249642)
							(end -0.2794 -0.1778)
						)
						(arc
							(start -0.2794 0.1778)
							(mid -0.249642 0.249642)
							(end -0.1778 0.2794)
						)
						(arc
							(start 0.1778 0.2794)
							(mid 0.249642 0.249642)
							(end 0.2794 0.1778)
						)
						(arc
							(start 0.2794 -0.1778)
							(mid 0.249642 -0.249642)
							(end 0.1778 -0.2794)
						)
					)
					(width 0)
					(fill yes)
				)
			)
		)
		(pad "2" smd custom
			(at 0 0.4445 180)
			(size 0.1397 0.1397)
			(layers "F.Cu" "F.Mask" "F.Paste")
			(net "P3V3_STBY")
			(options
				(clearance outline)
				(anchor circle)
			)
			(primitives
				(gr_poly
					(pts
						(arc
							(start -0.1778 -0.2794)
							(mid -0.249642 -0.249642)
							(end -0.2794 -0.1778)
						)
						(arc
							(start -0.2794 0.1778)
							(mid -0.249642 0.249642)
							(end -0.1778 0.2794)
						)
						(arc
							(start 0.1778 0.2794)
							(mid 0.249642 0.249642)
							(end 0.2794 0.1778)
						)
						(arc
							(start 0.2794 -0.1778)
							(mid 0.249642 -0.249642)
							(end 0.1778 -0.2794)
						)
					)
					(width 0)
					(fill yes)
				)
			)
		)
	)
	(footprint ""
		(layer "F.Cu")
		(at 93.3958 -37.8206 180)
		(property "Reference" "C246"
			(at 0 0 180)
			(layer "F.SilkS")
			(hide yes)
			(effects
				(font
					(size 1.27 1.27)
				)
			)
		)
		(property "Value" "ST150U16VDM-3-GP"
			(at 0 -9.6012 180)
			(unlocked yes)
			(layer "F.Fab")
			(hide yes)
			(effects
				(font
					(size 1.016 1.016)
					(thickness 0.1524)
				)
			)
		)
		(property "Device Type" "CT7343H119"
			(at 0 -11.1252 180)
			(unlocked yes)
			(layer "F.Fab")
			(hide yes)
			(effects
				(font
					(size 1.016 1.016)
					(thickness 0.1524)
				)
			)
		)
		(duplicate_pad_numbers_are_jumpers no)
		(fp_line
			(start 2.286 4.8768)
			(end -2.286 4.8768)
			(stroke
				(width 0.1524)
				(type default)
			)
			(layer "F.SilkS")
		)
		(fp_line
			(start 2.286 2.032)
			(end 2.286 4.8768)
			(stroke
				(width 0.1524)
				(type default)
			)
			(layer "F.SilkS")
		)
		(fp_line
			(start 2.286 -2.032)
			(end 2.286 -4.8768)
			(stroke
				(width 0.1524)
				(type default)
			)
			(layer "F.SilkS")
		)
		(fp_line
			(start 2.286 -4.8768)
			(end -2.286 -4.8768)
			(stroke
				(width 0.1524)
				(type default)
			)
			(layer "F.SilkS")
		)
		(fp_line
			(start 2.1082 -4.699)
			(end -2.1082 -4.699)
			(stroke
				(width 0.508)
				(type default)
			)
			(layer "F.SilkS")
		)
		(fp_line
			(start -2.286 4.8768)
			(end -2.286 2.032)
			(stroke
				(width 0.1524)
				(type default)
			)
			(layer "F.SilkS")
		)
		(fp_line
			(start -2.286 -4.8768)
			(end -2.286 -2.032)
			(stroke
				(width 0.1524)
				(type default)
			)
			(layer "F.SilkS")
		)
		(fp_rect
			(start -2.1463 3.6449)
			(end 2.1463 -3.6449)
			(stroke
				(width 0)
				(type default)
			)
			(fill no)
			(layer "F.CrtYd")
		)
		(fp_poly
			(pts
				(xy -2.54 4.953) (xy -2.54 4.2926) (xy -3.81 4.2926) (xy -3.81 -4.2926) (xy -2.54 -4.2926) (xy -2.54 -4.953)
				(xy 2.54 -4.953) (xy 2.54 -4.2926) (xy 3.81 -4.2926) (xy 3.81 -1.6256) (xy 2.1463 -1.6256) (xy 2.1463 -3.6449)
				(xy -2.1463 -3.6449) (xy -2.1463 3.6449) (xy 2.1463 3.6449) (xy 2.1463 -1.6129) (xy 3.81 -1.6129)
				(xy 3.81 4.2926) (xy 2.54 4.2926) (xy 2.54 4.953)
			)
			(stroke
				(width 0)
				(type default)
			)
			(fill no)
			(layer "F.CrtYd")
		)
		(fp_rect
			(start 2.54 4.2926)
			(end 3.81 -4.2926)
			(stroke
				(width 0)
				(type default)
			)
			(fill no)
			(layer "F.Fab")
		)
		(fp_rect
			(start -2.54 4.953)
			(end 2.54 -4.953)
			(stroke
				(width 0)
				(type default)
			)
			(fill no)
			(layer "F.Fab")
		)
		(fp_rect
			(start -3.81 4.2926)
			(end -2.54 -4.2926)
			(stroke
				(width 0)
				(type default)
			)
			(fill no)
			(layer "F.Fab")
		)
		(pad "1" smd rect
			(at 0 -3.1496 180)
			(size 2.413 2.286)
			(layers "F.Cu" "F.Mask" "F.Paste")
			(net "P5V_USB")
		)
		(pad "2" smd rect
			(at 0 3.1496 180)
			(size 2.413 2.286)
			(layers "F.Cu" "F.Mask" "F.Paste")
			(net "GND")
		)
		(zone
			(layer "F.Cu")
			(hatch none 0.5)
			(connect_pads
				(clearance 0)
			)
			(min_thickness 0.25)
			(keepout
				(tracks allowed)
				(vias not_allowed)
				(pads allowed)
				(copperpour not_allowed)
				(footprints allowed)
			)
			(placement
				(enabled no)
				(sheetname "")
			)
			(fill
				(thermal_gap 0.5)
				(thermal_bridge_width 0.5)
				(island_removal_mode 0)
			)
			(polygon
				(pts
					(xy 91.8845 -36.1315) (xy 91.8845 -33.2232) (xy 94.9071 -33.2232) (xy 94.9071 -36.1188) (xy 94.9071 -36.449)
					(xy 91.8845 -36.449)
				)
			)
		)
		(zone
			(layer "F.Cu")
			(hatch none 0.5)
			(connect_pads
				(clearance 0)
			)
			(min_thickness 0.25)
			(keepout
				(tracks allowed)
				(vias not_allowed)
				(pads allowed)
				(copperpour not_allowed)
				(footprints allowed)
			)
			(placement
				(enabled no)
				(sheetname "")
			)
			(fill
				(thermal_gap 0.5)
				(thermal_bridge_width 0.5)
				(island_removal_mode 0)
			)
			(polygon
				(pts
					(xy 94.9071 -42.418) (xy 91.8845 -42.418) (xy 91.8845 -39.5224) (xy 91.8845 -39.1922) (xy 94.9071 -39.1922)
					(xy 94.9071 -39.5224)
				)
			)
		)
	)
	(footprint ""
		(layer "F.Cu")
		(at 128.112774 -6.400546)
		(property "Reference" "C146"
			(at 0 0 0)
			(layer "F.SilkS")
			(hide yes)
			(effects
				(font
					(size 1.27 1.27)
				)
			)
		)
		(property "Value" "SCD033U50V3KX-1GP"
			(at 0 -2.8194 0)
			(unlocked yes)
			(layer "F.Fab")
			(hide yes)
			(effects
				(font
					(size 1.016 1.016)
					(thickness 0.1524)
				)
			)
		)
		(property "Device Type" "C603H36"
			(at 0 -4.3434 0)
			(unlocked yes)
			(layer "F.Fab")
			(hide yes)
			(effects
				(font
					(size 1.016 1.016)
					(thickness 0.1524)
				)
			)
		)
		(duplicate_pad_numbers_are_jumpers no)
		(fp_line
			(start 0.508 0)
			(end -0.508 0)
			(stroke
				(width 0.2032)
				(type default)
			)
			(layer "F.SilkS")
		)
		(fp_rect
			(start -0.5842 1.3335)
			(end 0.5842 -1.3335)
			(stroke
				(width 0)
				(type default)
			)
			(fill no)
			(layer "F.CrtYd")
		)
		(fp_rect
			(start -0.5842 1.3335)
			(end 0.5842 -1.3335)
			(stroke
				(width 0)
				(type default)
			)
			(fill no)
			(layer "F.Fab")
		)
		(pad "1" smd custom
			(at 0 -0.762)
			(size 0.2159 0.2159)
			(layers "F.Cu" "F.Mask" "F.Paste")
			(net "MB0_CM_GATE_2")
			(options
				(clearance outline)
				(anchor circle)
			)
			(primitives
				(gr_poly
					(pts
						(arc
							(start -0.3302 -0.4318)
							(mid -0.402042 -0.402042)
							(end -0.4318 -0.3302)
						)
						(arc
							(start -0.4318 0.3302)
							(mid -0.402042 0.402042)
							(end -0.3302 0.4318)
						)
						(arc
							(start 0.3302 0.4318)
							(mid 0.402042 0.402042)
							(end 0.4318 0.3302)
						)
						(arc
							(start 0.4318 -0.3302)
							(mid 0.402042 -0.402042)
							(end 0.3302 -0.4318)
						)
					)
					(width 0)
					(fill yes)
				)
			)
		)
		(pad "2" smd custom
			(at 0 0.762)
			(size 0.2159 0.2159)
			(layers "F.Cu" "F.Mask" "F.Paste")
			(net "GND")
			(options
				(clearance outline)
				(anchor circle)
			)
			(primitives
				(gr_poly
					(pts
						(arc
							(start -0.3302 -0.4318)
							(mid -0.402042 -0.402042)
							(end -0.4318 -0.3302)
						)
						(arc
							(start -0.4318 0.3302)
							(mid -0.402042 0.402042)
							(end -0.3302 0.4318)
						)
						(arc
							(start 0.3302 0.4318)
							(mid 0.402042 0.402042)
							(end 0.4318 0.3302)
						)
						(arc
							(start 0.4318 -0.3302)
							(mid 0.402042 -0.402042)
							(end 0.3302 -0.4318)
						)
					)
					(width 0)
					(fill yes)
				)
			)
		)
	)
	(footprint ""
		(layer "F.Cu")
		(at 75.81138 -186.683396 180)
		(property "Reference" "C199"
			(at 0 0 180)
			(layer "F.SilkS")
			(hide yes)
			(effects
				(font
					(size 1.27 1.27)
				)
			)
		)
		(property "Value" "SC10U6D3V5KX-4GP"
			(at -0.0762 -6.1214 180)
			(unlocked yes)
			(layer "F.Fab")
			(hide yes)
			(effects
				(font
					(size 1.016 1.016)
					(thickness 0.1524)
				)
			)
		)
		(property "Device Type" "C805H58"
			(at -0.0762 -8.1534 180)
			(unlocked yes)
			(layer "F.Fab")
			(hide yes)
			(effects
				(font
					(size 1.016 1.016)
					(thickness 0.1524)
				)
			)
		)
		(duplicate_pad_numbers_are_jumpers no)
		(fp_line
			(start 0.635 0)
			(end -0.635 0)
			(stroke
				(width 0.508)
				(type default)
			)
			(layer "F.SilkS")
		)
		(fp_rect
			(start -0.9652 1.778)
			(end 0.9652 -1.778)
			(stroke
				(width 0)
				(type default)
			)
			(fill no)
			(layer "F.CrtYd")
		)
		(fp_poly
			(pts
				(xy -0.9652 -1.778) (xy 0.9652 -1.778) (xy 0.9652 1.778) (xy -0.9652 1.778)
			)
			(stroke
				(width 0)
				(type default)
			)
			(fill no)
			(layer "F.Fab")
		)
		(pad "1" smd rect
			(at 0 -0.9652 180)
			(size 1.397 1.143)
			(layers "F.Cu" "F.Mask" "F.Paste")
			(net "P3V3_STBY")
		)
		(pad "2" smd rect
			(at 0 0.9652 180)
			(size 1.397 1.143)
			(layers "F.Cu" "F.Mask" "F.Paste")
			(net "GND")
		)
	)
	(footprint ""
		(layer "F.Cu")
		(at 192.405 -139.573 -135)
		(property "Reference" "VIA57"
			(at 0 0 225)
			(layer "F.SilkS")
			(hide yes)
			(effects
				(font
					(size 1.27 1.27)
				)
			)
		)
		(property "Value" "85OHM-8L-1D6MM-L16L18-GP"
			(at 4.064105 0.609655 225)
			(unlocked yes)
			(layer "F.Fab")
			(hide yes)
			(effects
				(font
					(size 1.016 1.016)
					(thickness 0.1524)
				)
			)
		)
		(property "Device Type" "VIA-PCIE-4P-368076"
			(at 4.064105 -0.914474 225)
			(unlocked yes)
			(layer "F.Fab")
			(hide yes)
			(effects
				(font
					(size 1.016 1.016)
					(thickness 0.1524)
				)
			)
		)
		(duplicate_pad_numbers_are_jumpers no)
		(fp_poly
			(pts
				(xy -1.841491 -0.381057) (xy 1.841509 -0.381058) (xy 1.841508 0.380942) (xy -1.841491 0.380942)
			)
			(stroke
				(width 0)
				(type default)
			)
			(fill no)
			(layer "F.CrtYd")
		)
		(fp_poly
			(pts
				(xy -1.841491 -0.381057) (xy 1.841509 -0.381058) (xy 1.841508 0.380942) (xy -1.841491 0.380942)
			)
			(stroke
				(width 0)
				(type default)
			)
			(fill no)
			(layer "F.Fab")
		)
		(pad "1" thru_hole circle
			(at -1.460499 0 225)
			(size 0.508 0.508)
			(drill 0.254)
			(layers "*.Cu" "*.Mask")
			(remove_unused_layers no)
			(net "GND")
			(clearance 0.127)
			(thermal_gap 0.127)
		)
		(pad "2" thru_hole circle
			(at -0.4445 0 225)
			(size 0.508 0.508)
			(drill 0.254)
			(layers "*.Cu" "*.Mask")
			(remove_unused_layers no)
			(net "PCIE_IOM_TO_COMP_11_DP")
			(clearance 0.127)
			(thermal_gap 0.127)
		)
		(pad "3" thru_hole circle
			(at 0.4445 0 225)
			(size 0.508 0.508)
			(drill 0.254)
			(layers "*.Cu" "*.Mask")
			(remove_unused_layers no)
			(net "PCIE_IOM_TO_COMP_11_DN")
			(clearance 0.127)
			(thermal_gap 0.127)
		)
		(pad "4" thru_hole circle
			(at 1.460499 0 225)
			(size 0.508 0.508)
			(drill 0.254)
			(layers "*.Cu" "*.Mask")
			(remove_unused_layers no)
			(net "GND")
			(clearance 0.127)
			(thermal_gap 0.127)
		)
	)
	(footprint ""
		(layer "F.Cu")
		(at 67.8434 -170.2054 180)
		(property "Reference" "C35"
			(at 0 0 180)
			(layer "F.SilkS")
			(hide yes)
			(effects
				(font
					(size 1.27 1.27)
				)
			)
		)
		(property "Value" "SC1U16V2KX-7-GP"
			(at 1.7526 -1.6002 180)
			(unlocked yes)
			(layer "F.Fab")
			(hide yes)
			(effects
				(font
					(size 1.016 1.016)
					(thickness 0.1524)
				)
			)
		)
		(property "Device Type" "C402-TO0D2H24"
			(at 1.7526 -3.1242 180)
			(unlocked yes)
			(layer "F.Fab")
			(hide yes)
			(effects
				(font
					(size 1.016 1.016)
					(thickness 0.1524)
				)
			)
		)
		(duplicate_pad_numbers_are_jumpers no)
		(fp_rect
			(start -0.4826 0.889)
			(end 0.4826 -0.889)
			(stroke
				(width 0)
				(type default)
			)
			(fill no)
			(layer "F.CrtYd")
		)
		(fp_rect
			(start -0.4826 0.889)
			(end 0.4826 -0.889)
			(stroke
				(width 0)
				(type default)
			)
			(fill no)
			(layer "F.Fab")
		)
		(pad "1" smd custom
			(at 0 -0.4572 180)
			(size 0.1524 0.1524)
			(layers "F.Cu" "F.Mask" "F.Paste")
			(net "BMC_SELF_HW_RST_D")
			(options
				(clearance outline)
				(anchor circle)
			)
			(primitives
				(gr_poly
					(pts
						(arc
							(start -0.254 0.3048)
							(mid -0.325842 0.275042)
							(end -0.3556 0.2032)
						)
						(arc
							(start -0.3556 -0.2032)
							(mid -0.325842 -0.275042)
							(end -0.254 -0.3048)
						)
						(arc
							(start 0.254 -0.3048)
							(mid 0.325842 -0.275042)
							(end 0.3556 -0.2032)
						)
						(arc
							(start 0.3556 0.2032)
							(mid 0.325842 0.275042)
							(end 0.254 0.3048)
						)
					)
					(width 0)
					(fill yes)
				)
			)
		)
		(pad "2" smd custom
			(at 0 0.4572 180)
			(size 0.1524 0.1524)
			(layers "F.Cu" "F.Mask" "F.Paste")
			(net "Q4_G")
			(options
				(clearance outline)
				(anchor circle)
			)
			(primitives
				(gr_poly
					(pts
						(arc
							(start -0.254 0.3048)
							(mid -0.325842 0.275042)
							(end -0.3556 0.2032)
						)
						(arc
							(start -0.3556 -0.2032)
							(mid -0.325842 -0.275042)
							(end -0.254 -0.3048)
						)
						(arc
							(start 0.254 -0.3048)
							(mid 0.325842 -0.275042)
							(end 0.3556 -0.2032)
						)
						(arc
							(start 0.3556 0.2032)
							(mid 0.325842 0.275042)
							(end 0.254 0.3048)
						)
					)
					(width 0)
					(fill yes)
				)
			)
		)
	)
	(footprint ""
		(layer "F.Cu")
		(at 112.856264 -9.689338 -90)
		(property "Reference" "R462"
			(at 0 0 270)
			(layer "F.SilkS")
			(hide yes)
			(effects
				(font
					(size 1.27 1.27)
				)
			)
		)
		(property "Value" "22K6R2F-1-GP"
			(at 0.064008 -3.993896 270)
			(unlocked yes)
			(layer "F.Fab")
			(hide yes)
			(effects
				(font
					(size 1.016 1.016)
					(thickness 0.1524)
				)
			)
		)
		(property "Device Type" "R402H16"
			(at 0.064008 -5.517896 270)
			(unlocked yes)
			(layer "F.Fab")
			(hide yes)
			(effects
				(font
					(size 1.016 1.016)
					(thickness 0.1524)
				)
			)
		)
		(duplicate_pad_numbers_are_jumpers no)
		(fp_line
			(start -0.508 -0.9398)
			(end -0.508 0.9398)
			(stroke
				(width 0.1524)
				(type default)
			)
			(layer "F.SilkS")
		)
		(fp_line
			(start 0.508 -0.9398)
			(end -0.508 -0.9398)
			(stroke
				(width 0.1524)
				(type default)
			)
			(layer "F.SilkS")
		)
		(fp_rect
			(start -0.508 0.9398)
			(end 0.508 -0.9398)
			(stroke
				(width 0)
				(type default)
			)
			(fill no)
			(layer "F.CrtYd")
		)
		(fp_rect
			(start -0.508 0.9398)
			(end 0.508 -0.9398)
			(stroke
				(width 0)
				(type default)
			)
			(fill no)
			(layer "F.Fab")
		)
		(pad "1" smd custom
			(at 0 -0.4445 270)
			(size 0.1397 0.1397)
			(layers "F.Cu" "F.Mask" "F.Paste")
			(net "MB0_ISTART_R")
			(options
				(clearance outline)
				(anchor circle)
			)
			(primitives
				(gr_poly
					(pts
						(arc
							(start -0.1778 -0.2794)
							(mid -0.249642 -0.249642)
							(end -0.2794 -0.1778)
						)
						(arc
							(start -0.2794 0.1778)
							(mid -0.249642 0.249642)
							(end -0.1778 0.2794)
						)
						(arc
							(start 0.1778 0.2794)
							(mid 0.249642 0.249642)
							(end 0.2794 0.1778)
						)
						(arc
							(start 0.2794 -0.1778)
							(mid 0.249642 -0.249642)
							(end 0.1778 -0.2794)
						)
					)
					(width 0)
					(fill yes)
				)
			)
		)
		(pad "2" smd custom
			(at 0 0.4445 270)
			(size 0.1397 0.1397)
			(layers "F.Cu" "F.Mask" "F.Paste")
			(net "AGND_CURRENT_MON")
			(options
				(clearance outline)
				(anchor circle)
			)
			(primitives
				(gr_poly
					(pts
						(arc
							(start -0.1778 -0.2794)
							(mid -0.249642 -0.249642)
							(end -0.2794 -0.1778)
						)
						(arc
							(start -0.2794 0.1778)
							(mid -0.249642 0.249642)
							(end -0.1778 0.2794)
						)
						(arc
							(start 0.1778 0.2794)
							(mid 0.249642 0.249642)
							(end 0.2794 0.1778)
						)
						(arc
							(start 0.2794 -0.1778)
							(mid 0.249642 -0.249642)
							(end 0.1778 -0.2794)
						)
					)
					(width 0)
					(fill yes)
				)
			)
		)
	)
	(footprint ""
		(layer "F.Cu")
		(at 27.800046 -186.56681 180)
		(property "Reference" "C176"
			(at 0 0 180)
			(layer "F.SilkS")
			(hide yes)
			(effects
				(font
					(size 1.27 1.27)
				)
			)
		)
		(property "Value" "SC10U16V5KX-7-GP-U"
			(at -0.0762 -6.1214 180)
			(unlocked yes)
			(layer "F.Fab")
			(hide yes)
			(effects
				(font
					(size 1.016 1.016)
					(thickness 0.1524)
				)
			)
		)
		(property "Device Type" "C805H58"
			(at -0.0762 -8.1534 180)
			(unlocked yes)
			(layer "F.Fab")
			(hide yes)
			(effects
				(font
					(size 1.016 1.016)
					(thickness 0.1524)
				)
			)
		)
		(duplicate_pad_numbers_are_jumpers no)
		(fp_line
			(start 0.635 0)
			(end -0.635 0)
			(stroke
				(width 0.508)
				(type default)
			)
			(layer "F.SilkS")
		)
		(fp_rect
			(start -0.9652 1.778)
			(end 0.9652 -1.778)
			(stroke
				(width 0)
				(type default)
			)
			(fill no)
			(layer "F.CrtYd")
		)
		(fp_poly
			(pts
				(xy -0.9652 -1.778) (xy 0.9652 -1.778) (xy 0.9652 1.778) (xy -0.9652 1.778)
			)
			(stroke
				(width 0)
				(type default)
			)
			(fill no)
			(layer "F.Fab")
		)
		(pad "1" smd rect
			(at 0 -0.9652 180)
			(size 1.397 1.143)
			(layers "F.Cu" "F.Mask" "F.Paste")
			(net "P12V_STBY_VIN_PU2")
		)
		(pad "2" smd rect
			(at 0 0.9652 180)
			(size 1.397 1.143)
			(layers "F.Cu" "F.Mask" "F.Paste")
			(net "GND")
		)
	)
	(footprint ""
		(layer "F.Cu")
		(at 10.7442 -139.573 90)
		(property "Reference" "R218"
			(at 0 0 90)
			(layer "F.SilkS")
			(hide yes)
			(effects
				(font
					(size 1.27 1.27)
				)
			)
		)
		(property "Value" "120R2F-GP"
			(at 0.064008 -3.993896 90)
			(unlocked yes)
			(layer "F.Fab")
			(hide yes)
			(effects
				(font
					(size 1.016 1.016)
					(thickness 0.1524)
				)
			)
		)
		(property "Device Type" "R402H16"
			(at 0.064008 -5.517896 90)
			(unlocked yes)
			(layer "F.Fab")
			(hide yes)
			(effects
				(font
					(size 1.016 1.016)
					(thickness 0.1524)
				)
			)
		)
		(duplicate_pad_numbers_are_jumpers no)
		(fp_line
			(start 0.508 -0.9398)
			(end -0.508 -0.9398)
			(stroke
				(width 0.1524)
				(type default)
			)
			(layer "F.SilkS")
		)
		(fp_line
			(start -0.508 -0.9398)
			(end -0.508 0.9398)
			(stroke
				(width 0.1524)
				(type default)
			)
			(layer "F.SilkS")
		)
		(fp_rect
			(start -0.508 0.9398)
			(end 0.508 -0.9398)
			(stroke
				(width 0)
				(type default)
			)
			(fill no)
			(layer "F.CrtYd")
		)
		(fp_rect
			(start -0.508 0.9398)
			(end 0.508 -0.9398)
			(stroke
				(width 0)
				(type default)
			)
			(fill no)
			(layer "F.Fab")
		)
		(pad "1" smd custom
			(at 0 -0.4445 90)
			(size 0.1397 0.1397)
			(layers "F.Cu" "F.Mask" "F.Paste")
			(net "MEMBG_0")
			(options
				(clearance outline)
				(anchor circle)
			)
			(primitives
				(gr_poly
					(pts
						(arc
							(start -0.1778 -0.2794)
							(mid -0.249642 -0.249642)
							(end -0.2794 -0.1778)
						)
						(arc
							(start -0.2794 0.1778)
							(mid -0.249642 0.249642)
							(end -0.1778 0.2794)
						)
						(arc
							(start 0.1778 0.2794)
							(mid 0.249642 0.249642)
							(end 0.2794 0.1778)
						)
						(arc
							(start 0.2794 -0.1778)
							(mid 0.249642 -0.249642)
							(end 0.1778 -0.2794)
						)
					)
					(width 0)
					(fill yes)
				)
			)
		)
		(pad "2" smd custom
			(at 0 0.4445 90)
			(size 0.1397 0.1397)
			(layers "F.Cu" "F.Mask" "F.Paste")
			(net "P1V2_STBY")
			(options
				(clearance outline)
				(anchor circle)
			)
			(primitives
				(gr_poly
					(pts
						(arc
							(start -0.1778 -0.2794)
							(mid -0.249642 -0.249642)
							(end -0.2794 -0.1778)
						)
						(arc
							(start -0.2794 0.1778)
							(mid -0.249642 0.249642)
							(end -0.1778 0.2794)
						)
						(arc
							(start 0.1778 0.2794)
							(mid 0.249642 0.249642)
							(end 0.2794 0.1778)
						)
						(arc
							(start 0.2794 -0.1778)
							(mid 0.249642 -0.249642)
							(end 0.1778 -0.2794)
						)
					)
					(width 0)
					(fill yes)
				)
			)
		)
	)
	(footprint ""
		(layer "F.Cu")
		(at 42.291 -161.417)
		(property "Reference" "R313"
			(at 0 0 0)
			(layer "F.SilkS")
			(hide yes)
			(effects
				(font
					(size 1.27 1.27)
				)
			)
		)
		(property "Value" "4K7R2F-GP"
			(at 0.064008 -3.993896 0)
			(unlocked yes)
			(layer "F.Fab")
			(hide yes)
			(effects
				(font
					(size 1.016 1.016)
					(thickness 0.1524)
				)
			)
		)
		(property "Device Type" "R402H16"
			(at 0.064008 -5.517896 0)
			(unlocked yes)
			(layer "F.Fab")
			(hide yes)
			(effects
				(font
					(size 1.016 1.016)
					(thickness 0.1524)
				)
			)
		)
		(duplicate_pad_numbers_are_jumpers no)
		(fp_line
			(start -0.508 -0.9398)
			(end -0.508 0.9398)
			(stroke
				(width 0.1524)
				(type default)
			)
			(layer "F.SilkS")
		)
		(fp_line
			(start 0.508 -0.9398)
			(end -0.508 -0.9398)
			(stroke
				(width 0.1524)
				(type default)
			)
			(layer "F.SilkS")
		)
		(fp_rect
			(start -0.508 0.9398)
			(end 0.508 -0.9398)
			(stroke
				(width 0)
				(type default)
			)
			(fill no)
			(layer "F.CrtYd")
		)
		(fp_rect
			(start -0.508 0.9398)
			(end 0.508 -0.9398)
			(stroke
				(width 0)
				(type default)
			)
			(fill no)
			(layer "F.Fab")
		)
		(pad "1" smd custom
			(at 0 -0.4445)
			(size 0.1397 0.1397)
			(layers "F.Cu" "F.Mask" "F.Paste")
			(net "GND")
			(options
				(clearance outline)
				(anchor circle)
			)
			(primitives
				(gr_poly
					(pts
						(arc
							(start -0.1778 -0.2794)
							(mid -0.249642 -0.249642)
							(end -0.2794 -0.1778)
						)
						(arc
							(start -0.2794 0.1778)
							(mid -0.249642 0.249642)
							(end -0.1778 0.2794)
						)
						(arc
							(start 0.1778 0.2794)
							(mid 0.249642 0.249642)
							(end 0.2794 0.1778)
						)
						(arc
							(start 0.2794 -0.1778)
							(mid 0.249642 -0.249642)
							(end 0.1778 -0.2794)
						)
					)
					(width 0)
					(fill yes)
				)
			)
		)
		(pad "2" smd custom
			(at 0 0.4445)
			(size 0.1397 0.1397)
			(layers "F.Cu" "F.Mask" "F.Paste")
			(net "BOARD_REV_0")
			(options
				(clearance outline)
				(anchor circle)
			)
			(primitives
				(gr_poly
					(pts
						(arc
							(start -0.1778 -0.2794)
							(mid -0.249642 -0.249642)
							(end -0.2794 -0.1778)
						)
						(arc
							(start -0.2794 0.1778)
							(mid -0.249642 0.249642)
							(end -0.1778 0.2794)
						)
						(arc
							(start 0.1778 0.2794)
							(mid 0.249642 0.249642)
							(end 0.2794 0.1778)
						)
						(arc
							(start 0.2794 -0.1778)
							(mid 0.249642 -0.249642)
							(end 0.1778 -0.2794)
						)
					)
					(width 0)
					(fill yes)
				)
			)
		)
	)
	(footprint ""
		(layer "F.Cu")
		(at 17.723612 -131.007358 180)
		(property "Reference" "R221"
			(at 0 0 180)
			(layer "F.SilkS")
			(hide yes)
			(effects
				(font
					(size 1.27 1.27)
				)
			)
		)
		(property "Value" "120R2F-GP"
			(at 0.064008 -3.993896 180)
			(unlocked yes)
			(layer "F.Fab")
			(hide yes)
			(effects
				(font
					(size 1.016 1.016)
					(thickness 0.1524)
				)
			)
		)
		(property "Device Type" "R402H16"
			(at 0.064008 -5.517896 180)
			(unlocked yes)
			(layer "F.Fab")
			(hide yes)
			(effects
				(font
					(size 1.016 1.016)
					(thickness 0.1524)
				)
			)
		)
		(duplicate_pad_numbers_are_jumpers no)
		(fp_line
			(start 0.508 -0.9398)
			(end -0.508 -0.9398)
			(stroke
				(width 0.1524)
				(type default)
			)
			(layer "F.SilkS")
		)
		(fp_line
			(start -0.508 -0.9398)
			(end -0.508 0.9398)
			(stroke
				(width 0.1524)
				(type default)
			)
			(layer "F.SilkS")
		)
		(fp_rect
			(start -0.508 0.9398)
			(end 0.508 -0.9398)
			(stroke
				(width 0)
				(type default)
			)
			(fill no)
			(layer "F.CrtYd")
		)
		(fp_rect
			(start -0.508 0.9398)
			(end 0.508 -0.9398)
			(stroke
				(width 0)
				(type default)
			)
			(fill no)
			(layer "F.Fab")
		)
		(pad "1" smd custom
			(at 0 -0.4445 180)
			(size 0.1397 0.1397)
			(layers "F.Cu" "F.Mask" "F.Paste")
			(net "DDR4_ACT")
			(options
				(clearance outline)
				(anchor circle)
			)
			(primitives
				(gr_poly
					(pts
						(arc
							(start -0.1778 -0.2794)
							(mid -0.249642 -0.249642)
							(end -0.2794 -0.1778)
						)
						(arc
							(start -0.2794 0.1778)
							(mid -0.249642 0.249642)
							(end -0.1778 0.2794)
						)
						(arc
							(start 0.1778 0.2794)
							(mid 0.249642 0.249642)
							(end 0.2794 0.1778)
						)
						(arc
							(start 0.2794 -0.1778)
							(mid 0.249642 -0.249642)
							(end 0.1778 -0.2794)
						)
					)
					(width 0)
					(fill yes)
				)
			)
		)
		(pad "2" smd custom
			(at 0 0.4445 180)
			(size 0.1397 0.1397)
			(layers "F.Cu" "F.Mask" "F.Paste")
			(net "P1V2_STBY")
			(options
				(clearance outline)
				(anchor circle)
			)
			(primitives
				(gr_poly
					(pts
						(arc
							(start -0.1778 -0.2794)
							(mid -0.249642 -0.249642)
							(end -0.2794 -0.1778)
						)
						(arc
							(start -0.2794 0.1778)
							(mid -0.249642 0.249642)
							(end -0.1778 0.2794)
						)
						(arc
							(start 0.1778 0.2794)
							(mid 0.249642 0.249642)
							(end 0.2794 0.1778)
						)
						(arc
							(start 0.2794 -0.1778)
							(mid 0.249642 -0.249642)
							(end 0.1778 -0.2794)
						)
					)
					(width 0)
					(fill yes)
				)
			)
		)
	)
	(footprint ""
		(layer "F.Cu")
		(at 63.3476 -148.7678 90)
		(property "Reference" "R189"
			(at 0 0 90)
			(layer "F.SilkS")
			(hide yes)
			(effects
				(font
					(size 1.27 1.27)
				)
			)
		)
		(property "Value" "499R2F-2-GP"
			(at 0.064008 -3.993896 90)
			(unlocked yes)
			(layer "F.Fab")
			(hide yes)
			(effects
				(font
					(size 1.016 1.016)
					(thickness 0.1524)
				)
			)
		)
		(property "Device Type" "R402H16"
			(at 0.064008 -5.517896 90)
			(unlocked yes)
			(layer "F.Fab")
			(hide yes)
			(effects
				(font
					(size 1.016 1.016)
					(thickness 0.1524)
				)
			)
		)
		(duplicate_pad_numbers_are_jumpers no)
		(fp_line
			(start 0.508 -0.9398)
			(end -0.508 -0.9398)
			(stroke
				(width 0.1524)
				(type default)
			)
			(layer "F.SilkS")
		)
		(fp_line
			(start -0.508 -0.9398)
			(end -0.508 0.9398)
			(stroke
				(width 0.1524)
				(type default)
			)
			(layer "F.SilkS")
		)
		(fp_rect
			(start -0.508 0.9398)
			(end 0.508 -0.9398)
			(stroke
				(width 0)
				(type default)
			)
			(fill no)
			(layer "F.CrtYd")
		)
		(fp_rect
			(start -0.508 0.9398)
			(end 0.508 -0.9398)
			(stroke
				(width 0)
				(type default)
			)
			(fill no)
			(layer "F.Fab")
		)
		(pad "1" smd custom
			(at 0 -0.4445 90)
			(size 0.1397 0.1397)
			(layers "F.Cu" "F.Mask" "F.Paste")
			(net "I2C_BMC_COMP_SCL_OUT")
			(options
				(clearance outline)
				(anchor circle)
			)
			(primitives
				(gr_poly
					(pts
						(arc
							(start -0.1778 -0.2794)
							(mid -0.249642 -0.249642)
							(end -0.2794 -0.1778)
						)
						(arc
							(start -0.2794 0.1778)
							(mid -0.249642 0.249642)
							(end -0.1778 0.2794)
						)
						(arc
							(start 0.1778 0.2794)
							(mid 0.249642 0.249642)
							(end 0.2794 0.1778)
						)
						(arc
							(start 0.2794 -0.1778)
							(mid 0.249642 -0.249642)
							(end 0.1778 -0.2794)
						)
					)
					(width 0)
					(fill yes)
				)
			)
		)
		(pad "2" smd custom
			(at 0 0.4445 90)
			(size 0.1397 0.1397)
			(layers "F.Cu" "F.Mask" "F.Paste")
			(net "P3V3_STBY")
			(options
				(clearance outline)
				(anchor circle)
			)
			(primitives
				(gr_poly
					(pts
						(arc
							(start -0.1778 -0.2794)
							(mid -0.249642 -0.249642)
							(end -0.2794 -0.1778)
						)
						(arc
							(start -0.2794 0.1778)
							(mid -0.249642 0.249642)
							(end -0.1778 0.2794)
						)
						(arc
							(start 0.1778 0.2794)
							(mid 0.249642 0.249642)
							(end 0.2794 0.1778)
						)
						(arc
							(start 0.2794 -0.1778)
							(mid 0.249642 -0.249642)
							(end 0.1778 -0.2794)
						)
					)
					(width 0)
					(fill yes)
				)
			)
		)
	)
	(footprint ""
		(layer "F.Cu")
		(at 226.222306 -93.81744 180)
		(property "Reference" "C646"
			(at 0 0 180)
			(layer "F.SilkS")
			(hide yes)
			(effects
				(font
					(size 1.27 1.27)
				)
			)
		)
		(property "Value" "SC2200P50V2KX-2GP"
			(at 1.1811 -2.7051 180)
			(unlocked yes)
			(layer "F.Fab")
			(hide yes)
			(effects
				(font
					(size 1.016 1.016)
					(thickness 0.1524)
				)
			)
		)
		(property "Device Type" "C402H22"
			(at 1.1811 -4.2291 180)
			(unlocked yes)
			(layer "F.Fab")
			(hide yes)
			(effects
				(font
					(size 1.016 1.016)
					(thickness 0.1524)
				)
			)
		)
		(duplicate_pad_numbers_are_jumpers no)
		(fp_rect
			(start -0.4318 0.9525)
			(end 0.4318 -0.9525)
			(stroke
				(width 0)
				(type default)
			)
			(fill no)
			(layer "F.CrtYd")
		)
		(fp_rect
			(start -0.4318 0.9525)
			(end 0.4318 -0.9525)
			(stroke
				(width 0)
				(type default)
			)
			(fill no)
			(layer "F.Fab")
		)
		(pad "1" smd custom
			(at 0 -0.4445 180)
			(size 0.1524 0.1524)
			(layers "F.Cu" "F.Mask" "F.Paste")
			(net "P3V3_M2_LL")
			(options
				(clearance outline)
				(anchor circle)
			)
			(primitives
				(gr_poly
					(pts
						(arc
							(start 0.3048 -0.2032)
							(mid 0.275042 -0.275042)
							(end 0.2032 -0.3048)
						)
						(arc
							(start -0.2032 -0.3048)
							(mid -0.275042 -0.275042)
							(end -0.3048 -0.2032)
						)
						(arc
							(start -0.3048 0.2032)
							(mid -0.275042 0.275042)
							(end -0.2032 0.3048)
						)
						(arc
							(start 0.2032 0.3048)
							(mid 0.275042 0.275042)
							(end 0.3048 0.2032)
						)
					)
					(width 0)
					(fill yes)
				)
			)
		)
		(pad "2" smd custom
			(at 0 0.4445 180)
			(size 0.1524 0.1524)
			(layers "F.Cu" "F.Mask" "F.Paste")
			(net "P3V3_M2_SNB")
			(options
				(clearance outline)
				(anchor circle)
			)
			(primitives
				(gr_poly
					(pts
						(arc
							(start 0.3048 -0.2032)
							(mid 0.275042 -0.275042)
							(end 0.2032 -0.3048)
						)
						(arc
							(start -0.2032 -0.3048)
							(mid -0.275042 -0.275042)
							(end -0.3048 -0.2032)
						)
						(arc
							(start -0.3048 0.2032)
							(mid -0.275042 0.275042)
							(end -0.2032 0.3048)
						)
						(arc
							(start 0.2032 0.3048)
							(mid 0.275042 0.275042)
							(end 0.3048 0.2032)
						)
					)
					(width 0)
					(fill yes)
				)
			)
		)
	)
	(footprint ""
		(layer "F.Cu")
		(at 200.533 -141.224 -135)
		(property "Reference" "VIA54"
			(at 0 0 225)
			(layer "F.SilkS")
			(hide yes)
			(effects
				(font
					(size 1.27 1.27)
				)
			)
		)
		(property "Value" "85OHM-8L-1D6MM-L16L18-GP"
			(at 4.064105 0.609655 225)
			(unlocked yes)
			(layer "F.Fab")
			(hide yes)
			(effects
				(font
					(size 1.016 1.016)
					(thickness 0.1524)
				)
			)
		)
		(property "Device Type" "VIA-PCIE-4P-368076"
			(at 4.064105 -0.914474 225)
			(unlocked yes)
			(layer "F.Fab")
			(hide yes)
			(effects
				(font
					(size 1.016 1.016)
					(thickness 0.1524)
				)
			)
		)
		(duplicate_pad_numbers_are_jumpers no)
		(fp_poly
			(pts
				(xy -1.841491 -0.381057) (xy 1.841509 -0.381058) (xy 1.841508 0.380942) (xy -1.841491 0.380942)
			)
			(stroke
				(width 0)
				(type default)
			)
			(fill no)
			(layer "F.CrtYd")
		)
		(fp_poly
			(pts
				(xy -1.841491 -0.381057) (xy 1.841509 -0.381058) (xy 1.841508 0.380942) (xy -1.841491 0.380942)
			)
			(stroke
				(width 0)
				(type default)
			)
			(fill no)
			(layer "F.Fab")
		)
		(pad "1" thru_hole circle
			(at -1.460499 0 225)
			(size 0.508 0.508)
			(drill 0.254)
			(layers "*.Cu" "*.Mask")
			(remove_unused_layers no)
			(net "GND")
			(clearance 0.127)
			(thermal_gap 0.127)
		)
		(pad "2" thru_hole circle
			(at -0.4445 0 225)
			(size 0.508 0.508)
			(drill 0.254)
			(layers "*.Cu" "*.Mask")
			(remove_unused_layers no)
			(net "PCIE_COMP_TO_IOM_10_DP")
			(clearance 0.127)
			(thermal_gap 0.127)
		)
		(pad "3" thru_hole circle
			(at 0.4445 0 225)
			(size 0.508 0.508)
			(drill 0.254)
			(layers "*.Cu" "*.Mask")
			(remove_unused_layers no)
			(net "PCIE_COMP_TO_IOM_10_DN")
			(clearance 0.127)
			(thermal_gap 0.127)
		)
		(pad "4" thru_hole circle
			(at 1.460499 0 225)
			(size 0.508 0.508)
			(drill 0.254)
			(layers "*.Cu" "*.Mask")
			(remove_unused_layers no)
			(net "GND")
			(clearance 0.127)
			(thermal_gap 0.127)
		)
	)
	(footprint ""
		(layer "F.Cu")
		(at 63.119 -169.291 90)
		(property "Reference" "Q4"
			(at 0 0 90)
			(layer "F.SilkS")
			(hide yes)
			(effects
				(font
					(size 1.27 1.27)
				)
			)
		)
		(property "Value" "2N7002K-1-GP"
			(at 0.127 -8.9662 90)
			(unlocked yes)
			(layer "F.Fab")
			(hide yes)
			(effects
				(font
					(size 1.016 1.016)
					(thickness 0.1524)
				)
			)
		)
		(property "Device Type" "SOT23DGS2D4H44"
			(at 0.127 -10.4902 90)
			(unlocked yes)
			(layer "F.Fab")
			(hide yes)
			(effects
				(font
					(size 1.016 1.016)
					(thickness 0.1524)
				)
			)
		)
		(duplicate_pad_numbers_are_jumpers no)
		(fp_line
			(start 1.651 -1.778)
			(end -1.651 -1.778)
			(stroke
				(width 0.1524)
				(type default)
			)
			(layer "F.SilkS")
		)
		(fp_line
			(start -1.651 -1.778)
			(end -1.651 1.778)
			(stroke
				(width 0.1524)
				(type default)
			)
			(layer "F.SilkS")
		)
		(fp_line
			(start 1.651 1.778)
			(end 1.651 -1.778)
			(stroke
				(width 0.1524)
				(type default)
			)
			(layer "F.SilkS")
		)
		(fp_line
			(start -1.651 1.778)
			(end 1.651 1.778)
			(stroke
				(width 0.1524)
				(type default)
			)
			(layer "F.SilkS")
		)
		(fp_poly
			(pts
				(xy -1.778 1.8796) (xy -1.778 -1.8796) (xy 1.778 -1.8796) (xy 1.778 1.8796)
			)
			(stroke
				(width 0)
				(type default)
			)
			(fill no)
			(layer "F.CrtYd")
		)
		(fp_poly
			(pts
				(xy -1.778 1.8796) (xy -1.778 -1.8796) (xy 1.778 -1.8796) (xy 1.778 1.8796)
			)
			(stroke
				(width 0)
				(type default)
			)
			(fill no)
			(layer "F.Fab")
		)
		(pad "D" smd custom
			(at 0 -0.9525 90)
			(size 0.1905 0.1905)
			(layers "F.Cu" "F.Mask" "F.Paste")
			(net "FM_TPM_PRSNT_RST_N")
			(options
				(clearance outline)
				(anchor circle)
			)
			(primitives
				(gr_poly
					(pts
						(arc
							(start -0.1778 0.5715)
							(mid -0.321484 0.511984)
							(end -0.381 0.3683)
						)
						(arc
							(start -0.381 -0.3683)
							(mid -0.321484 -0.511984)
							(end -0.1778 -0.5715)
						)
						(arc
							(start 0.1778 -0.5715)
							(mid 0.321484 -0.511984)
							(end 0.381 -0.3683)
						)
						(arc
							(start 0.381 0.3683)
							(mid 0.321484 0.511984)
							(end 0.1778 0.5715)
						)
					)
					(width 0)
					(fill yes)
				)
			)
		)
		(pad "G" smd custom
			(at -0.98425 0.9525 90)
			(size 0.1905 0.1905)
			(layers "F.Cu" "F.Mask" "F.Paste")
			(net "Q4_G")
			(options
				(clearance outline)
				(anchor circle)
			)
			(primitives
				(gr_poly
					(pts
						(arc
							(start -0.1778 0.5715)
							(mid -0.321484 0.511984)
							(end -0.381 0.3683)
						)
						(arc
							(start -0.381 -0.3683)
							(mid -0.321484 -0.511984)
							(end -0.1778 -0.5715)
						)
						(arc
							(start 0.1778 -0.5715)
							(mid 0.321484 -0.511984)
							(end 0.381 -0.3683)
						)
						(arc
							(start 0.381 0.3683)
							(mid 0.321484 0.511984)
							(end 0.1778 0.5715)
						)
					)
					(width 0)
					(fill yes)
				)
			)
		)
		(pad "S" smd custom
			(at 0.98425 0.9525 90)
			(size 0.1905 0.1905)
			(layers "F.Cu" "F.Mask" "F.Paste")
			(net "GND")
			(options
				(clearance outline)
				(anchor circle)
			)
			(primitives
				(gr_poly
					(pts
						(arc
							(start -0.1778 0.5715)
							(mid -0.321484 0.511984)
							(end -0.381 0.3683)
						)
						(arc
							(start -0.381 -0.3683)
							(mid -0.321484 -0.511984)
							(end -0.1778 -0.5715)
						)
						(arc
							(start 0.1778 -0.5715)
							(mid 0.321484 -0.511984)
							(end 0.381 -0.3683)
						)
						(arc
							(start 0.381 0.3683)
							(mid 0.321484 0.511984)
							(end 0.1778 0.5715)
						)
					)
					(width 0)
					(fill yes)
				)
			)
		)
	)
	(footprint ""
		(layer "F.Cu")
		(at 20.582128 -131.007358 180)
		(property "Reference" "R226"
			(at 0 0 180)
			(layer "F.SilkS")
			(hide yes)
			(effects
				(font
					(size 1.27 1.27)
				)
			)
		)
		(property "Value" "120R2F-GP"
			(at 0.064008 -3.993896 180)
			(unlocked yes)
			(layer "F.Fab")
			(hide yes)
			(effects
				(font
					(size 1.016 1.016)
					(thickness 0.1524)
				)
			)
		)
		(property "Device Type" "R402H16"
			(at 0.064008 -5.517896 180)
			(unlocked yes)
			(layer "F.Fab")
			(hide yes)
			(effects
				(font
					(size 1.016 1.016)
					(thickness 0.1524)
				)
			)
		)
		(duplicate_pad_numbers_are_jumpers no)
		(fp_line
			(start 0.508 -0.9398)
			(end -0.508 -0.9398)
			(stroke
				(width 0.1524)
				(type default)
			)
			(layer "F.SilkS")
		)
		(fp_line
			(start -0.508 -0.9398)
			(end -0.508 0.9398)
			(stroke
				(width 0.1524)
				(type default)
			)
			(layer "F.SilkS")
		)
		(fp_rect
			(start -0.508 0.9398)
			(end 0.508 -0.9398)
			(stroke
				(width 0)
				(type default)
			)
			(fill no)
			(layer "F.CrtYd")
		)
		(fp_rect
			(start -0.508 0.9398)
			(end 0.508 -0.9398)
			(stroke
				(width 0)
				(type default)
			)
			(fill no)
			(layer "F.Fab")
		)
		(pad "1" smd custom
			(at 0 -0.4445 180)
			(size 0.1397 0.1397)
			(layers "F.Cu" "F.Mask" "F.Paste")
			(net "MEMCASN")
			(options
				(clearance outline)
				(anchor circle)
			)
			(primitives
				(gr_poly
					(pts
						(arc
							(start -0.1778 -0.2794)
							(mid -0.249642 -0.249642)
							(end -0.2794 -0.1778)
						)
						(arc
							(start -0.2794 0.1778)
							(mid -0.249642 0.249642)
							(end -0.1778 0.2794)
						)
						(arc
							(start 0.1778 0.2794)
							(mid 0.249642 0.249642)
							(end 0.2794 0.1778)
						)
						(arc
							(start 0.2794 -0.1778)
							(mid 0.249642 -0.249642)
							(end 0.1778 -0.2794)
						)
					)
					(width 0)
					(fill yes)
				)
			)
		)
		(pad "2" smd custom
			(at 0 0.4445 180)
			(size 0.1397 0.1397)
			(layers "F.Cu" "F.Mask" "F.Paste")
			(net "P1V2_STBY")
			(options
				(clearance outline)
				(anchor circle)
			)
			(primitives
				(gr_poly
					(pts
						(arc
							(start -0.1778 -0.2794)
							(mid -0.249642 -0.249642)
							(end -0.2794 -0.1778)
						)
						(arc
							(start -0.2794 0.1778)
							(mid -0.249642 0.249642)
							(end -0.1778 0.2794)
						)
						(arc
							(start 0.1778 0.2794)
							(mid 0.249642 0.249642)
							(end 0.2794 0.1778)
						)
						(arc
							(start 0.2794 -0.1778)
							(mid 0.249642 -0.249642)
							(end 0.1778 -0.2794)
						)
					)
					(width 0)
					(fill yes)
				)
			)
		)
	)
	(footprint ""
		(layer "F.Cu")
		(at 77.18298 -155.5369 -90)
		(property "Reference" "C234"
			(at 0 0 270)
			(layer "F.SilkS")
			(hide yes)
			(effects
				(font
					(size 1.27 1.27)
				)
			)
		)
		(property "Value" "SC1KP50V2KX-1GP"
			(at 1.1811 -2.7051 270)
			(unlocked yes)
			(layer "F.Fab")
			(hide yes)
			(effects
				(font
					(size 1.016 1.016)
					(thickness 0.1524)
				)
			)
		)
		(property "Device Type" "C402H22"
			(at 1.1811 -4.2291 270)
			(unlocked yes)
			(layer "F.Fab")
			(hide yes)
			(effects
				(font
					(size 1.016 1.016)
					(thickness 0.1524)
				)
			)
		)
		(duplicate_pad_numbers_are_jumpers no)
		(fp_rect
			(start -0.4318 0.9525)
			(end 0.4318 -0.9525)
			(stroke
				(width 0)
				(type default)
			)
			(fill no)
			(layer "F.CrtYd")
		)
		(fp_rect
			(start -0.4318 0.9525)
			(end 0.4318 -0.9525)
			(stroke
				(width 0)
				(type default)
			)
			(fill no)
			(layer "F.Fab")
		)
		(pad "1" smd custom
			(at 0 -0.4445 270)
			(size 0.1524 0.1524)
			(layers "F.Cu" "F.Mask" "F.Paste")
			(net "TPS74801_P1V15_STBY_OUT")
			(options
				(clearance outline)
				(anchor circle)
			)
			(primitives
				(gr_poly
					(pts
						(arc
							(start 0.3048 -0.2032)
							(mid 0.275042 -0.275042)
							(end 0.2032 -0.3048)
						)
						(arc
							(start -0.2032 -0.3048)
							(mid -0.275042 -0.275042)
							(end -0.3048 -0.2032)
						)
						(arc
							(start -0.3048 0.2032)
							(mid -0.275042 0.275042)
							(end -0.2032 0.3048)
						)
						(arc
							(start 0.2032 0.3048)
							(mid 0.275042 0.275042)
							(end 0.3048 0.2032)
						)
					)
					(width 0)
					(fill yes)
				)
			)
		)
		(pad "2" smd custom
			(at 0 0.4445 270)
			(size 0.1524 0.1524)
			(layers "F.Cu" "F.Mask" "F.Paste")
			(net "TPS74801_P1V15_STBY_FB")
			(options
				(clearance outline)
				(anchor circle)
			)
			(primitives
				(gr_poly
					(pts
						(arc
							(start 0.3048 -0.2032)
							(mid 0.275042 -0.275042)
							(end 0.2032 -0.3048)
						)
						(arc
							(start -0.2032 -0.3048)
							(mid -0.275042 -0.275042)
							(end -0.3048 -0.2032)
						)
						(arc
							(start -0.3048 0.2032)
							(mid -0.275042 0.275042)
							(end -0.2032 0.3048)
						)
						(arc
							(start 0.2032 0.3048)
							(mid 0.275042 0.275042)
							(end 0.3048 0.2032)
						)
					)
					(width 0)
					(fill yes)
				)
			)
		)
	)
	(footprint ""
		(layer "F.Cu")
		(at 59.857132 -135.702548)
		(property "Reference" "TP208"
			(at 0 0 0)
			(layer "F.SilkS")
			(hide yes)
			(effects
				(font
					(size 1.27 1.27)
				)
			)
		)
		(property "Value" "TPAD28-2-GP"
			(at -0.0127 -1.6637 0)
			(unlocked yes)
			(layer "F.Fab")
			(hide yes)
			(effects
				(font
					(size 1.016 1.016)
					(thickness 0.1524)
				)
			)
		)
		(property "Device Type" "TPAD28"
			(at -0.0127 -3.1877 0)
			(unlocked yes)
			(layer "F.Fab")
			(hide yes)
			(effects
				(font
					(size 1.016 1.016)
					(thickness 0.1524)
				)
			)
		)
		(duplicate_pad_numbers_are_jumpers no)
		(fp_poly
			(pts
				(arc
					(start 0.3556 0)
					(mid -0.3556 0)
					(end 0.3556 0)
				)
			)
			(stroke
				(width 0)
				(type default)
			)
			(fill no)
			(layer "F.CrtYd")
		)
		(fp_poly
			(pts
				(arc
					(start 0.6096 0)
					(mid -0.6096 0)
					(end 0.6096 0)
				)
			)
			(stroke
				(width 0)
				(type default)
			)
			(fill no)
			(layer "F.Fab")
		)
		(pad "1" smd circle
			(at 0 0)
			(size 0.7112 0.7112)
			(layers "F.Cu" "F.Mask" "F.Paste")
			(net "TP_BMC_EXT2_LED_G")
		)
	)
	(footprint ""
		(layer "F.Cu")
		(at 35.246818 -136.59993 90)
		(property "Reference" "R351"
			(at 0 0 90)
			(layer "F.SilkS")
			(hide yes)
			(effects
				(font
					(size 1.27 1.27)
				)
			)
		)
		(property "Value" "10KR2F-2-GP"
			(at 0.064008 -3.993896 90)
			(unlocked yes)
			(layer "F.Fab")
			(hide yes)
			(effects
				(font
					(size 1.016 1.016)
					(thickness 0.1524)
				)
			)
		)
		(property "Device Type" "R402H16"
			(at 0.064008 -5.517896 90)
			(unlocked yes)
			(layer "F.Fab")
			(hide yes)
			(effects
				(font
					(size 1.016 1.016)
					(thickness 0.1524)
				)
			)
		)
		(duplicate_pad_numbers_are_jumpers no)
		(fp_line
			(start 0.508 -0.9398)
			(end -0.508 -0.9398)
			(stroke
				(width 0.1524)
				(type default)
			)
			(layer "F.SilkS")
		)
		(fp_line
			(start -0.508 -0.9398)
			(end -0.508 0.9398)
			(stroke
				(width 0.1524)
				(type default)
			)
			(layer "F.SilkS")
		)
		(fp_rect
			(start -0.508 0.9398)
			(end 0.508 -0.9398)
			(stroke
				(width 0)
				(type default)
			)
			(fill no)
			(layer "F.CrtYd")
		)
		(fp_rect
			(start -0.508 0.9398)
			(end 0.508 -0.9398)
			(stroke
				(width 0)
				(type default)
			)
			(fill no)
			(layer "F.Fab")
		)
		(pad "1" smd custom
			(at 0 -0.4445 90)
			(size 0.1397 0.1397)
			(layers "F.Cu" "F.Mask" "F.Paste")
			(net "GND")
			(options
				(clearance outline)
				(anchor circle)
			)
			(primitives
				(gr_poly
					(pts
						(arc
							(start -0.1778 -0.2794)
							(mid -0.249642 -0.249642)
							(end -0.2794 -0.1778)
						)
						(arc
							(start -0.2794 0.1778)
							(mid -0.249642 0.249642)
							(end -0.1778 0.2794)
						)
						(arc
							(start 0.1778 0.2794)
							(mid 0.249642 0.249642)
							(end 0.2794 0.1778)
						)
						(arc
							(start 0.2794 -0.1778)
							(mid 0.249642 -0.249642)
							(end 0.1778 -0.2794)
						)
					)
					(width 0)
					(fill yes)
				)
			)
		)
		(pad "2" smd custom
			(at 0 0.4445 90)
			(size 0.1397 0.1397)
			(layers "F.Cu" "F.Mask" "F.Paste")
			(net "PECI")
			(options
				(clearance outline)
				(anchor circle)
			)
			(primitives
				(gr_poly
					(pts
						(arc
							(start -0.1778 -0.2794)
							(mid -0.249642 -0.249642)
							(end -0.2794 -0.1778)
						)
						(arc
							(start -0.2794 0.1778)
							(mid -0.249642 0.249642)
							(end -0.1778 0.2794)
						)
						(arc
							(start 0.1778 0.2794)
							(mid 0.249642 0.249642)
							(end 0.2794 0.1778)
						)
						(arc
							(start 0.2794 -0.1778)
							(mid 0.249642 -0.249642)
							(end 0.1778 -0.2794)
						)
					)
					(width 0)
					(fill yes)
				)
			)
		)
	)
	(footprint ""
		(layer "F.Cu")
		(at 213.098888 -94.683326)
		(property "Reference" "C648"
			(at 0 0 0)
			(layer "F.SilkS")
			(hide yes)
			(effects
				(font
					(size 1.27 1.27)
				)
			)
		)
		(property "Value" "SC68P50V2JN-2-GP"
			(at 1.1811 -2.7051 0)
			(unlocked yes)
			(layer "F.Fab")
			(hide yes)
			(effects
				(font
					(size 1.016 1.016)
					(thickness 0.1524)
				)
			)
		)
		(property "Device Type" "C402H22"
			(at 1.1811 -4.2291 0)
			(unlocked yes)
			(layer "F.Fab")
			(hide yes)
			(effects
				(font
					(size 1.016 1.016)
					(thickness 0.1524)
				)
			)
		)
		(duplicate_pad_numbers_are_jumpers no)
		(fp_rect
			(start -0.4318 0.9525)
			(end 0.4318 -0.9525)
			(stroke
				(width 0)
				(type default)
			)
			(fill no)
			(layer "F.CrtYd")
		)
		(fp_rect
			(start -0.4318 0.9525)
			(end 0.4318 -0.9525)
			(stroke
				(width 0)
				(type default)
			)
			(fill no)
			(layer "F.Fab")
		)
		(pad "1" smd custom
			(at 0 -0.4445)
			(size 0.1524 0.1524)
			(layers "F.Cu" "F.Mask" "F.Paste")
			(net "P3V3_M2_VFB")
			(options
				(clearance outline)
				(anchor circle)
			)
			(primitives
				(gr_poly
					(pts
						(arc
							(start 0.3048 -0.2032)
							(mid 0.275042 -0.275042)
							(end 0.2032 -0.3048)
						)
						(arc
							(start -0.2032 -0.3048)
							(mid -0.275042 -0.275042)
							(end -0.3048 -0.2032)
						)
						(arc
							(start -0.3048 0.2032)
							(mid -0.275042 0.275042)
							(end -0.2032 0.3048)
						)
						(arc
							(start 0.2032 0.3048)
							(mid 0.275042 0.275042)
							(end 0.3048 0.2032)
						)
					)
					(width 0)
					(fill yes)
				)
			)
		)
		(pad "2" smd custom
			(at 0 0.4445)
			(size 0.1524 0.1524)
			(layers "F.Cu" "F.Mask" "F.Paste")
			(net "P3V3_M2_VFB_R")
			(options
				(clearance outline)
				(anchor circle)
			)
			(primitives
				(gr_poly
					(pts
						(arc
							(start 0.3048 -0.2032)
							(mid 0.275042 -0.275042)
							(end 0.2032 -0.3048)
						)
						(arc
							(start -0.2032 -0.3048)
							(mid -0.275042 -0.275042)
							(end -0.3048 -0.2032)
						)
						(arc
							(start -0.3048 0.2032)
							(mid -0.275042 0.275042)
							(end -0.2032 0.3048)
						)
						(arc
							(start 0.2032 0.3048)
							(mid 0.275042 0.275042)
							(end 0.3048 0.2032)
						)
					)
					(width 0)
					(fill yes)
				)
			)
		)
	)
	(footprint ""
		(layer "F.Cu")
		(at 212.331046 -122.65406)
		(property "Reference" "TP211"
			(at 0 0 0)
			(layer "F.SilkS")
			(hide yes)
			(effects
				(font
					(size 1.27 1.27)
				)
			)
		)
		(property "Value" "TPAD28-2-GP"
			(at -0.0127 -1.6637 0)
			(unlocked yes)
			(layer "F.Fab")
			(hide yes)
			(effects
				(font
					(size 1.016 1.016)
					(thickness 0.1524)
				)
			)
		)
		(property "Device Type" "TPAD28"
			(at -0.0127 -3.1877 0)
			(unlocked yes)
			(layer "F.Fab")
			(hide yes)
			(effects
				(font
					(size 1.016 1.016)
					(thickness 0.1524)
				)
			)
		)
		(duplicate_pad_numbers_are_jumpers no)
		(fp_poly
			(pts
				(arc
					(start 0.3556 0)
					(mid -0.3556 0)
					(end 0.3556 0)
				)
			)
			(stroke
				(width 0)
				(type default)
			)
			(fill no)
			(layer "F.CrtYd")
		)
		(fp_poly
			(pts
				(arc
					(start 0.6096 0)
					(mid -0.6096 0)
					(end 0.6096 0)
				)
			)
			(stroke
				(width 0)
				(type default)
			)
			(fill no)
			(layer "F.Fab")
		)
		(pad "1" smd circle
			(at 0 0)
			(size 0.7112 0.7112)
			(layers "F.Cu" "F.Mask" "F.Paste")
			(net "TP_M2_1_MFG_CLK")
		)
	)
	(footprint ""
		(layer "F.Cu")
		(at 59.436 -158.369)
		(property "Reference" "R396"
			(at 0 0 0)
			(layer "F.SilkS")
			(hide yes)
			(effects
				(font
					(size 1.27 1.27)
				)
			)
		)
		(property "Value" "4K7R2F-GP"
			(at 0.064008 -3.993896 0)
			(unlocked yes)
			(layer "F.Fab")
			(hide yes)
			(effects
				(font
					(size 1.016 1.016)
					(thickness 0.1524)
				)
			)
		)
		(property "Device Type" "R402H16"
			(at 0.064008 -5.517896 0)
			(unlocked yes)
			(layer "F.Fab")
			(hide yes)
			(effects
				(font
					(size 1.016 1.016)
					(thickness 0.1524)
				)
			)
		)
		(duplicate_pad_numbers_are_jumpers no)
		(fp_line
			(start -0.508 -0.9398)
			(end -0.508 0.9398)
			(stroke
				(width 0.1524)
				(type default)
			)
			(layer "F.SilkS")
		)
		(fp_line
			(start 0.508 -0.9398)
			(end -0.508 -0.9398)
			(stroke
				(width 0.1524)
				(type default)
			)
			(layer "F.SilkS")
		)
		(fp_rect
			(start -0.508 0.9398)
			(end 0.508 -0.9398)
			(stroke
				(width 0)
				(type default)
			)
			(fill no)
			(layer "F.CrtYd")
		)
		(fp_rect
			(start -0.508 0.9398)
			(end 0.508 -0.9398)
			(stroke
				(width 0)
				(type default)
			)
			(fill no)
			(layer "F.Fab")
		)
		(pad "1" smd custom
			(at 0 -0.4445)
			(size 0.1397 0.1397)
			(layers "F.Cu" "F.Mask" "F.Paste")
			(net "GND")
			(options
				(clearance outline)
				(anchor circle)
			)
			(primitives
				(gr_poly
					(pts
						(arc
							(start -0.1778 -0.2794)
							(mid -0.249642 -0.249642)
							(end -0.2794 -0.1778)
						)
						(arc
							(start -0.2794 0.1778)
							(mid -0.249642 0.249642)
							(end -0.1778 0.2794)
						)
						(arc
							(start 0.1778 0.2794)
							(mid 0.249642 0.249642)
							(end 0.2794 0.1778)
						)
						(arc
							(start 0.2794 -0.1778)
							(mid 0.249642 -0.249642)
							(end 0.1778 -0.2794)
						)
					)
					(width 0)
					(fill yes)
				)
			)
		)
		(pad "2" smd custom
			(at 0 0.4445)
			(size 0.1397 0.1397)
			(layers "F.Cu" "F.Mask" "F.Paste")
			(net "MAC2_TXD0")
			(options
				(clearance outline)
				(anchor circle)
			)
			(primitives
				(gr_poly
					(pts
						(arc
							(start -0.1778 -0.2794)
							(mid -0.249642 -0.249642)
							(end -0.2794 -0.1778)
						)
						(arc
							(start -0.2794 0.1778)
							(mid -0.249642 0.249642)
							(end -0.1778 0.2794)
						)
						(arc
							(start 0.1778 0.2794)
							(mid 0.249642 0.249642)
							(end 0.2794 0.1778)
						)
						(arc
							(start 0.2794 -0.1778)
							(mid 0.249642 -0.249642)
							(end 0.1778 -0.2794)
						)
					)
					(width 0)
					(fill yes)
				)
			)
		)
	)
	(footprint ""
		(layer "F.Cu")
		(at 83.359498 -88.535764 90)
		(property "Reference" "VIA13"
			(at 0 0 90)
			(layer "F.SilkS")
			(hide yes)
			(effects
				(font
					(size 1.27 1.27)
				)
			)
		)
		(property "Value" "85OHM-8L-1D6MM-L16L18-GP"
			(at 4.064 0.6096 90)
			(unlocked yes)
			(layer "F.Fab")
			(hide yes)
			(effects
				(font
					(size 1.016 1.016)
					(thickness 0.1524)
				)
			)
		)
		(property "Device Type" "VIA-PCIE-4P-368076"
			(at 4.064 -0.9144 90)
			(unlocked yes)
			(layer "F.Fab")
			(hide yes)
			(effects
				(font
					(size 1.016 1.016)
					(thickness 0.1524)
				)
			)
		)
		(duplicate_pad_numbers_are_jumpers no)
		(fp_rect
			(start -1.8415 0.381)
			(end 1.8415 -0.381)
			(stroke
				(width 0)
				(type default)
			)
			(fill no)
			(layer "F.CrtYd")
		)
		(fp_rect
			(start -1.8415 0.381)
			(end 1.8415 -0.381)
			(stroke
				(width 0)
				(type default)
			)
			(fill no)
			(layer "F.Fab")
		)
		(pad "1" thru_hole circle
			(at -1.4605 0 90)
			(size 0.508 0.508)
			(drill 0.254)
			(layers "*.Cu" "*.Mask")
			(remove_unused_layers no)
			(net "GND")
			(clearance 0.127)
			(thermal_gap 0.127)
		)
		(pad "2" thru_hole circle
			(at -0.4445 0 90)
			(size 0.508 0.508)
			(drill 0.254)
			(layers "*.Cu" "*.Mask")
			(remove_unused_layers no)
			(net "PCIE_IOM_TO_COMP_21_DP")
			(clearance 0.127)
			(thermal_gap 0.127)
		)
		(pad "3" thru_hole circle
			(at 0.4445 0 90)
			(size 0.508 0.508)
			(drill 0.254)
			(layers "*.Cu" "*.Mask")
			(remove_unused_layers no)
			(net "PCIE_IOM_TO_COMP_21_DN")
			(clearance 0.127)
			(thermal_gap 0.127)
		)
		(pad "4" thru_hole circle
			(at 1.4605 0 90)
			(size 0.508 0.508)
			(drill 0.254)
			(layers "*.Cu" "*.Mask")
			(remove_unused_layers no)
			(net "GND")
			(clearance 0.127)
			(thermal_gap 0.127)
		)
	)
	(footprint ""
		(layer "F.Cu")
		(at 52.485544 -157.136846)
		(property "Reference" "TP210"
			(at 0 0 0)
			(layer "F.SilkS")
			(hide yes)
			(effects
				(font
					(size 1.27 1.27)
				)
			)
		)
		(property "Value" "TPAD28-2-GP"
			(at -0.0127 -1.6637 0)
			(unlocked yes)
			(layer "F.Fab")
			(hide yes)
			(effects
				(font
					(size 1.016 1.016)
					(thickness 0.1524)
				)
			)
		)
		(property "Device Type" "TPAD28"
			(at -0.0127 -3.1877 0)
			(unlocked yes)
			(layer "F.Fab")
			(hide yes)
			(effects
				(font
					(size 1.016 1.016)
					(thickness 0.1524)
				)
			)
		)
		(duplicate_pad_numbers_are_jumpers no)
		(fp_poly
			(pts
				(arc
					(start 0.3556 0)
					(mid -0.3556 0)
					(end 0.3556 0)
				)
			)
			(stroke
				(width 0)
				(type default)
			)
			(fill no)
			(layer "F.CrtYd")
		)
		(fp_poly
			(pts
				(arc
					(start 0.6096 0)
					(mid -0.6096 0)
					(end 0.6096 0)
				)
			)
			(stroke
				(width 0)
				(type default)
			)
			(fill no)
			(layer "F.Fab")
		)
		(pad "1" smd circle
			(at 0 0)
			(size 0.7112 0.7112)
			(layers "F.Cu" "F.Mask" "F.Paste")
			(net "ADC_P0V975")
		)
	)
	(footprint ""
		(layer "F.Cu")
		(at 226.515676 -102.169214 180)
		(property "Reference" "C672"
			(at 0 0 180)
			(layer "F.SilkS")
			(hide yes)
			(effects
				(font
					(size 1.27 1.27)
				)
			)
		)
		(property "Value" "SC10U16V5KX-7-GP-U"
			(at -0.0762 -6.1214 180)
			(unlocked yes)
			(layer "F.Fab")
			(hide yes)
			(effects
				(font
					(size 1.016 1.016)
					(thickness 0.1524)
				)
			)
		)
		(property "Device Type" "C805H58"
			(at -0.0762 -8.1534 180)
			(unlocked yes)
			(layer "F.Fab")
			(hide yes)
			(effects
				(font
					(size 1.016 1.016)
					(thickness 0.1524)
				)
			)
		)
		(duplicate_pad_numbers_are_jumpers no)
		(fp_line
			(start 0.635 0)
			(end -0.635 0)
			(stroke
				(width 0.508)
				(type default)
			)
			(layer "F.SilkS")
		)
		(fp_rect
			(start -0.9652 1.778)
			(end 0.9652 -1.778)
			(stroke
				(width 0)
				(type default)
			)
			(fill no)
			(layer "F.CrtYd")
		)
		(fp_poly
			(pts
				(xy -0.9652 -1.778) (xy 0.9652 -1.778) (xy 0.9652 1.778) (xy -0.9652 1.778)
			)
			(stroke
				(width 0)
				(type default)
			)
			(fill no)
			(layer "F.Fab")
		)
		(pad "1" smd rect
			(at 0 -0.9652 180)
			(size 1.397 1.143)
			(layers "F.Cu" "F.Mask" "F.Paste")
			(net "P12V_STBY_VIN_U81")
		)
		(pad "2" smd rect
			(at 0 0.9652 180)
			(size 1.397 1.143)
			(layers "F.Cu" "F.Mask" "F.Paste")
			(net "GND")
		)
	)
	(footprint ""
		(layer "F.Cu")
		(at 51.689 -131.7244)
		(property "Reference" "R148"
			(at 0 0 0)
			(layer "F.SilkS")
			(hide yes)
			(effects
				(font
					(size 1.27 1.27)
				)
			)
		)
		(property "Value" "100KR2F-L1-GP"
			(at 0.064008 -3.993896 0)
			(unlocked yes)
			(layer "F.Fab")
			(hide yes)
			(effects
				(font
					(size 1.016 1.016)
					(thickness 0.1524)
				)
			)
		)
		(property "Device Type" "R402H16"
			(at 0.064008 -5.517896 0)
			(unlocked yes)
			(layer "F.Fab")
			(hide yes)
			(effects
				(font
					(size 1.016 1.016)
					(thickness 0.1524)
				)
			)
		)
		(duplicate_pad_numbers_are_jumpers no)
		(fp_line
			(start -0.508 -0.9398)
			(end -0.508 0.9398)
			(stroke
				(width 0.1524)
				(type default)
			)
			(layer "F.SilkS")
		)
		(fp_line
			(start 0.508 -0.9398)
			(end -0.508 -0.9398)
			(stroke
				(width 0.1524)
				(type default)
			)
			(layer "F.SilkS")
		)
		(fp_rect
			(start -0.508 0.9398)
			(end 0.508 -0.9398)
			(stroke
				(width 0)
				(type default)
			)
			(fill no)
			(layer "F.CrtYd")
		)
		(fp_rect
			(start -0.508 0.9398)
			(end 0.508 -0.9398)
			(stroke
				(width 0)
				(type default)
			)
			(fill no)
			(layer "F.Fab")
		)
		(pad "1" smd custom
			(at 0 -0.4445)
			(size 0.1397 0.1397)
			(layers "F.Cu" "F.Mask" "F.Paste")
			(net "IRQ_CPU_SERIAL")
			(options
				(clearance outline)
				(anchor circle)
			)
			(primitives
				(gr_poly
					(pts
						(arc
							(start -0.1778 -0.2794)
							(mid -0.249642 -0.249642)
							(end -0.2794 -0.1778)
						)
						(arc
							(start -0.2794 0.1778)
							(mid -0.249642 0.249642)
							(end -0.1778 0.2794)
						)
						(arc
							(start 0.1778 0.2794)
							(mid 0.249642 0.249642)
							(end 0.2794 0.1778)
						)
						(arc
							(start 0.2794 -0.1778)
							(mid 0.249642 -0.249642)
							(end 0.1778 -0.2794)
						)
					)
					(width 0)
					(fill yes)
				)
			)
		)
		(pad "2" smd custom
			(at 0 0.4445)
			(size 0.1397 0.1397)
			(layers "F.Cu" "F.Mask" "F.Paste")
			(net "GND")
			(options
				(clearance outline)
				(anchor circle)
			)
			(primitives
				(gr_poly
					(pts
						(arc
							(start -0.1778 -0.2794)
							(mid -0.249642 -0.249642)
							(end -0.2794 -0.1778)
						)
						(arc
							(start -0.2794 0.1778)
							(mid -0.249642 0.249642)
							(end -0.1778 0.2794)
						)
						(arc
							(start 0.1778 0.2794)
							(mid 0.249642 0.249642)
							(end 0.2794 0.1778)
						)
						(arc
							(start 0.2794 -0.1778)
							(mid 0.249642 -0.249642)
							(end 0.1778 -0.2794)
						)
					)
					(width 0)
					(fill yes)
				)
			)
		)
	)
	(footprint ""
		(layer "F.Cu")
		(at 216.069672 -52.797456 90)
		(property "Reference" "R475"
			(at 0 0 90)
			(layer "F.SilkS")
			(hide yes)
			(effects
				(font
					(size 1.27 1.27)
				)
			)
		)
		(property "Value" "57K6R2D-GP"
			(at 0.064008 -3.993896 90)
			(unlocked yes)
			(layer "F.Fab")
			(hide yes)
			(effects
				(font
					(size 1.016 1.016)
					(thickness 0.1524)
				)
			)
		)
		(property "Device Type" "R402H16"
			(at 0.064008 -5.517896 90)
			(unlocked yes)
			(layer "F.Fab")
			(hide yes)
			(effects
				(font
					(size 1.016 1.016)
					(thickness 0.1524)
				)
			)
		)
		(duplicate_pad_numbers_are_jumpers no)
		(fp_line
			(start 0.508 -0.9398)
			(end -0.508 -0.9398)
			(stroke
				(width 0.1524)
				(type default)
			)
			(layer "F.SilkS")
		)
		(fp_line
			(start -0.508 -0.9398)
			(end -0.508 0.9398)
			(stroke
				(width 0.1524)
				(type default)
			)
			(layer "F.SilkS")
		)
		(fp_rect
			(start -0.508 0.9398)
			(end 0.508 -0.9398)
			(stroke
				(width 0)
				(type default)
			)
			(fill no)
			(layer "F.CrtYd")
		)
		(fp_rect
			(start -0.508 0.9398)
			(end 0.508 -0.9398)
			(stroke
				(width 0)
				(type default)
			)
			(fill no)
			(layer "F.Fab")
		)
		(pad "1" smd custom
			(at 0 -0.4445 90)
			(size 0.1397 0.1397)
			(layers "F.Cu" "F.Mask" "F.Paste")
			(net "AGND_P5V")
			(options
				(clearance outline)
				(anchor circle)
			)
			(primitives
				(gr_poly
					(pts
						(arc
							(start -0.1778 -0.2794)
							(mid -0.249642 -0.249642)
							(end -0.2794 -0.1778)
						)
						(arc
							(start -0.2794 0.1778)
							(mid -0.249642 0.249642)
							(end -0.1778 0.2794)
						)
						(arc
							(start 0.1778 0.2794)
							(mid 0.249642 0.249642)
							(end 0.2794 0.1778)
						)
						(arc
							(start 0.2794 -0.1778)
							(mid 0.249642 -0.249642)
							(end 0.1778 -0.2794)
						)
					)
					(width 0)
					(fill yes)
				)
			)
		)
		(pad "2" smd custom
			(at 0 0.4445 90)
			(size 0.1397 0.1397)
			(layers "F.Cu" "F.Mask" "F.Paste")
			(net "P5V_TRIP")
			(options
				(clearance outline)
				(anchor circle)
			)
			(primitives
				(gr_poly
					(pts
						(arc
							(start -0.1778 -0.2794)
							(mid -0.249642 -0.249642)
							(end -0.2794 -0.1778)
						)
						(arc
							(start -0.2794 0.1778)
							(mid -0.249642 0.249642)
							(end -0.1778 0.2794)
						)
						(arc
							(start 0.1778 0.2794)
							(mid 0.249642 0.249642)
							(end 0.2794 0.1778)
						)
						(arc
							(start 0.2794 -0.1778)
							(mid 0.249642 -0.249642)
							(end 0.1778 -0.2794)
						)
					)
					(width 0)
					(fill yes)
				)
			)
		)
	)
	(footprint ""
		(layer "F.Cu")
		(at 86.671404 -134.673086)
		(property "Reference" "R134"
			(at 0 0 0)
			(layer "F.SilkS")
			(hide yes)
			(effects
				(font
					(size 1.27 1.27)
				)
			)
		)
		(property "Value" "8K2R2J-3-GP"
			(at 0.064008 -3.993896 0)
			(unlocked yes)
			(layer "F.Fab")
			(hide yes)
			(effects
				(font
					(size 1.016 1.016)
					(thickness 0.1524)
				)
			)
		)
		(property "Device Type" "R402H16"
			(at 0.064008 -5.517896 0)
			(unlocked yes)
			(layer "F.Fab")
			(hide yes)
			(effects
				(font
					(size 1.016 1.016)
					(thickness 0.1524)
				)
			)
		)
		(duplicate_pad_numbers_are_jumpers no)
		(fp_line
			(start -0.508 -0.9398)
			(end -0.508 0.9398)
			(stroke
				(width 0.1524)
				(type default)
			)
			(layer "F.SilkS")
		)
		(fp_line
			(start 0.508 -0.9398)
			(end -0.508 -0.9398)
			(stroke
				(width 0.1524)
				(type default)
			)
			(layer "F.SilkS")
		)
		(fp_rect
			(start -0.508 0.9398)
			(end 0.508 -0.9398)
			(stroke
				(width 0)
				(type default)
			)
			(fill no)
			(layer "F.CrtYd")
		)
		(fp_rect
			(start -0.508 0.9398)
			(end 0.508 -0.9398)
			(stroke
				(width 0)
				(type default)
			)
			(fill no)
			(layer "F.Fab")
		)
		(pad "1" smd custom
			(at 0 -0.4445)
			(size 0.1397 0.1397)
			(layers "F.Cu" "F.Mask" "F.Paste")
			(net "P3V3_STBY")
			(options
				(clearance outline)
				(anchor circle)
			)
			(primitives
				(gr_poly
					(pts
						(arc
							(start -0.1778 -0.2794)
							(mid -0.249642 -0.249642)
							(end -0.2794 -0.1778)
						)
						(arc
							(start -0.2794 0.1778)
							(mid -0.249642 0.249642)
							(end -0.1778 0.2794)
						)
						(arc
							(start 0.1778 0.2794)
							(mid 0.249642 0.249642)
							(end 0.2794 0.1778)
						)
						(arc
							(start 0.2794 -0.1778)
							(mid 0.249642 -0.249642)
							(end 0.1778 -0.2794)
						)
					)
					(width 0)
					(fill yes)
				)
			)
		)
		(pad "2" smd custom
			(at 0 0.4445)
			(size 0.1397 0.1397)
			(layers "F.Cu" "F.Mask" "F.Paste")
			(net "EEPROM_A1")
			(options
				(clearance outline)
				(anchor circle)
			)
			(primitives
				(gr_poly
					(pts
						(arc
							(start -0.1778 -0.2794)
							(mid -0.249642 -0.249642)
							(end -0.2794 -0.1778)
						)
						(arc
							(start -0.2794 0.1778)
							(mid -0.249642 0.249642)
							(end -0.1778 0.2794)
						)
						(arc
							(start 0.1778 0.2794)
							(mid 0.249642 0.249642)
							(end 0.2794 0.1778)
						)
						(arc
							(start 0.2794 -0.1778)
							(mid 0.249642 -0.249642)
							(end 0.1778 -0.2794)
						)
					)
					(width 0)
					(fill yes)
				)
			)
		)
	)
	(footprint ""
		(layer "F.Cu")
		(at 60.4774 -139.9032)
		(property "Reference" "TP75"
			(at 0 0 0)
			(layer "F.SilkS")
			(hide yes)
			(effects
				(font
					(size 1.27 1.27)
				)
			)
		)
		(property "Value" "TPAD28-2-GP"
			(at -0.0127 -1.6637 0)
			(unlocked yes)
			(layer "F.Fab")
			(hide yes)
			(effects
				(font
					(size 1.016 1.016)
					(thickness 0.1524)
				)
			)
		)
		(property "Device Type" "TPAD28"
			(at -0.0127 -3.1877 0)
			(unlocked yes)
			(layer "F.Fab")
			(hide yes)
			(effects
				(font
					(size 1.016 1.016)
					(thickness 0.1524)
				)
			)
		)
		(duplicate_pad_numbers_are_jumpers no)
		(fp_poly
			(pts
				(arc
					(start 0.3556 0)
					(mid -0.3556 0)
					(end 0.3556 0)
				)
			)
			(stroke
				(width 0)
				(type default)
			)
			(fill no)
			(layer "F.CrtYd")
		)
		(fp_poly
			(pts
				(arc
					(start 0.6096 0)
					(mid -0.6096 0)
					(end 0.6096 0)
				)
			)
			(stroke
				(width 0)
				(type default)
			)
			(fill no)
			(layer "F.Fab")
		)
		(pad "1" smd circle
			(at 0 0)
			(size 0.7112 0.7112)
			(layers "F.Cu" "F.Mask" "F.Paste")
			(net "TP_BMC_GPIOI6")
		)
	)
	(footprint ""
		(layer "F.Cu")
		(at 53.0098 -160.1724 -90)
		(property "Reference" "C86"
			(at 0 0 270)
			(layer "F.SilkS")
			(hide yes)
			(effects
				(font
					(size 1.27 1.27)
				)
			)
		)
		(property "Value" "SCD1U16V2KX-3GP"
			(at 1.1811 -2.7051 270)
			(unlocked yes)
			(layer "F.Fab")
			(hide yes)
			(effects
				(font
					(size 1.016 1.016)
					(thickness 0.1524)
				)
			)
		)
		(property "Device Type" "C402H22"
			(at 1.1811 -4.2291 270)
			(unlocked yes)
			(layer "F.Fab")
			(hide yes)
			(effects
				(font
					(size 1.016 1.016)
					(thickness 0.1524)
				)
			)
		)
		(duplicate_pad_numbers_are_jumpers no)
		(fp_rect
			(start -0.4318 0.9525)
			(end 0.4318 -0.9525)
			(stroke
				(width 0)
				(type default)
			)
			(fill no)
			(layer "F.CrtYd")
		)
		(fp_rect
			(start -0.4318 0.9525)
			(end 0.4318 -0.9525)
			(stroke
				(width 0)
				(type default)
			)
			(fill no)
			(layer "F.Fab")
		)
		(pad "1" smd custom
			(at 0 -0.4445 270)
			(size 0.1524 0.1524)
			(layers "F.Cu" "F.Mask" "F.Paste")
			(net "ADCVREFFN")
			(options
				(clearance outline)
				(anchor circle)
			)
			(primitives
				(gr_poly
					(pts
						(arc
							(start 0.3048 -0.2032)
							(mid 0.275042 -0.275042)
							(end 0.2032 -0.3048)
						)
						(arc
							(start -0.2032 -0.3048)
							(mid -0.275042 -0.275042)
							(end -0.3048 -0.2032)
						)
						(arc
							(start -0.3048 0.2032)
							(mid -0.275042 0.275042)
							(end -0.2032 0.3048)
						)
						(arc
							(start 0.2032 0.3048)
							(mid 0.275042 0.275042)
							(end 0.3048 0.2032)
						)
					)
					(width 0)
					(fill yes)
				)
			)
		)
		(pad "2" smd custom
			(at 0 0.4445 270)
			(size 0.1524 0.1524)
			(layers "F.Cu" "F.Mask" "F.Paste")
			(net "ADCVREFFP")
			(options
				(clearance outline)
				(anchor circle)
			)
			(primitives
				(gr_poly
					(pts
						(arc
							(start 0.3048 -0.2032)
							(mid 0.275042 -0.275042)
							(end 0.2032 -0.3048)
						)
						(arc
							(start -0.2032 -0.3048)
							(mid -0.275042 -0.275042)
							(end -0.3048 -0.2032)
						)
						(arc
							(start -0.3048 0.2032)
							(mid -0.275042 0.275042)
							(end -0.2032 0.3048)
						)
						(arc
							(start 0.2032 0.3048)
							(mid 0.275042 0.275042)
							(end 0.3048 0.2032)
						)
					)
					(width 0)
					(fill yes)
				)
			)
		)
	)
	(footprint ""
		(layer "F.Cu")
		(at 191.7192 -134.2898)
		(property "Reference" "R845"
			(at 0 0 0)
			(layer "F.SilkS")
			(hide yes)
			(effects
				(font
					(size 1.27 1.27)
				)
			)
		)
		(property "Value" "4K7R2F-GP"
			(at 0.064008 -3.993896 0)
			(unlocked yes)
			(layer "F.Fab")
			(hide yes)
			(effects
				(font
					(size 1.016 1.016)
					(thickness 0.1524)
				)
			)
		)
		(property "Device Type" "R402H16"
			(at 0.064008 -5.517896 0)
			(unlocked yes)
			(layer "F.Fab")
			(hide yes)
			(effects
				(font
					(size 1.016 1.016)
					(thickness 0.1524)
				)
			)
		)
		(duplicate_pad_numbers_are_jumpers no)
		(fp_line
			(start -0.508 -0.9398)
			(end -0.508 0.9398)
			(stroke
				(width 0.1524)
				(type default)
			)
			(layer "F.SilkS")
		)
		(fp_line
			(start 0.508 -0.9398)
			(end -0.508 -0.9398)
			(stroke
				(width 0.1524)
				(type default)
			)
			(layer "F.SilkS")
		)
		(fp_rect
			(start -0.508 0.9398)
			(end 0.508 -0.9398)
			(stroke
				(width 0)
				(type default)
			)
			(fill no)
			(layer "F.CrtYd")
		)
		(fp_rect
			(start -0.508 0.9398)
			(end 0.508 -0.9398)
			(stroke
				(width 0)
				(type default)
			)
			(fill no)
			(layer "F.Fab")
		)
		(pad "1" smd custom
			(at 0 -0.4445)
			(size 0.1397 0.1397)
			(layers "F.Cu" "F.Mask" "F.Paste")
			(net "P3V3_STBY")
			(options
				(clearance outline)
				(anchor circle)
			)
			(primitives
				(gr_poly
					(pts
						(arc
							(start -0.1778 -0.2794)
							(mid -0.249642 -0.249642)
							(end -0.2794 -0.1778)
						)
						(arc
							(start -0.2794 0.1778)
							(mid -0.249642 0.249642)
							(end -0.1778 0.2794)
						)
						(arc
							(start 0.1778 0.2794)
							(mid 0.249642 0.249642)
							(end 0.2794 0.1778)
						)
						(arc
							(start 0.2794 -0.1778)
							(mid 0.249642 -0.249642)
							(end 0.1778 -0.2794)
						)
					)
					(width 0)
					(fill yes)
				)
			)
		)
		(pad "2" smd custom
			(at 0 0.4445)
			(size 0.1397 0.1397)
			(layers "F.Cu" "F.Mask" "F.Paste")
			(net "M2_1_ACTIVE_N")
			(options
				(clearance outline)
				(anchor circle)
			)
			(primitives
				(gr_poly
					(pts
						(arc
							(start -0.1778 -0.2794)
							(mid -0.249642 -0.249642)
							(end -0.2794 -0.1778)
						)
						(arc
							(start -0.2794 0.1778)
							(mid -0.249642 0.249642)
							(end -0.1778 0.2794)
						)
						(arc
							(start 0.1778 0.2794)
							(mid 0.249642 0.249642)
							(end 0.2794 0.1778)
						)
						(arc
							(start 0.2794 -0.1778)
							(mid 0.249642 -0.249642)
							(end 0.1778 -0.2794)
						)
					)
					(width 0)
					(fill yes)
				)
			)
		)
	)
	(footprint ""
		(layer "F.Cu")
		(at 165.629082 -134.66953 90)
		(property "Reference" "R822"
			(at 0 0 90)
			(layer "F.SilkS")
			(hide yes)
			(effects
				(font
					(size 1.27 1.27)
				)
			)
		)
		(property "Value" "0R2J-2-GP"
			(at 0.064008 -3.993896 90)
			(unlocked yes)
			(layer "F.Fab")
			(hide yes)
			(effects
				(font
					(size 1.016 1.016)
					(thickness 0.1524)
				)
			)
		)
		(property "Device Type" "R402H16"
			(at 0.064008 -5.517896 90)
			(unlocked yes)
			(layer "F.Fab")
			(hide yes)
			(effects
				(font
					(size 1.016 1.016)
					(thickness 0.1524)
				)
			)
		)
		(duplicate_pad_numbers_are_jumpers no)
		(fp_line
			(start 0.508 -0.9398)
			(end -0.508 -0.9398)
			(stroke
				(width 0.1524)
				(type default)
			)
			(layer "F.SilkS")
		)
		(fp_line
			(start -0.508 -0.9398)
			(end -0.508 0.9398)
			(stroke
				(width 0.1524)
				(type default)
			)
			(layer "F.SilkS")
		)
		(fp_rect
			(start -0.508 0.9398)
			(end 0.508 -0.9398)
			(stroke
				(width 0)
				(type default)
			)
			(fill no)
			(layer "F.CrtYd")
		)
		(fp_rect
			(start -0.508 0.9398)
			(end 0.508 -0.9398)
			(stroke
				(width 0)
				(type default)
			)
			(fill no)
			(layer "F.Fab")
		)
		(pad "1" smd custom
			(at 0 -0.4445 90)
			(size 0.1397 0.1397)
			(layers "F.Cu" "F.Mask" "F.Paste")
			(net "M2_2_PRESENT_N_R")
			(options
				(clearance outline)
				(anchor circle)
			)
			(primitives
				(gr_poly
					(pts
						(arc
							(start -0.1778 -0.2794)
							(mid -0.249642 -0.249642)
							(end -0.2794 -0.1778)
						)
						(arc
							(start -0.2794 0.1778)
							(mid -0.249642 0.249642)
							(end -0.1778 0.2794)
						)
						(arc
							(start 0.1778 0.2794)
							(mid 0.249642 0.249642)
							(end 0.2794 0.1778)
						)
						(arc
							(start 0.2794 -0.1778)
							(mid 0.249642 -0.249642)
							(end 0.1778 -0.2794)
						)
					)
					(width 0)
					(fill yes)
				)
			)
		)
		(pad "2" smd custom
			(at 0 0.4445 90)
			(size 0.1397 0.1397)
			(layers "F.Cu" "F.Mask" "F.Paste")
			(net "GND")
			(options
				(clearance outline)
				(anchor circle)
			)
			(primitives
				(gr_poly
					(pts
						(arc
							(start -0.1778 -0.2794)
							(mid -0.249642 -0.249642)
							(end -0.2794 -0.1778)
						)
						(arc
							(start -0.2794 0.1778)
							(mid -0.249642 0.249642)
							(end -0.1778 0.2794)
						)
						(arc
							(start 0.1778 0.2794)
							(mid 0.249642 0.249642)
							(end 0.2794 0.1778)
						)
						(arc
							(start 0.2794 -0.1778)
							(mid 0.249642 -0.249642)
							(end 0.1778 -0.2794)
						)
					)
					(width 0)
					(fill yes)
				)
			)
		)
	)
	(footprint ""
		(layer "F.Cu")
		(at 53.4416 -125.8062 90)
		(property "Reference" "R269"
			(at 0 0 90)
			(layer "F.SilkS")
			(hide yes)
			(effects
				(font
					(size 1.27 1.27)
				)
			)
		)
		(property "Value" "2K2R2J-2-GP"
			(at 0.064008 -3.993896 90)
			(unlocked yes)
			(layer "F.Fab")
			(hide yes)
			(effects
				(font
					(size 1.016 1.016)
					(thickness 0.1524)
				)
			)
		)
		(property "Device Type" "R402H16"
			(at 0.064008 -5.517896 90)
			(unlocked yes)
			(layer "F.Fab")
			(hide yes)
			(effects
				(font
					(size 1.016 1.016)
					(thickness 0.1524)
				)
			)
		)
		(duplicate_pad_numbers_are_jumpers no)
		(fp_line
			(start 0.508 -0.9398)
			(end -0.508 -0.9398)
			(stroke
				(width 0.1524)
				(type default)
			)
			(layer "F.SilkS")
		)
		(fp_line
			(start -0.508 -0.9398)
			(end -0.508 0.9398)
			(stroke
				(width 0.1524)
				(type default)
			)
			(layer "F.SilkS")
		)
		(fp_rect
			(start -0.508 0.9398)
			(end 0.508 -0.9398)
			(stroke
				(width 0)
				(type default)
			)
			(fill no)
			(layer "F.CrtYd")
		)
		(fp_rect
			(start -0.508 0.9398)
			(end 0.508 -0.9398)
			(stroke
				(width 0)
				(type default)
			)
			(fill no)
			(layer "F.Fab")
		)
		(pad "1" smd custom
			(at 0 -0.4445 90)
			(size 0.1397 0.1397)
			(layers "F.Cu" "F.Mask" "F.Paste")
			(net "P3V3_STBY")
			(options
				(clearance outline)
				(anchor circle)
			)
			(primitives
				(gr_poly
					(pts
						(arc
							(start -0.1778 -0.2794)
							(mid -0.249642 -0.249642)
							(end -0.2794 -0.1778)
						)
						(arc
							(start -0.2794 0.1778)
							(mid -0.249642 0.249642)
							(end -0.1778 0.2794)
						)
						(arc
							(start 0.1778 0.2794)
							(mid 0.249642 0.249642)
							(end 0.2794 0.1778)
						)
						(arc
							(start 0.2794 -0.1778)
							(mid 0.249642 -0.249642)
							(end 0.1778 -0.2794)
						)
					)
					(width 0)
					(fill yes)
				)
			)
		)
		(pad "2" smd custom
			(at 0 0.4445 90)
			(size 0.1397 0.1397)
			(layers "F.Cu" "F.Mask" "F.Paste")
			(net "FLA1_WP_N")
			(options
				(clearance outline)
				(anchor circle)
			)
			(primitives
				(gr_poly
					(pts
						(arc
							(start -0.1778 -0.2794)
							(mid -0.249642 -0.249642)
							(end -0.2794 -0.1778)
						)
						(arc
							(start -0.2794 0.1778)
							(mid -0.249642 0.249642)
							(end -0.1778 0.2794)
						)
						(arc
							(start 0.1778 0.2794)
							(mid 0.249642 0.249642)
							(end 0.2794 0.1778)
						)
						(arc
							(start 0.2794 -0.1778)
							(mid 0.249642 -0.249642)
							(end 0.1778 -0.2794)
						)
					)
					(width 0)
					(fill yes)
				)
			)
		)
	)
	(footprint ""
		(layer "F.Cu")
		(at 202.2094 -99.441)
		(property "Reference" "R558"
			(at 0 0 0)
			(layer "F.SilkS")
			(hide yes)
			(effects
				(font
					(size 1.27 1.27)
				)
			)
		)
		(property "Value" "0R2J-2-GP"
			(at 0.064008 -3.993896 0)
			(unlocked yes)
			(layer "F.Fab")
			(hide yes)
			(effects
				(font
					(size 1.016 1.016)
					(thickness 0.1524)
				)
			)
		)
		(property "Device Type" "R402H16"
			(at 0.064008 -5.517896 0)
			(unlocked yes)
			(layer "F.Fab")
			(hide yes)
			(effects
				(font
					(size 1.016 1.016)
					(thickness 0.1524)
				)
			)
		)
		(duplicate_pad_numbers_are_jumpers no)
		(fp_line
			(start -0.508 -0.9398)
			(end -0.508 0.9398)
			(stroke
				(width 0.1524)
				(type default)
			)
			(layer "F.SilkS")
		)
		(fp_line
			(start 0.508 -0.9398)
			(end -0.508 -0.9398)
			(stroke
				(width 0.1524)
				(type default)
			)
			(layer "F.SilkS")
		)
		(fp_rect
			(start -0.508 0.9398)
			(end 0.508 -0.9398)
			(stroke
				(width 0)
				(type default)
			)
			(fill no)
			(layer "F.CrtYd")
		)
		(fp_rect
			(start -0.508 0.9398)
			(end 0.508 -0.9398)
			(stroke
				(width 0)
				(type default)
			)
			(fill no)
			(layer "F.Fab")
		)
		(pad "1" smd custom
			(at 0 -0.4445)
			(size 0.1397 0.1397)
			(layers "F.Cu" "F.Mask" "F.Paste")
			(net "TEMP_2_SDA")
			(options
				(clearance outline)
				(anchor circle)
			)
			(primitives
				(gr_poly
					(pts
						(arc
							(start -0.1778 -0.2794)
							(mid -0.249642 -0.249642)
							(end -0.2794 -0.1778)
						)
						(arc
							(start -0.2794 0.1778)
							(mid -0.249642 0.249642)
							(end -0.1778 0.2794)
						)
						(arc
							(start 0.1778 0.2794)
							(mid 0.249642 0.249642)
							(end 0.2794 0.1778)
						)
						(arc
							(start 0.2794 -0.1778)
							(mid 0.249642 -0.249642)
							(end 0.1778 -0.2794)
						)
					)
					(width 0)
					(fill yes)
				)
			)
		)
		(pad "2" smd custom
			(at 0 0.4445)
			(size 0.1397 0.1397)
			(layers "F.Cu" "F.Mask" "F.Paste")
			(net "I2C_IOM_SDA")
			(options
				(clearance outline)
				(anchor circle)
			)
			(primitives
				(gr_poly
					(pts
						(arc
							(start -0.1778 -0.2794)
							(mid -0.249642 -0.249642)
							(end -0.2794 -0.1778)
						)
						(arc
							(start -0.2794 0.1778)
							(mid -0.249642 0.249642)
							(end -0.1778 0.2794)
						)
						(arc
							(start 0.1778 0.2794)
							(mid 0.249642 0.249642)
							(end 0.2794 0.1778)
						)
						(arc
							(start 0.2794 -0.1778)
							(mid 0.249642 -0.249642)
							(end 0.1778 -0.2794)
						)
					)
					(width 0)
					(fill yes)
				)
			)
		)
	)
	(footprint ""
		(layer "F.Cu")
		(at 155.716478 -6.088634 -90)
		(property "Reference" "R520"
			(at 0 0 270)
			(layer "F.SilkS")
			(hide yes)
			(effects
				(font
					(size 1.27 1.27)
				)
			)
		)
		(property "Value" "3D01R5F-GP"
			(at 0 -8.953754 270)
			(unlocked yes)
			(layer "F.Fab")
			(hide yes)
			(effects
				(font
					(size 1.27 1.016)
					(thickness 0.1524)
				)
			)
		)
		(property "Device Type" "R805H24"
			(at 0 -10.629646 270)
			(unlocked yes)
			(layer "F.Fab")
			(hide yes)
			(effects
				(font
					(size 1.27 1.016)
					(thickness 0.1524)
				)
			)
		)
		(duplicate_pad_numbers_are_jumpers no)
		(fp_line
			(start -0.888746 1.7018)
			(end 0.888746 1.7018)
			(stroke
				(width 0.1524)
				(type default)
			)
			(layer "F.SilkS")
		)
		(fp_line
			(start 0.888746 1.7018)
			(end 0.889 -0.508)
			(stroke
				(width 0.1524)
				(type default)
			)
			(layer "F.SilkS")
		)
		(fp_line
			(start -0.889 0.0762)
			(end -0.888746 1.7018)
			(stroke
				(width 0.1524)
				(type default)
			)
			(layer "F.SilkS")
		)
		(fp_line
			(start -0.888746 -1.7018)
			(end -0.889 0.2794)
			(stroke
				(width 0.1524)
				(type default)
			)
			(layer "F.SilkS")
		)
		(fp_line
			(start 0.888746 -1.7018)
			(end 0.889 -0.381)
			(stroke
				(width 0.1524)
				(type default)
			)
			(layer "F.SilkS")
		)
		(fp_line
			(start 0.888746 -1.7018)
			(end -0.888746 -1.7018)
			(stroke
				(width 0.1524)
				(type default)
			)
			(layer "F.SilkS")
		)
		(fp_poly
			(pts
				(xy 0.9652 -1.778) (xy 0.9652 1.778) (xy -0.9652 1.778) (xy -0.9652 -1.778)
			)
			(stroke
				(width 0)
				(type default)
			)
			(fill no)
			(layer "F.CrtYd")
		)
		(fp_rect
			(start -0.9652 1.778)
			(end 0.9652 -1.778)
			(stroke
				(width 0)
				(type default)
			)
			(fill no)
			(layer "F.Fab")
		)
		(pad "1" smd rect
			(at 0 -0.9652 270)
			(size 1.397 1.143)
			(layers "F.Cu" "F.Mask" "F.Paste")
			(net "P1V8_STBY_SNB")
		)
		(pad "2" smd rect
			(at 0 0.9652 270)
			(size 1.397 1.143)
			(layers "F.Cu" "F.Mask" "F.Paste")
			(net "GND")
		)
	)
	(footprint ""
		(layer "F.Cu")
		(at 24.452072 -15.81277 -90)
		(property "Reference" "C528"
			(at 0 0 270)
			(layer "F.SilkS")
			(hide yes)
			(effects
				(font
					(size 1.27 1.27)
				)
			)
		)
		(property "Value" "SC1000P2KV6KX-GP-U"
			(at 0.0508 -3.5052 270)
			(unlocked yes)
			(layer "F.Fab")
			(hide yes)
			(effects
				(font
					(size 1.016 1.016)
					(thickness 0.1524)
				)
			)
		)
		(property "Device Type" "C1206H58"
			(at 0.0508 -5.0292 270)
			(unlocked yes)
			(layer "F.Fab")
			(hide yes)
			(effects
				(font
					(size 1.016 1.016)
					(thickness 0.1524)
				)
			)
		)
		(duplicate_pad_numbers_are_jumpers no)
		(fp_line
			(start -1.016 2.2352)
			(end -1.016 0.8128)
			(stroke
				(width 0.1524)
				(type default)
			)
			(layer "F.SilkS")
		)
		(fp_line
			(start 1.016 2.2352)
			(end -1.016 2.2352)
			(stroke
				(width 0.1524)
				(type default)
			)
			(layer "F.SilkS")
		)
		(fp_line
			(start 1.016 0.8382)
			(end 1.016 2.2352)
			(stroke
				(width 0.1524)
				(type default)
			)
			(layer "F.SilkS")
		)
		(fp_line
			(start -1.016 -2.2352)
			(end -1.016 -0.8382)
			(stroke
				(width 0.1524)
				(type default)
			)
			(layer "F.SilkS")
		)
		(fp_line
			(start 1.016 -2.2352)
			(end 1.016 -0.8382)
			(stroke
				(width 0.1524)
				(type default)
			)
			(layer "F.SilkS")
		)
		(fp_line
			(start 1.016 -2.2352)
			(end -1.016 -2.2352)
			(stroke
				(width 0.1524)
				(type default)
			)
			(layer "F.SilkS")
		)
		(fp_rect
			(start -1.0922 2.3114)
			(end 1.0922 -2.3114)
			(stroke
				(width 0)
				(type default)
			)
			(fill no)
			(layer "F.CrtYd")
		)
		(fp_poly
			(pts
				(xy -1.0922 -2.3114) (xy 1.0922 -2.3114) (xy 1.0922 2.3114) (xy -1.0922 2.3114)
			)
			(stroke
				(width 0)
				(type default)
			)
			(fill no)
			(layer "F.Fab")
		)
		(pad "1" smd rect
			(at 0 -1.397 270)
			(size 1.651 1.27)
			(layers "F.Cu" "F.Mask" "F.Paste")
			(net "PWR_BTN_GND")
		)
		(pad "2" smd rect
			(at 0 1.397 270)
			(size 1.651 1.27)
			(layers "F.Cu" "F.Mask" "F.Paste")
			(net "GND")
		)
	)
	(footprint ""
		(layer "F.Cu")
		(at 68.6054 -124.333 -90)
		(property "Reference" "R267"
			(at 0 0 270)
			(layer "F.SilkS")
			(hide yes)
			(effects
				(font
					(size 1.27 1.27)
				)
			)
		)
		(property "Value" "2K2R2J-2-GP"
			(at 0.064008 -3.993896 270)
			(unlocked yes)
			(layer "F.Fab")
			(hide yes)
			(effects
				(font
					(size 1.016 1.016)
					(thickness 0.1524)
				)
			)
		)
		(property "Device Type" "R402H16"
			(at 0.064008 -5.517896 270)
			(unlocked yes)
			(layer "F.Fab")
			(hide yes)
			(effects
				(font
					(size 1.016 1.016)
					(thickness 0.1524)
				)
			)
		)
		(duplicate_pad_numbers_are_jumpers no)
		(fp_line
			(start -0.508 -0.9398)
			(end -0.508 0.9398)
			(stroke
				(width 0.1524)
				(type default)
			)
			(layer "F.SilkS")
		)
		(fp_line
			(start 0.508 -0.9398)
			(end -0.508 -0.9398)
			(stroke
				(width 0.1524)
				(type default)
			)
			(layer "F.SilkS")
		)
		(fp_rect
			(start -0.508 0.9398)
			(end 0.508 -0.9398)
			(stroke
				(width 0)
				(type default)
			)
			(fill no)
			(layer "F.CrtYd")
		)
		(fp_rect
			(start -0.508 0.9398)
			(end 0.508 -0.9398)
			(stroke
				(width 0)
				(type default)
			)
			(fill no)
			(layer "F.Fab")
		)
		(pad "1" smd custom
			(at 0 -0.4445 270)
			(size 0.1397 0.1397)
			(layers "F.Cu" "F.Mask" "F.Paste")
			(net "P3V3_STBY")
			(options
				(clearance outline)
				(anchor circle)
			)
			(primitives
				(gr_poly
					(pts
						(arc
							(start -0.1778 -0.2794)
							(mid -0.249642 -0.249642)
							(end -0.2794 -0.1778)
						)
						(arc
							(start -0.2794 0.1778)
							(mid -0.249642 0.249642)
							(end -0.1778 0.2794)
						)
						(arc
							(start 0.1778 0.2794)
							(mid 0.249642 0.249642)
							(end 0.2794 0.1778)
						)
						(arc
							(start 0.2794 -0.1778)
							(mid 0.249642 -0.249642)
							(end 0.1778 -0.2794)
						)
					)
					(width 0)
					(fill yes)
				)
			)
		)
		(pad "2" smd custom
			(at 0 0.4445 270)
			(size 0.1397 0.1397)
			(layers "F.Cu" "F.Mask" "F.Paste")
			(net "FLA_CS_1_R")
			(options
				(clearance outline)
				(anchor circle)
			)
			(primitives
				(gr_poly
					(pts
						(arc
							(start -0.1778 -0.2794)
							(mid -0.249642 -0.249642)
							(end -0.2794 -0.1778)
						)
						(arc
							(start -0.2794 0.1778)
							(mid -0.249642 0.249642)
							(end -0.1778 0.2794)
						)
						(arc
							(start 0.1778 0.2794)
							(mid 0.249642 0.249642)
							(end 0.2794 0.1778)
						)
						(arc
							(start 0.2794 -0.1778)
							(mid 0.249642 -0.249642)
							(end 0.1778 -0.2794)
						)
					)
					(width 0)
					(fill yes)
				)
			)
		)
	)
	(footprint ""
		(layer "F.Cu")
		(at 16.041116 -162.5473 -90)
		(property "Reference" "R530"
			(at 0 0 270)
			(layer "F.SilkS")
			(hide yes)
			(effects
				(font
					(size 1.27 1.27)
				)
			)
		)
		(property "Value" "2K49R2F-GP"
			(at 0.064008 -3.993896 270)
			(unlocked yes)
			(layer "F.Fab")
			(hide yes)
			(effects
				(font
					(size 1.016 1.016)
					(thickness 0.1524)
				)
			)
		)
		(property "Device Type" "R402H16"
			(at 0.064008 -5.517896 270)
			(unlocked yes)
			(layer "F.Fab")
			(hide yes)
			(effects
				(font
					(size 1.016 1.016)
					(thickness 0.1524)
				)
			)
		)
		(duplicate_pad_numbers_are_jumpers no)
		(fp_line
			(start -0.508 -0.9398)
			(end -0.508 0.9398)
			(stroke
				(width 0.1524)
				(type default)
			)
			(layer "F.SilkS")
		)
		(fp_line
			(start 0.508 -0.9398)
			(end -0.508 -0.9398)
			(stroke
				(width 0.1524)
				(type default)
			)
			(layer "F.SilkS")
		)
		(fp_rect
			(start -0.508 0.9398)
			(end 0.508 -0.9398)
			(stroke
				(width 0)
				(type default)
			)
			(fill no)
			(layer "F.CrtYd")
		)
		(fp_rect
			(start -0.508 0.9398)
			(end 0.508 -0.9398)
			(stroke
				(width 0)
				(type default)
			)
			(fill no)
			(layer "F.Fab")
		)
		(pad "1" smd custom
			(at 0 -0.4445 270)
			(size 0.1397 0.1397)
			(layers "F.Cu" "F.Mask" "F.Paste")
			(net "TPS74801_P1V2_STBY_OUT")
			(options
				(clearance outline)
				(anchor circle)
			)
			(primitives
				(gr_poly
					(pts
						(arc
							(start -0.1778 -0.2794)
							(mid -0.249642 -0.249642)
							(end -0.2794 -0.1778)
						)
						(arc
							(start -0.2794 0.1778)
							(mid -0.249642 0.249642)
							(end -0.1778 0.2794)
						)
						(arc
							(start 0.1778 0.2794)
							(mid 0.249642 0.249642)
							(end 0.2794 0.1778)
						)
						(arc
							(start 0.2794 -0.1778)
							(mid 0.249642 -0.249642)
							(end 0.1778 -0.2794)
						)
					)
					(width 0)
					(fill yes)
				)
			)
		)
		(pad "2" smd custom
			(at 0 0.4445 270)
			(size 0.1397 0.1397)
			(layers "F.Cu" "F.Mask" "F.Paste")
			(net "TPS74801_P1V2_STBY_FB")
			(options
				(clearance outline)
				(anchor circle)
			)
			(primitives
				(gr_poly
					(pts
						(arc
							(start -0.1778 -0.2794)
							(mid -0.249642 -0.249642)
							(end -0.2794 -0.1778)
						)
						(arc
							(start -0.2794 0.1778)
							(mid -0.249642 0.249642)
							(end -0.1778 0.2794)
						)
						(arc
							(start 0.1778 0.2794)
							(mid 0.249642 0.249642)
							(end 0.2794 0.1778)
						)
						(arc
							(start 0.2794 -0.1778)
							(mid 0.249642 -0.249642)
							(end 0.1778 -0.2794)
						)
					)
					(width 0)
					(fill yes)
				)
			)
		)
	)
	(footprint ""
		(layer "F.Cu")
		(at 112.86109 -8.726678 -90)
		(property "Reference" "C131"
			(at 0 0 270)
			(layer "F.SilkS")
			(hide yes)
			(effects
				(font
					(size 1.27 1.27)
				)
			)
		)
		(property "Value" "SCD01U25V2KX-3GP"
			(at 1.1811 -2.7051 270)
			(unlocked yes)
			(layer "F.Fab")
			(hide yes)
			(effects
				(font
					(size 1.016 1.016)
					(thickness 0.1524)
				)
			)
		)
		(property "Device Type" "C402H22"
			(at 1.1811 -4.2291 270)
			(unlocked yes)
			(layer "F.Fab")
			(hide yes)
			(effects
				(font
					(size 1.016 1.016)
					(thickness 0.1524)
				)
			)
		)
		(duplicate_pad_numbers_are_jumpers no)
		(fp_rect
			(start -0.4318 0.9525)
			(end 0.4318 -0.9525)
			(stroke
				(width 0)
				(type default)
			)
			(fill no)
			(layer "F.CrtYd")
		)
		(fp_rect
			(start -0.4318 0.9525)
			(end 0.4318 -0.9525)
			(stroke
				(width 0)
				(type default)
			)
			(fill no)
			(layer "F.Fab")
		)
		(pad "1" smd custom
			(at 0 -0.4445 270)
			(size 0.1524 0.1524)
			(layers "F.Cu" "F.Mask" "F.Paste")
			(net "MB0_TIME_R")
			(options
				(clearance outline)
				(anchor circle)
			)
			(primitives
				(gr_poly
					(pts
						(arc
							(start 0.3048 -0.2032)
							(mid 0.275042 -0.275042)
							(end 0.2032 -0.3048)
						)
						(arc
							(start -0.2032 -0.3048)
							(mid -0.275042 -0.275042)
							(end -0.3048 -0.2032)
						)
						(arc
							(start -0.3048 0.2032)
							(mid -0.275042 0.275042)
							(end -0.2032 0.3048)
						)
						(arc
							(start 0.2032 0.3048)
							(mid 0.275042 0.275042)
							(end 0.3048 0.2032)
						)
					)
					(width 0)
					(fill yes)
				)
			)
		)
		(pad "2" smd custom
			(at 0 0.4445 270)
			(size 0.1524 0.1524)
			(layers "F.Cu" "F.Mask" "F.Paste")
			(net "AGND_CURRENT_MON")
			(options
				(clearance outline)
				(anchor circle)
			)
			(primitives
				(gr_poly
					(pts
						(arc
							(start 0.3048 -0.2032)
							(mid 0.275042 -0.275042)
							(end 0.2032 -0.3048)
						)
						(arc
							(start -0.2032 -0.3048)
							(mid -0.275042 -0.275042)
							(end -0.3048 -0.2032)
						)
						(arc
							(start -0.3048 0.2032)
							(mid -0.275042 0.275042)
							(end -0.2032 0.3048)
						)
						(arc
							(start 0.2032 0.3048)
							(mid 0.275042 0.275042)
							(end 0.3048 0.2032)
						)
					)
					(width 0)
					(fill yes)
				)
			)
		)
	)
	(footprint ""
		(layer "F.Cu")
		(at 48.4124 -131.4958 180)
		(property "Reference" "R177"
			(at 0 0 180)
			(layer "F.SilkS")
			(hide yes)
			(effects
				(font
					(size 1.27 1.27)
				)
			)
		)
		(property "Value" "0R2J-2-GP"
			(at 0.064008 -3.993896 180)
			(unlocked yes)
			(layer "F.Fab")
			(hide yes)
			(effects
				(font
					(size 1.016 1.016)
					(thickness 0.1524)
				)
			)
		)
		(property "Device Type" "R402H16"
			(at 0.064008 -5.517896 180)
			(unlocked yes)
			(layer "F.Fab")
			(hide yes)
			(effects
				(font
					(size 1.016 1.016)
					(thickness 0.1524)
				)
			)
		)
		(duplicate_pad_numbers_are_jumpers no)
		(fp_line
			(start 0.508 -0.9398)
			(end -0.508 -0.9398)
			(stroke
				(width 0.1524)
				(type default)
			)
			(layer "F.SilkS")
		)
		(fp_line
			(start -0.508 -0.9398)
			(end -0.508 0.9398)
			(stroke
				(width 0.1524)
				(type default)
			)
			(layer "F.SilkS")
		)
		(fp_rect
			(start -0.508 0.9398)
			(end 0.508 -0.9398)
			(stroke
				(width 0)
				(type default)
			)
			(fill no)
			(layer "F.CrtYd")
		)
		(fp_rect
			(start -0.508 0.9398)
			(end 0.508 -0.9398)
			(stroke
				(width 0)
				(type default)
			)
			(fill no)
			(layer "F.Fab")
		)
		(pad "1" smd custom
			(at 0 -0.4445 180)
			(size 0.1397 0.1397)
			(layers "F.Cu" "F.Mask" "F.Paste")
			(net "I2C_TPM_SCL")
			(options
				(clearance outline)
				(anchor circle)
			)
			(primitives
				(gr_poly
					(pts
						(arc
							(start -0.1778 -0.2794)
							(mid -0.249642 -0.249642)
							(end -0.2794 -0.1778)
						)
						(arc
							(start -0.2794 0.1778)
							(mid -0.249642 0.249642)
							(end -0.1778 0.2794)
						)
						(arc
							(start 0.1778 0.2794)
							(mid 0.249642 0.249642)
							(end 0.2794 0.1778)
						)
						(arc
							(start 0.2794 -0.1778)
							(mid 0.249642 -0.249642)
							(end 0.1778 -0.2794)
						)
					)
					(width 0)
					(fill yes)
				)
			)
		)
		(pad "2" smd custom
			(at 0 0.4445 180)
			(size 0.1397 0.1397)
			(layers "F.Cu" "F.Mask" "F.Paste")
			(net "BMC_SMB14_CLK")
			(options
				(clearance outline)
				(anchor circle)
			)
			(primitives
				(gr_poly
					(pts
						(arc
							(start -0.1778 -0.2794)
							(mid -0.249642 -0.249642)
							(end -0.2794 -0.1778)
						)
						(arc
							(start -0.2794 0.1778)
							(mid -0.249642 0.249642)
							(end -0.1778 0.2794)
						)
						(arc
							(start 0.1778 0.2794)
							(mid 0.249642 0.249642)
							(end 0.2794 0.1778)
						)
						(arc
							(start 0.2794 -0.1778)
							(mid 0.249642 -0.249642)
							(end 0.1778 -0.2794)
						)
					)
					(width 0)
					(fill yes)
				)
			)
		)
	)
	(footprint ""
		(layer "F.Cu")
		(at 224.968054 -71.934832 90)
		(property "Reference" "C658"
			(at 0 0 90)
			(layer "F.SilkS")
			(hide yes)
			(effects
				(font
					(size 1.27 1.27)
				)
			)
		)
		(property "Value" "ST100U6D3VDM-8-GP"
			(at 0 -9.6012 90)
			(unlocked yes)
			(layer "F.Fab")
			(hide yes)
			(effects
				(font
					(size 1.016 1.016)
					(thickness 0.1524)
				)
			)
		)
		(property "Device Type" "CT7343H83"
			(at 0 -11.1252 90)
			(unlocked yes)
			(layer "F.Fab")
			(hide yes)
			(effects
				(font
					(size 1.016 1.016)
					(thickness 0.1524)
				)
			)
		)
		(duplicate_pad_numbers_are_jumpers no)
		(fp_line
			(start 2.286 -4.8768)
			(end -2.286 -4.8768)
			(stroke
				(width 0.1524)
				(type default)
			)
			(layer "F.SilkS")
		)
		(fp_line
			(start -2.286 -4.8768)
			(end -2.286 -2.032)
			(stroke
				(width 0.1524)
				(type default)
			)
			(layer "F.SilkS")
		)
		(fp_line
			(start 2.1082 -4.699)
			(end -2.1082 -4.699)
			(stroke
				(width 0.508)
				(type default)
			)
			(layer "F.SilkS")
		)
		(fp_line
			(start 2.286 -2.032)
			(end 2.286 -4.8768)
			(stroke
				(width 0.1524)
				(type default)
			)
			(layer "F.SilkS")
		)
		(fp_line
			(start 2.286 2.032)
			(end 2.286 4.8768)
			(stroke
				(width 0.1524)
				(type default)
			)
			(layer "F.SilkS")
		)
		(fp_line
			(start 2.286 4.8768)
			(end -2.286 4.8768)
			(stroke
				(width 0.1524)
				(type default)
			)
			(layer "F.SilkS")
		)
		(fp_line
			(start -2.286 4.8768)
			(end -2.286 2.032)
			(stroke
				(width 0.1524)
				(type default)
			)
			(layer "F.SilkS")
		)
		(fp_rect
			(start -2.1463 3.6449)
			(end 2.1463 -3.6449)
			(stroke
				(width 0)
				(type default)
			)
			(fill no)
			(layer "F.CrtYd")
		)
		(fp_poly
			(pts
				(xy -2.54 4.953) (xy -2.54 4.2926) (xy -3.81 4.2926) (xy -3.81 -4.2926) (xy -2.54 -4.2926) (xy -2.54 -4.953)
				(xy 2.54 -4.953) (xy 2.54 -4.2926) (xy 3.81 -4.2926) (xy 3.81 -1.6256) (xy 2.1463 -1.6256) (xy 2.1463 -3.6449)
				(xy -2.1463 -3.6449) (xy -2.1463 3.6449) (xy 2.1463 3.6449) (xy 2.1463 -1.6129) (xy 3.81 -1.6129)
				(xy 3.81 4.2926) (xy 2.54 4.2926) (xy 2.54 4.953)
			)
			(stroke
				(width 0)
				(type default)
			)
			(fill no)
			(layer "F.CrtYd")
		)
		(fp_rect
			(start 2.54 4.2926)
			(end 3.81 -4.2926)
			(stroke
				(width 0)
				(type default)
			)
			(fill no)
			(layer "F.Fab")
		)
		(fp_rect
			(start -3.81 4.2926)
			(end -2.54 -4.2926)
			(stroke
				(width 0)
				(type default)
			)
			(fill no)
			(layer "F.Fab")
		)
		(fp_rect
			(start -2.54 4.953)
			(end 2.54 -4.953)
			(stroke
				(width 0)
				(type default)
			)
			(fill no)
			(layer "F.Fab")
		)
		(pad "1" smd rect
			(at 0 -3.1496 90)
			(size 2.413 2.286)
			(layers "F.Cu" "F.Mask" "F.Paste")
			(net "P3V3_M2")
		)
		(pad "2" smd rect
			(at 0 3.1496 90)
			(size 2.413 2.286)
			(layers "F.Cu" "F.Mask" "F.Paste")
			(net "GND")
		)
		(zone
			(layer "F.Cu")
			(hatch none 0.5)
			(connect_pads
				(clearance 0)
			)
			(min_thickness 0.25)
			(keepout
				(tracks allowed)
				(vias not_allowed)
				(pads allowed)
				(copperpour not_allowed)
				(footprints allowed)
			)
			(placement
				(enabled no)
				(sheetname "")
			)
			(fill
				(thermal_gap 0.5)
				(thermal_bridge_width 0.5)
				(island_removal_mode 0)
			)
			(polygon
				(pts
					(xy 223.278954 -73.446132) (xy 220.370654 -73.446132) (xy 220.370654 -70.423532) (xy 223.266254 -70.423532)
					(xy 223.596454 -70.423532) (xy 223.596454 -73.446132)
				)
			)
		)
		(zone
			(layer "F.Cu")
			(hatch none 0.5)
			(connect_pads
				(clearance 0)
			)
			(min_thickness 0.25)
			(keepout
				(tracks allowed)
				(vias not_allowed)
				(pads allowed)
				(copperpour not_allowed)
				(footprints allowed)
			)
			(placement
				(enabled no)
				(sheetname "")
			)
			(fill
				(thermal_gap 0.5)
				(thermal_bridge_width 0.5)
				(island_removal_mode 0)
			)
			(polygon
				(pts
					(xy 229.565454 -70.423532) (xy 229.565454 -73.446132) (xy 226.669854 -73.446132) (xy 226.339654 -73.446132)
					(xy 226.339654 -70.423532) (xy 226.669854 -70.423532)
				)
			)
		)
	)
	(footprint ""
		(layer "F.Cu")
		(at 24.579072 -14.03477 -90)
		(property "Reference" "R45"
			(at 0 0 270)
			(layer "F.SilkS")
			(hide yes)
			(effects
				(font
					(size 1.27 1.27)
				)
			)
		)
		(property "Value" "1MR2F-GP"
			(at 0.064008 -3.993896 270)
			(unlocked yes)
			(layer "F.Fab")
			(hide yes)
			(effects
				(font
					(size 1.016 1.016)
					(thickness 0.1524)
				)
			)
		)
		(property "Device Type" "R402H16"
			(at 0.064008 -5.517896 270)
			(unlocked yes)
			(layer "F.Fab")
			(hide yes)
			(effects
				(font
					(size 1.016 1.016)
					(thickness 0.1524)
				)
			)
		)
		(duplicate_pad_numbers_are_jumpers no)
		(fp_line
			(start -0.508 -0.9398)
			(end -0.508 0.9398)
			(stroke
				(width 0.1524)
				(type default)
			)
			(layer "F.SilkS")
		)
		(fp_line
			(start 0.508 -0.9398)
			(end -0.508 -0.9398)
			(stroke
				(width 0.1524)
				(type default)
			)
			(layer "F.SilkS")
		)
		(fp_rect
			(start -0.508 0.9398)
			(end 0.508 -0.9398)
			(stroke
				(width 0)
				(type default)
			)
			(fill no)
			(layer "F.CrtYd")
		)
		(fp_rect
			(start -0.508 0.9398)
			(end 0.508 -0.9398)
			(stroke
				(width 0)
				(type default)
			)
			(fill no)
			(layer "F.Fab")
		)
		(pad "1" smd custom
			(at 0 -0.4445 270)
			(size 0.1397 0.1397)
			(layers "F.Cu" "F.Mask" "F.Paste")
			(net "PWR_BTN_GND")
			(options
				(clearance outline)
				(anchor circle)
			)
			(primitives
				(gr_poly
					(pts
						(arc
							(start -0.1778 -0.2794)
							(mid -0.249642 -0.249642)
							(end -0.2794 -0.1778)
						)
						(arc
							(start -0.2794 0.1778)
							(mid -0.249642 0.249642)
							(end -0.1778 0.2794)
						)
						(arc
							(start 0.1778 0.2794)
							(mid 0.249642 0.249642)
							(end 0.2794 0.1778)
						)
						(arc
							(start 0.2794 -0.1778)
							(mid 0.249642 -0.249642)
							(end 0.1778 -0.2794)
						)
					)
					(width 0)
					(fill yes)
				)
			)
		)
		(pad "2" smd custom
			(at 0 0.4445 270)
			(size 0.1397 0.1397)
			(layers "F.Cu" "F.Mask" "F.Paste")
			(net "GND")
			(options
				(clearance outline)
				(anchor circle)
			)
			(primitives
				(gr_poly
					(pts
						(arc
							(start -0.1778 -0.2794)
							(mid -0.249642 -0.249642)
							(end -0.2794 -0.1778)
						)
						(arc
							(start -0.2794 0.1778)
							(mid -0.249642 0.249642)
							(end -0.1778 0.2794)
						)
						(arc
							(start 0.1778 0.2794)
							(mid 0.249642 0.249642)
							(end 0.2794 0.1778)
						)
						(arc
							(start 0.2794 -0.1778)
							(mid 0.249642 -0.249642)
							(end 0.1778 -0.2794)
						)
					)
					(width 0)
					(fill yes)
				)
			)
		)
	)
	(footprint ""
		(layer "F.Cu")
		(at 41.123108 -131.482846 180)
		(property "Reference" "R376"
			(at 0 0 180)
			(layer "F.SilkS")
			(hide yes)
			(effects
				(font
					(size 1.27 1.27)
				)
			)
		)
		(property "Value" "4K7R2F-GP"
			(at 0.064008 -3.993896 180)
			(unlocked yes)
			(layer "F.Fab")
			(hide yes)
			(effects
				(font
					(size 1.016 1.016)
					(thickness 0.1524)
				)
			)
		)
		(property "Device Type" "R402H16"
			(at 0.064008 -5.517896 180)
			(unlocked yes)
			(layer "F.Fab")
			(hide yes)
			(effects
				(font
					(size 1.016 1.016)
					(thickness 0.1524)
				)
			)
		)
		(duplicate_pad_numbers_are_jumpers no)
		(fp_line
			(start 0.508 -0.9398)
			(end -0.508 -0.9398)
			(stroke
				(width 0.1524)
				(type default)
			)
			(layer "F.SilkS")
		)
		(fp_line
			(start -0.508 -0.9398)
			(end -0.508 0.9398)
			(stroke
				(width 0.1524)
				(type default)
			)
			(layer "F.SilkS")
		)
		(fp_rect
			(start -0.508 0.9398)
			(end 0.508 -0.9398)
			(stroke
				(width 0)
				(type default)
			)
			(fill no)
			(layer "F.CrtYd")
		)
		(fp_rect
			(start -0.508 0.9398)
			(end 0.508 -0.9398)
			(stroke
				(width 0)
				(type default)
			)
			(fill no)
			(layer "F.Fab")
		)
		(pad "1" smd custom
			(at 0 -0.4445 180)
			(size 0.1397 0.1397)
			(layers "F.Cu" "F.Mask" "F.Paste")
			(net "P3V3_STBY")
			(options
				(clearance outline)
				(anchor circle)
			)
			(primitives
				(gr_poly
					(pts
						(arc
							(start -0.1778 -0.2794)
							(mid -0.249642 -0.249642)
							(end -0.2794 -0.1778)
						)
						(arc
							(start -0.2794 0.1778)
							(mid -0.249642 0.249642)
							(end -0.1778 0.2794)
						)
						(arc
							(start 0.1778 0.2794)
							(mid 0.249642 0.249642)
							(end 0.2794 0.1778)
						)
						(arc
							(start 0.2794 -0.1778)
							(mid 0.249642 -0.249642)
							(end 0.1778 -0.2794)
						)
					)
					(width 0)
					(fill yes)
				)
			)
		)
		(pad "2" smd custom
			(at 0 0.4445 180)
			(size 0.1397 0.1397)
			(layers "F.Cu" "F.Mask" "F.Paste")
			(net "BMC_GPIOZ4")
			(options
				(clearance outline)
				(anchor circle)
			)
			(primitives
				(gr_poly
					(pts
						(arc
							(start -0.1778 -0.2794)
							(mid -0.249642 -0.249642)
							(end -0.2794 -0.1778)
						)
						(arc
							(start -0.2794 0.1778)
							(mid -0.249642 0.249642)
							(end -0.1778 0.2794)
						)
						(arc
							(start 0.1778 0.2794)
							(mid 0.249642 0.249642)
							(end 0.2794 0.1778)
						)
						(arc
							(start 0.2794 -0.1778)
							(mid 0.249642 -0.249642)
							(end 0.1778 -0.2794)
						)
					)
					(width 0)
					(fill yes)
				)
			)
		)
	)
	(footprint ""
		(layer "F.Cu")
		(at 62.947296 -159.921956 90)
		(property "Reference" "C95"
			(at 0 0 90)
			(layer "F.SilkS")
			(hide yes)
			(effects
				(font
					(size 1.27 1.27)
				)
			)
		)
		(property "Value" "SC1U16V3KX-5GP"
			(at 0 -2.8194 90)
			(unlocked yes)
			(layer "F.Fab")
			(hide yes)
			(effects
				(font
					(size 1.016 1.016)
					(thickness 0.1524)
				)
			)
		)
		(property "Device Type" "C603H36"
			(at 0 -4.3434 90)
			(unlocked yes)
			(layer "F.Fab")
			(hide yes)
			(effects
				(font
					(size 1.016 1.016)
					(thickness 0.1524)
				)
			)
		)
		(duplicate_pad_numbers_are_jumpers no)
		(fp_line
			(start 0.508 0)
			(end -0.508 0)
			(stroke
				(width 0.2032)
				(type default)
			)
			(layer "F.SilkS")
		)
		(fp_rect
			(start -0.5842 1.3335)
			(end 0.5842 -1.3335)
			(stroke
				(width 0)
				(type default)
			)
			(fill no)
			(layer "F.CrtYd")
		)
		(fp_rect
			(start -0.5842 1.3335)
			(end 0.5842 -1.3335)
			(stroke
				(width 0)
				(type default)
			)
			(fill no)
			(layer "F.Fab")
		)
		(pad "1" smd custom
			(at 0 -0.762 90)
			(size 0.2159 0.2159)
			(layers "F.Cu" "F.Mask" "F.Paste")
			(net "VPLLAV33")
			(options
				(clearance outline)
				(anchor circle)
			)
			(primitives
				(gr_poly
					(pts
						(arc
							(start -0.3302 -0.4318)
							(mid -0.402042 -0.402042)
							(end -0.4318 -0.3302)
						)
						(arc
							(start -0.4318 0.3302)
							(mid -0.402042 0.402042)
							(end -0.3302 0.4318)
						)
						(arc
							(start 0.3302 0.4318)
							(mid 0.402042 0.402042)
							(end 0.4318 0.3302)
						)
						(arc
							(start 0.4318 -0.3302)
							(mid 0.402042 -0.402042)
							(end 0.3302 -0.4318)
						)
					)
					(width 0)
					(fill yes)
				)
			)
		)
		(pad "2" smd custom
			(at 0 0.762 90)
			(size 0.2159 0.2159)
			(layers "F.Cu" "F.Mask" "F.Paste")
			(net "GND")
			(options
				(clearance outline)
				(anchor circle)
			)
			(primitives
				(gr_poly
					(pts
						(arc
							(start -0.3302 -0.4318)
							(mid -0.402042 -0.402042)
							(end -0.4318 -0.3302)
						)
						(arc
							(start -0.4318 0.3302)
							(mid -0.402042 0.402042)
							(end -0.3302 0.4318)
						)
						(arc
							(start 0.3302 0.4318)
							(mid 0.402042 0.402042)
							(end 0.4318 0.3302)
						)
						(arc
							(start 0.4318 -0.3302)
							(mid 0.402042 -0.402042)
							(end 0.3302 -0.4318)
						)
					)
					(width 0)
					(fill yes)
				)
			)
		)
	)
	(footprint ""
		(layer "F.Cu")
		(at 77.1398 -156.561536 -90)
		(property "Reference" "R537"
			(at 0 0 270)
			(layer "F.SilkS")
			(hide yes)
			(effects
				(font
					(size 1.27 1.27)
				)
			)
		)
		(property "Value" "2K05R2F-1-GP"
			(at 0.064008 -3.993896 270)
			(unlocked yes)
			(layer "F.Fab")
			(hide yes)
			(effects
				(font
					(size 1.016 1.016)
					(thickness 0.1524)
				)
			)
		)
		(property "Device Type" "R402H16"
			(at 0.064008 -5.517896 270)
			(unlocked yes)
			(layer "F.Fab")
			(hide yes)
			(effects
				(font
					(size 1.016 1.016)
					(thickness 0.1524)
				)
			)
		)
		(duplicate_pad_numbers_are_jumpers no)
		(fp_line
			(start -0.508 -0.9398)
			(end -0.508 0.9398)
			(stroke
				(width 0.1524)
				(type default)
			)
			(layer "F.SilkS")
		)
		(fp_line
			(start 0.508 -0.9398)
			(end -0.508 -0.9398)
			(stroke
				(width 0.1524)
				(type default)
			)
			(layer "F.SilkS")
		)
		(fp_rect
			(start -0.508 0.9398)
			(end 0.508 -0.9398)
			(stroke
				(width 0)
				(type default)
			)
			(fill no)
			(layer "F.CrtYd")
		)
		(fp_rect
			(start -0.508 0.9398)
			(end 0.508 -0.9398)
			(stroke
				(width 0)
				(type default)
			)
			(fill no)
			(layer "F.Fab")
		)
		(pad "1" smd custom
			(at 0 -0.4445 270)
			(size 0.1397 0.1397)
			(layers "F.Cu" "F.Mask" "F.Paste")
			(net "TPS74801_P1V15_STBY_OUT")
			(options
				(clearance outline)
				(anchor circle)
			)
			(primitives
				(gr_poly
					(pts
						(arc
							(start -0.1778 -0.2794)
							(mid -0.249642 -0.249642)
							(end -0.2794 -0.1778)
						)
						(arc
							(start -0.2794 0.1778)
							(mid -0.249642 0.249642)
							(end -0.1778 0.2794)
						)
						(arc
							(start 0.1778 0.2794)
							(mid 0.249642 0.249642)
							(end 0.2794 0.1778)
						)
						(arc
							(start 0.2794 -0.1778)
							(mid 0.249642 -0.249642)
							(end 0.1778 -0.2794)
						)
					)
					(width 0)
					(fill yes)
				)
			)
		)
		(pad "2" smd custom
			(at 0 0.4445 270)
			(size 0.1397 0.1397)
			(layers "F.Cu" "F.Mask" "F.Paste")
			(net "TPS74801_P1V15_STBY_FB")
			(options
				(clearance outline)
				(anchor circle)
			)
			(primitives
				(gr_poly
					(pts
						(arc
							(start -0.1778 -0.2794)
							(mid -0.249642 -0.249642)
							(end -0.2794 -0.1778)
						)
						(arc
							(start -0.2794 0.1778)
							(mid -0.249642 0.249642)
							(end -0.1778 0.2794)
						)
						(arc
							(start 0.1778 0.2794)
							(mid 0.249642 0.249642)
							(end 0.2794 0.1778)
						)
						(arc
							(start 0.2794 -0.1778)
							(mid 0.249642 -0.249642)
							(end 0.1778 -0.2794)
						)
					)
					(width 0)
					(fill yes)
				)
			)
		)
	)
	(footprint ""
		(layer "F.Cu")
		(at 156.729938 -17.603978 90)
		(property "Reference" "C205"
			(at 0 0 90)
			(layer "F.SilkS")
			(hide yes)
			(effects
				(font
					(size 1.27 1.27)
				)
			)
		)
		(property "Value" "SC10U16V5KX-7-GP-U"
			(at -0.0762 -6.1214 90)
			(unlocked yes)
			(layer "F.Fab")
			(hide yes)
			(effects
				(font
					(size 1.016 1.016)
					(thickness 0.1524)
				)
			)
		)
		(property "Device Type" "C805H58"
			(at -0.0762 -8.1534 90)
			(unlocked yes)
			(layer "F.Fab")
			(hide yes)
			(effects
				(font
					(size 1.016 1.016)
					(thickness 0.1524)
				)
			)
		)
		(duplicate_pad_numbers_are_jumpers no)
		(fp_line
			(start 0.635 0)
			(end -0.635 0)
			(stroke
				(width 0.508)
				(type default)
			)
			(layer "F.SilkS")
		)
		(fp_rect
			(start -0.9652 1.778)
			(end 0.9652 -1.778)
			(stroke
				(width 0)
				(type default)
			)
			(fill no)
			(layer "F.CrtYd")
		)
		(fp_poly
			(pts
				(xy -0.9652 -1.778) (xy 0.9652 -1.778) (xy 0.9652 1.778) (xy -0.9652 1.778)
			)
			(stroke
				(width 0)
				(type default)
			)
			(fill no)
			(layer "F.Fab")
		)
		(pad "1" smd rect
			(at 0 -0.9652 90)
			(size 1.397 1.143)
			(layers "F.Cu" "F.Mask" "F.Paste")
			(net "P12V_STBY_VIN_PU4")
		)
		(pad "2" smd rect
			(at 0 0.9652 90)
			(size 1.397 1.143)
			(layers "F.Cu" "F.Mask" "F.Paste")
			(net "GND")
		)
	)
	(footprint ""
		(layer "F.Cu")
		(at 77.283818 -74.153268 90)
		(property "Reference" "VIA2"
			(at 0 0 90)
			(layer "F.SilkS")
			(hide yes)
			(effects
				(font
					(size 1.27 1.27)
				)
			)
		)
		(property "Value" "85OHM-8L-1D6MM-L16L18-GP"
			(at 4.064 0.6096 90)
			(unlocked yes)
			(layer "F.Fab")
			(hide yes)
			(effects
				(font
					(size 1.016 1.016)
					(thickness 0.1524)
				)
			)
		)
		(property "Device Type" "VIA-PCIE-4P-368076"
			(at 4.064 -0.9144 90)
			(unlocked yes)
			(layer "F.Fab")
			(hide yes)
			(effects
				(font
					(size 1.016 1.016)
					(thickness 0.1524)
				)
			)
		)
		(duplicate_pad_numbers_are_jumpers no)
		(fp_rect
			(start -1.8415 0.381)
			(end 1.8415 -0.381)
			(stroke
				(width 0)
				(type default)
			)
			(fill no)
			(layer "F.CrtYd")
		)
		(fp_rect
			(start -1.8415 0.381)
			(end 1.8415 -0.381)
			(stroke
				(width 0)
				(type default)
			)
			(fill no)
			(layer "F.Fab")
		)
		(pad "1" thru_hole circle
			(at -1.4605 0 90)
			(size 0.508 0.508)
			(drill 0.254)
			(layers "*.Cu" "*.Mask")
			(remove_unused_layers no)
			(net "GND")
			(clearance 0.127)
			(thermal_gap 0.127)
		)
		(pad "2" thru_hole circle
			(at -0.4445 0 90)
			(size 0.508 0.508)
			(drill 0.254)
			(layers "*.Cu" "*.Mask")
			(remove_unused_layers no)
			(net "PCIE_COMP_TO_IOM_17_DP")
			(clearance 0.127)
			(thermal_gap 0.127)
		)
		(pad "3" thru_hole circle
			(at 0.4445 0 90)
			(size 0.508 0.508)
			(drill 0.254)
			(layers "*.Cu" "*.Mask")
			(remove_unused_layers no)
			(net "PCIE_COMP_TO_IOM_17_DN")
			(clearance 0.127)
			(thermal_gap 0.127)
		)
		(pad "4" thru_hole circle
			(at 1.4605 0 90)
			(size 0.508 0.508)
			(drill 0.254)
			(layers "*.Cu" "*.Mask")
			(remove_unused_layers no)
			(net "GND")
			(clearance 0.127)
			(thermal_gap 0.127)
		)
	)
	(footprint ""
		(layer "F.Cu")
		(at 23.2918 -183.5658 90)
		(property "Reference" "L8"
			(at 0 0 90)
			(layer "F.SilkS")
			(hide yes)
			(effects
				(font
					(size 1.27 1.27)
				)
			)
		)
		(property "Value" "BLM21PG220SN1DGP"
			(at 0.0254 -5.6896 90)
			(unlocked yes)
			(layer "F.Fab")
			(hide yes)
			(effects
				(font
					(size 1.016 1.016)
					(thickness 0.1524)
				)
			)
		)
		(property "Device Type" "L20125H42"
			(at 0.0254 -7.5946 90)
			(unlocked yes)
			(layer "F.Fab")
			(hide yes)
			(effects
				(font
					(size 1.016 1.016)
					(thickness 0.1524)
				)
			)
		)
		(duplicate_pad_numbers_are_jumpers no)
		(fp_line
			(start 0.9144 -1.7018)
			(end -0.9144 -1.7018)
			(stroke
				(width 0.1524)
				(type default)
			)
			(layer "F.SilkS")
		)
		(fp_line
			(start -0.9144 -1.7018)
			(end -0.9144 1.7018)
			(stroke
				(width 0.1524)
				(type default)
			)
			(layer "F.SilkS")
		)
		(fp_line
			(start 0.9144 1.7018)
			(end 0.9144 -1.7018)
			(stroke
				(width 0.1524)
				(type default)
			)
			(layer "F.SilkS")
		)
		(fp_line
			(start -0.9144 1.7018)
			(end 0.9144 1.7018)
			(stroke
				(width 0.1524)
				(type default)
			)
			(layer "F.SilkS")
		)
		(fp_rect
			(start -1.0033 1.778)
			(end 1.0033 -1.778)
			(stroke
				(width 0)
				(type default)
			)
			(fill no)
			(layer "F.CrtYd")
		)
		(fp_poly
			(pts
				(xy -1.0033 -1.778) (xy 1.0033 -1.778) (xy 1.0033 1.778) (xy -1.0033 1.778)
			)
			(stroke
				(width 0)
				(type default)
			)
			(fill no)
			(layer "F.Fab")
		)
		(pad "1" smd rect
			(at 0 -0.9652 90)
			(size 1.397 1.143)
			(layers "F.Cu" "F.Mask" "F.Paste")
			(net "P12V_STBY")
		)
		(pad "2" smd rect
			(at 0 0.9652 90)
			(size 1.397 1.143)
			(layers "F.Cu" "F.Mask" "F.Paste")
			(net "P12V_STBY_VIN_PU2")
		)
	)
	(footprint ""
		(layer "F.Cu")
		(at 60.44692 -141.149578)
		(property "Reference" "TP55"
			(at 0 0 0)
			(layer "F.SilkS")
			(hide yes)
			(effects
				(font
					(size 1.27 1.27)
				)
			)
		)
		(property "Value" "TPAD28-2-GP"
			(at -0.0127 -1.6637 0)
			(unlocked yes)
			(layer "F.Fab")
			(hide yes)
			(effects
				(font
					(size 1.016 1.016)
					(thickness 0.1524)
				)
			)
		)
		(property "Device Type" "TPAD28"
			(at -0.0127 -3.1877 0)
			(unlocked yes)
			(layer "F.Fab")
			(hide yes)
			(effects
				(font
					(size 1.016 1.016)
					(thickness 0.1524)
				)
			)
		)
		(duplicate_pad_numbers_are_jumpers no)
		(fp_poly
			(pts
				(arc
					(start 0.3556 0)
					(mid -0.3556 0)
					(end 0.3556 0)
				)
			)
			(stroke
				(width 0)
				(type default)
			)
			(fill no)
			(layer "F.CrtYd")
		)
		(fp_poly
			(pts
				(arc
					(start 0.6096 0)
					(mid -0.6096 0)
					(end 0.6096 0)
				)
			)
			(stroke
				(width 0)
				(type default)
			)
			(fill no)
			(layer "F.Fab")
		)
		(pad "1" smd circle
			(at 0 0)
			(size 0.7112 0.7112)
			(layers "F.Cu" "F.Mask" "F.Paste")
			(net "TP_BMC_GPIOA7")
		)
	)
	(footprint ""
		(layer "F.Cu")
		(at 149.948138 -14.987778)
		(property "Reference" "R515"
			(at 0 0 0)
			(layer "F.SilkS")
			(hide yes)
			(effects
				(font
					(size 1.27 1.27)
				)
			)
		)
		(property "Value" "13K7R2F-GP"
			(at 0.064008 -3.993896 0)
			(unlocked yes)
			(layer "F.Fab")
			(hide yes)
			(effects
				(font
					(size 1.016 1.016)
					(thickness 0.1524)
				)
			)
		)
		(property "Device Type" "R402H16"
			(at 0.064008 -5.517896 0)
			(unlocked yes)
			(layer "F.Fab")
			(hide yes)
			(effects
				(font
					(size 1.016 1.016)
					(thickness 0.1524)
				)
			)
		)
		(duplicate_pad_numbers_are_jumpers no)
		(fp_line
			(start -0.508 -0.9398)
			(end -0.508 0.9398)
			(stroke
				(width 0.1524)
				(type default)
			)
			(layer "F.SilkS")
		)
		(fp_line
			(start 0.508 -0.9398)
			(end -0.508 -0.9398)
			(stroke
				(width 0.1524)
				(type default)
			)
			(layer "F.SilkS")
		)
		(fp_rect
			(start -0.508 0.9398)
			(end 0.508 -0.9398)
			(stroke
				(width 0)
				(type default)
			)
			(fill no)
			(layer "F.CrtYd")
		)
		(fp_rect
			(start -0.508 0.9398)
			(end 0.508 -0.9398)
			(stroke
				(width 0)
				(type default)
			)
			(fill no)
			(layer "F.Fab")
		)
		(pad "1" smd custom
			(at 0 -0.4445)
			(size 0.1397 0.1397)
			(layers "F.Cu" "F.Mask" "F.Paste")
			(net "P1V8_STBY_CC_R")
			(options
				(clearance outline)
				(anchor circle)
			)
			(primitives
				(gr_poly
					(pts
						(arc
							(start -0.1778 -0.2794)
							(mid -0.249642 -0.249642)
							(end -0.2794 -0.1778)
						)
						(arc
							(start -0.2794 0.1778)
							(mid -0.249642 0.249642)
							(end -0.1778 0.2794)
						)
						(arc
							(start 0.1778 0.2794)
							(mid 0.249642 0.249642)
							(end 0.2794 0.1778)
						)
						(arc
							(start 0.2794 -0.1778)
							(mid 0.249642 -0.249642)
							(end 0.1778 -0.2794)
						)
					)
					(width 0)
					(fill yes)
				)
			)
		)
		(pad "2" smd custom
			(at 0 0.4445)
			(size 0.1397 0.1397)
			(layers "F.Cu" "F.Mask" "F.Paste")
			(net "P1V8_STBY_VFB")
			(options
				(clearance outline)
				(anchor circle)
			)
			(primitives
				(gr_poly
					(pts
						(arc
							(start -0.1778 -0.2794)
							(mid -0.249642 -0.249642)
							(end -0.2794 -0.1778)
						)
						(arc
							(start -0.2794 0.1778)
							(mid -0.249642 0.249642)
							(end -0.1778 0.2794)
						)
						(arc
							(start 0.1778 0.2794)
							(mid 0.249642 0.249642)
							(end 0.2794 0.1778)
						)
						(arc
							(start 0.2794 -0.1778)
							(mid 0.249642 -0.249642)
							(end 0.1778 -0.2794)
						)
					)
					(width 0)
					(fill yes)
				)
			)
		)
	)
	(footprint ""
		(layer "F.Cu")
		(at 166.466012 -131.46024 90)
		(property "Reference" "R846"
			(at 0 0 90)
			(layer "F.SilkS")
			(hide yes)
			(effects
				(font
					(size 1.27 1.27)
				)
			)
		)
		(property "Value" "4K7R2F-GP"
			(at 0.064008 -3.993896 90)
			(unlocked yes)
			(layer "F.Fab")
			(hide yes)
			(effects
				(font
					(size 1.016 1.016)
					(thickness 0.1524)
				)
			)
		)
		(property "Device Type" "R402H16"
			(at 0.064008 -5.517896 90)
			(unlocked yes)
			(layer "F.Fab")
			(hide yes)
			(effects
				(font
					(size 1.016 1.016)
					(thickness 0.1524)
				)
			)
		)
		(duplicate_pad_numbers_are_jumpers no)
		(fp_line
			(start 0.508 -0.9398)
			(end -0.508 -0.9398)
			(stroke
				(width 0.1524)
				(type default)
			)
			(layer "F.SilkS")
		)
		(fp_line
			(start -0.508 -0.9398)
			(end -0.508 0.9398)
			(stroke
				(width 0.1524)
				(type default)
			)
			(layer "F.SilkS")
		)
		(fp_rect
			(start -0.508 0.9398)
			(end 0.508 -0.9398)
			(stroke
				(width 0)
				(type default)
			)
			(fill no)
			(layer "F.CrtYd")
		)
		(fp_rect
			(start -0.508 0.9398)
			(end 0.508 -0.9398)
			(stroke
				(width 0)
				(type default)
			)
			(fill no)
			(layer "F.Fab")
		)
		(pad "1" smd custom
			(at 0 -0.4445 90)
			(size 0.1397 0.1397)
			(layers "F.Cu" "F.Mask" "F.Paste")
			(net "P3V3_STBY")
			(options
				(clearance outline)
				(anchor circle)
			)
			(primitives
				(gr_poly
					(pts
						(arc
							(start -0.1778 -0.2794)
							(mid -0.249642 -0.249642)
							(end -0.2794 -0.1778)
						)
						(arc
							(start -0.2794 0.1778)
							(mid -0.249642 0.249642)
							(end -0.1778 0.2794)
						)
						(arc
							(start 0.1778 0.2794)
							(mid 0.249642 0.249642)
							(end 0.2794 0.1778)
						)
						(arc
							(start 0.2794 -0.1778)
							(mid 0.249642 -0.249642)
							(end 0.1778 -0.2794)
						)
					)
					(width 0)
					(fill yes)
				)
			)
		)
		(pad "2" smd custom
			(at 0 0.4445 90)
			(size 0.1397 0.1397)
			(layers "F.Cu" "F.Mask" "F.Paste")
			(net "M2_2_ACTIVE_N")
			(options
				(clearance outline)
				(anchor circle)
			)
			(primitives
				(gr_poly
					(pts
						(arc
							(start -0.1778 -0.2794)
							(mid -0.249642 -0.249642)
							(end -0.2794 -0.1778)
						)
						(arc
							(start -0.2794 0.1778)
							(mid -0.249642 0.249642)
							(end -0.1778 0.2794)
						)
						(arc
							(start 0.1778 0.2794)
							(mid 0.249642 0.249642)
							(end 0.2794 0.1778)
						)
						(arc
							(start 0.2794 -0.1778)
							(mid 0.249642 -0.249642)
							(end 0.1778 -0.2794)
						)
					)
					(width 0)
					(fill yes)
				)
			)
		)
	)
	(footprint ""
		(layer "F.Cu")
		(at 87.638636 -31.905448 180)
		(property "Reference" "C2"
			(at 0 0 180)
			(layer "F.SilkS")
			(hide yes)
			(effects
				(font
					(size 1.27 1.27)
				)
			)
		)
		(property "Value" "SC1U16V3KX-5GP"
			(at 0 -2.8194 180)
			(unlocked yes)
			(layer "F.Fab")
			(hide yes)
			(effects
				(font
					(size 1.016 1.016)
					(thickness 0.1524)
				)
			)
		)
		(property "Device Type" "C603H36"
			(at 0 -4.3434 180)
			(unlocked yes)
			(layer "F.Fab")
			(hide yes)
			(effects
				(font
					(size 1.016 1.016)
					(thickness 0.1524)
				)
			)
		)
		(duplicate_pad_numbers_are_jumpers no)
		(fp_line
			(start 0.508 0)
			(end -0.508 0)
			(stroke
				(width 0.2032)
				(type default)
			)
			(layer "F.SilkS")
		)
		(fp_rect
			(start -0.5842 1.3335)
			(end 0.5842 -1.3335)
			(stroke
				(width 0)
				(type default)
			)
			(fill no)
			(layer "F.CrtYd")
		)
		(fp_rect
			(start -0.5842 1.3335)
			(end 0.5842 -1.3335)
			(stroke
				(width 0)
				(type default)
			)
			(fill no)
			(layer "F.Fab")
		)
		(pad "1" smd custom
			(at 0 -0.762 180)
			(size 0.2159 0.2159)
			(layers "F.Cu" "F.Mask" "F.Paste")
			(net "P5V_USB")
			(options
				(clearance outline)
				(anchor circle)
			)
			(primitives
				(gr_poly
					(pts
						(arc
							(start -0.3302 -0.4318)
							(mid -0.402042 -0.402042)
							(end -0.4318 -0.3302)
						)
						(arc
							(start -0.4318 0.3302)
							(mid -0.402042 0.402042)
							(end -0.3302 0.4318)
						)
						(arc
							(start 0.3302 0.4318)
							(mid 0.402042 0.402042)
							(end 0.4318 0.3302)
						)
						(arc
							(start 0.4318 -0.3302)
							(mid 0.402042 -0.402042)
							(end 0.3302 -0.4318)
						)
					)
					(width 0)
					(fill yes)
				)
			)
		)
		(pad "2" smd custom
			(at 0 0.762 180)
			(size 0.2159 0.2159)
			(layers "F.Cu" "F.Mask" "F.Paste")
			(net "GND")
			(options
				(clearance outline)
				(anchor circle)
			)
			(primitives
				(gr_poly
					(pts
						(arc
							(start -0.3302 -0.4318)
							(mid -0.402042 -0.402042)
							(end -0.4318 -0.3302)
						)
						(arc
							(start -0.4318 0.3302)
							(mid -0.402042 0.402042)
							(end -0.3302 0.4318)
						)
						(arc
							(start 0.3302 0.4318)
							(mid 0.402042 0.402042)
							(end 0.4318 0.3302)
						)
						(arc
							(start 0.4318 -0.3302)
							(mid 0.402042 -0.402042)
							(end 0.3302 -0.4318)
						)
					)
					(width 0)
					(fill yes)
				)
			)
		)
	)
	(footprint ""
		(layer "F.Cu")
		(at 38.544246 -177.14341)
		(property "Reference" "R486"
			(at 0 0 0)
			(layer "F.SilkS")
			(hide yes)
			(effects
				(font
					(size 1.27 1.27)
				)
			)
		)
		(property "Value" "3K83R2F-GP"
			(at 0.064008 -3.993896 0)
			(unlocked yes)
			(layer "F.Fab")
			(hide yes)
			(effects
				(font
					(size 1.016 1.016)
					(thickness 0.1524)
				)
			)
		)
		(property "Device Type" "R402H16"
			(at 0.064008 -5.517896 0)
			(unlocked yes)
			(layer "F.Fab")
			(hide yes)
			(effects
				(font
					(size 1.016 1.016)
					(thickness 0.1524)
				)
			)
		)
		(duplicate_pad_numbers_are_jumpers no)
		(fp_line
			(start -0.508 -0.9398)
			(end -0.508 0.9398)
			(stroke
				(width 0.1524)
				(type default)
			)
			(layer "F.SilkS")
		)
		(fp_line
			(start 0.508 -0.9398)
			(end -0.508 -0.9398)
			(stroke
				(width 0.1524)
				(type default)
			)
			(layer "F.SilkS")
		)
		(fp_rect
			(start -0.508 0.9398)
			(end 0.508 -0.9398)
			(stroke
				(width 0)
				(type default)
			)
			(fill no)
			(layer "F.CrtYd")
		)
		(fp_rect
			(start -0.508 0.9398)
			(end 0.508 -0.9398)
			(stroke
				(width 0)
				(type default)
			)
			(fill no)
			(layer "F.Fab")
		)
		(pad "1" smd custom
			(at 0 -0.4445)
			(size 0.1397 0.1397)
			(layers "F.Cu" "F.Mask" "F.Paste")
			(net "P3V3_STBY_EN")
			(options
				(clearance outline)
				(anchor circle)
			)
			(primitives
				(gr_poly
					(pts
						(arc
							(start -0.1778 -0.2794)
							(mid -0.249642 -0.249642)
							(end -0.2794 -0.1778)
						)
						(arc
							(start -0.2794 0.1778)
							(mid -0.249642 0.249642)
							(end -0.1778 0.2794)
						)
						(arc
							(start 0.1778 0.2794)
							(mid 0.249642 0.249642)
							(end 0.2794 0.1778)
						)
						(arc
							(start 0.2794 -0.1778)
							(mid 0.249642 -0.249642)
							(end 0.1778 -0.2794)
						)
					)
					(width 0)
					(fill yes)
				)
			)
		)
		(pad "2" smd custom
			(at 0 0.4445)
			(size 0.1397 0.1397)
			(layers "F.Cu" "F.Mask" "F.Paste")
			(net "GND")
			(options
				(clearance outline)
				(anchor circle)
			)
			(primitives
				(gr_poly
					(pts
						(arc
							(start -0.1778 -0.2794)
							(mid -0.249642 -0.249642)
							(end -0.2794 -0.1778)
						)
						(arc
							(start -0.2794 0.1778)
							(mid -0.249642 0.249642)
							(end -0.1778 0.2794)
						)
						(arc
							(start 0.1778 0.2794)
							(mid 0.249642 0.249642)
							(end 0.2794 0.1778)
						)
						(arc
							(start 0.2794 -0.1778)
							(mid 0.249642 -0.249642)
							(end 0.1778 -0.2794)
						)
					)
					(width 0)
					(fill yes)
				)
			)
		)
	)
	(footprint ""
		(layer "F.Cu")
		(at 82.08645 -172.324522 -90)
		(property "Reference" "R451"
			(at 0 0 270)
			(layer "F.SilkS")
			(hide yes)
			(effects
				(font
					(size 1.27 1.27)
				)
			)
		)
		(property "Value" "10KR2F-2-GP"
			(at 0.064008 -3.993896 270)
			(unlocked yes)
			(layer "F.Fab")
			(hide yes)
			(effects
				(font
					(size 1.016 1.016)
					(thickness 0.1524)
				)
			)
		)
		(property "Device Type" "R402H16"
			(at 0.064008 -5.517896 270)
			(unlocked yes)
			(layer "F.Fab")
			(hide yes)
			(effects
				(font
					(size 1.016 1.016)
					(thickness 0.1524)
				)
			)
		)
		(duplicate_pad_numbers_are_jumpers no)
		(fp_line
			(start -0.508 -0.9398)
			(end -0.508 0.9398)
			(stroke
				(width 0.1524)
				(type default)
			)
			(layer "F.SilkS")
		)
		(fp_line
			(start 0.508 -0.9398)
			(end -0.508 -0.9398)
			(stroke
				(width 0.1524)
				(type default)
			)
			(layer "F.SilkS")
		)
		(fp_rect
			(start -0.508 0.9398)
			(end 0.508 -0.9398)
			(stroke
				(width 0)
				(type default)
			)
			(fill no)
			(layer "F.CrtYd")
		)
		(fp_rect
			(start -0.508 0.9398)
			(end 0.508 -0.9398)
			(stroke
				(width 0)
				(type default)
			)
			(fill no)
			(layer "F.Fab")
		)
		(pad "1" smd custom
			(at 0 -0.4445 270)
			(size 0.1397 0.1397)
			(layers "F.Cu" "F.Mask" "F.Paste")
			(net "EXP_UART_EN_R")
			(options
				(clearance outline)
				(anchor circle)
			)
			(primitives
				(gr_poly
					(pts
						(arc
							(start -0.1778 -0.2794)
							(mid -0.249642 -0.249642)
							(end -0.2794 -0.1778)
						)
						(arc
							(start -0.2794 0.1778)
							(mid -0.249642 0.249642)
							(end -0.1778 0.2794)
						)
						(arc
							(start 0.1778 0.2794)
							(mid 0.249642 0.249642)
							(end 0.2794 0.1778)
						)
						(arc
							(start 0.2794 -0.1778)
							(mid 0.249642 -0.249642)
							(end 0.1778 -0.2794)
						)
					)
					(width 0)
					(fill yes)
				)
			)
		)
		(pad "2" smd custom
			(at 0 0.4445 270)
			(size 0.1397 0.1397)
			(layers "F.Cu" "F.Mask" "F.Paste")
			(net "GND")
			(options
				(clearance outline)
				(anchor circle)
			)
			(primitives
				(gr_poly
					(pts
						(arc
							(start -0.1778 -0.2794)
							(mid -0.249642 -0.249642)
							(end -0.2794 -0.1778)
						)
						(arc
							(start -0.2794 0.1778)
							(mid -0.249642 0.249642)
							(end -0.1778 0.2794)
						)
						(arc
							(start 0.1778 0.2794)
							(mid 0.249642 0.249642)
							(end 0.2794 0.1778)
						)
						(arc
							(start 0.2794 -0.1778)
							(mid 0.249642 -0.249642)
							(end 0.1778 -0.2794)
						)
					)
					(width 0)
					(fill yes)
				)
			)
		)
	)
	(footprint ""
		(layer "F.Cu")
		(at 124.841 -10.668 90)
		(property "Reference" "R439"
			(at 0 0 90)
			(layer "F.SilkS")
			(hide yes)
			(effects
				(font
					(size 1.27 1.27)
				)
			)
		)
		(property "Value" "11KR2F-L-GP"
			(at 0.064008 -3.993896 90)
			(unlocked yes)
			(layer "F.Fab")
			(hide yes)
			(effects
				(font
					(size 1.016 1.016)
					(thickness 0.1524)
				)
			)
		)
		(property "Device Type" "R402H16"
			(at 0.064008 -5.517896 90)
			(unlocked yes)
			(layer "F.Fab")
			(hide yes)
			(effects
				(font
					(size 1.016 1.016)
					(thickness 0.1524)
				)
			)
		)
		(duplicate_pad_numbers_are_jumpers no)
		(fp_line
			(start 0.508 -0.9398)
			(end -0.508 -0.9398)
			(stroke
				(width 0.1524)
				(type default)
			)
			(layer "F.SilkS")
		)
		(fp_line
			(start -0.508 -0.9398)
			(end -0.508 0.9398)
			(stroke
				(width 0.1524)
				(type default)
			)
			(layer "F.SilkS")
		)
		(fp_rect
			(start -0.508 0.9398)
			(end 0.508 -0.9398)
			(stroke
				(width 0)
				(type default)
			)
			(fill no)
			(layer "F.CrtYd")
		)
		(fp_rect
			(start -0.508 0.9398)
			(end 0.508 -0.9398)
			(stroke
				(width 0)
				(type default)
			)
			(fill no)
			(layer "F.Fab")
		)
		(pad "1" smd custom
			(at 0 -0.4445 90)
			(size 0.1397 0.1397)
			(layers "F.Cu" "F.Mask" "F.Paste")
			(net "MB0_P12V_PWGIN_R")
			(options
				(clearance outline)
				(anchor circle)
			)
			(primitives
				(gr_poly
					(pts
						(arc
							(start -0.1778 -0.2794)
							(mid -0.249642 -0.249642)
							(end -0.2794 -0.1778)
						)
						(arc
							(start -0.2794 0.1778)
							(mid -0.249642 0.249642)
							(end -0.1778 0.2794)
						)
						(arc
							(start 0.1778 0.2794)
							(mid 0.249642 0.249642)
							(end 0.2794 0.1778)
						)
						(arc
							(start 0.2794 -0.1778)
							(mid 0.249642 -0.249642)
							(end 0.1778 -0.2794)
						)
					)
					(width 0)
					(fill yes)
				)
			)
		)
		(pad "2" smd custom
			(at 0 0.4445 90)
			(size 0.1397 0.1397)
			(layers "F.Cu" "F.Mask" "F.Paste")
			(net "AGND_CURRENT_MON")
			(options
				(clearance outline)
				(anchor circle)
			)
			(primitives
				(gr_poly
					(pts
						(arc
							(start -0.1778 -0.2794)
							(mid -0.249642 -0.249642)
							(end -0.2794 -0.1778)
						)
						(arc
							(start -0.2794 0.1778)
							(mid -0.249642 0.249642)
							(end -0.1778 0.2794)
						)
						(arc
							(start 0.1778 0.2794)
							(mid 0.249642 0.249642)
							(end 0.2794 0.1778)
						)
						(arc
							(start 0.2794 -0.1778)
							(mid 0.249642 -0.249642)
							(end 0.1778 -0.2794)
						)
					)
					(width 0)
					(fill yes)
				)
			)
		)
	)
	(footprint ""
		(layer "F.Cu")
		(at 87.1474 -168.275 -90)
		(property "Reference" "Q12"
			(at 0 0 270)
			(layer "F.SilkS")
			(hide yes)
			(effects
				(font
					(size 1.27 1.27)
				)
			)
		)
		(property "Value" "2N7002K-1-GP"
			(at 0.127 -8.9662 270)
			(unlocked yes)
			(layer "F.Fab")
			(hide yes)
			(effects
				(font
					(size 1.016 1.016)
					(thickness 0.1524)
				)
			)
		)
		(property "Device Type" "SOT23DGS2D4H44"
			(at 0.127 -10.4902 270)
			(unlocked yes)
			(layer "F.Fab")
			(hide yes)
			(effects
				(font
					(size 1.016 1.016)
					(thickness 0.1524)
				)
			)
		)
		(duplicate_pad_numbers_are_jumpers no)
		(fp_line
			(start -1.651 1.778)
			(end 1.651 1.778)
			(stroke
				(width 0.1524)
				(type default)
			)
			(layer "F.SilkS")
		)
		(fp_line
			(start 1.651 1.778)
			(end 1.651 -1.778)
			(stroke
				(width 0.1524)
				(type default)
			)
			(layer "F.SilkS")
		)
		(fp_line
			(start -1.651 -1.778)
			(end -1.651 1.778)
			(stroke
				(width 0.1524)
				(type default)
			)
			(layer "F.SilkS")
		)
		(fp_line
			(start 1.651 -1.778)
			(end -1.651 -1.778)
			(stroke
				(width 0.1524)
				(type default)
			)
			(layer "F.SilkS")
		)
		(fp_poly
			(pts
				(xy -1.778 1.8796) (xy -1.778 -1.8796) (xy 1.778 -1.8796) (xy 1.778 1.8796)
			)
			(stroke
				(width 0)
				(type default)
			)
			(fill no)
			(layer "F.CrtYd")
		)
		(fp_poly
			(pts
				(xy -1.778 1.8796) (xy -1.778 -1.8796) (xy 1.778 -1.8796) (xy 1.778 1.8796)
			)
			(stroke
				(width 0)
				(type default)
			)
			(fill no)
			(layer "F.Fab")
		)
		(pad "D" smd custom
			(at 0 -0.9525 270)
			(size 0.1905 0.1905)
			(layers "F.Cu" "F.Mask" "F.Paste")
			(net "IOM_STBY_PGOOD")
			(options
				(clearance outline)
				(anchor circle)
			)
			(primitives
				(gr_poly
					(pts
						(arc
							(start -0.1778 0.5715)
							(mid -0.321484 0.511984)
							(end -0.381 0.3683)
						)
						(arc
							(start -0.381 -0.3683)
							(mid -0.321484 -0.511984)
							(end -0.1778 -0.5715)
						)
						(arc
							(start 0.1778 -0.5715)
							(mid 0.321484 -0.511984)
							(end 0.381 -0.3683)
						)
						(arc
							(start 0.381 0.3683)
							(mid 0.321484 0.511984)
							(end 0.1778 0.5715)
						)
					)
					(width 0)
					(fill yes)
				)
			)
		)
		(pad "G" smd custom
			(at -0.98425 0.9525 270)
			(size 0.1905 0.1905)
			(layers "F.Cu" "F.Mask" "F.Paste")
			(net "P1V15_STBY_PG_G")
			(options
				(clearance outline)
				(anchor circle)
			)
			(primitives
				(gr_poly
					(pts
						(arc
							(start -0.1778 0.5715)
							(mid -0.321484 0.511984)
							(end -0.381 0.3683)
						)
						(arc
							(start -0.381 -0.3683)
							(mid -0.321484 -0.511984)
							(end -0.1778 -0.5715)
						)
						(arc
							(start 0.1778 -0.5715)
							(mid 0.321484 -0.511984)
							(end 0.381 -0.3683)
						)
						(arc
							(start 0.381 0.3683)
							(mid 0.321484 0.511984)
							(end 0.1778 0.5715)
						)
					)
					(width 0)
					(fill yes)
				)
			)
		)
		(pad "S" smd custom
			(at 0.98425 0.9525 270)
			(size 0.1905 0.1905)
			(layers "F.Cu" "F.Mask" "F.Paste")
			(net "GND")
			(options
				(clearance outline)
				(anchor circle)
			)
			(primitives
				(gr_poly
					(pts
						(arc
							(start -0.1778 0.5715)
							(mid -0.321484 0.511984)
							(end -0.381 0.3683)
						)
						(arc
							(start -0.381 -0.3683)
							(mid -0.321484 -0.511984)
							(end -0.1778 -0.5715)
						)
						(arc
							(start 0.1778 -0.5715)
							(mid 0.321484 -0.511984)
							(end 0.381 -0.3683)
						)
						(arc
							(start 0.381 0.3683)
							(mid 0.321484 0.511984)
							(end 0.1778 0.5715)
						)
					)
					(width 0)
					(fill yes)
				)
			)
		)
	)
	(footprint ""
		(layer "F.Cu")
		(at 215.470994 -43.047412 -90)
		(property "Reference" "R465"
			(at 0 0 270)
			(layer "F.SilkS")
			(hide yes)
			(effects
				(font
					(size 1.27 1.27)
				)
			)
		)
		(property "Value" "2K2R2F-GP"
			(at 0.064008 -3.993896 270)
			(unlocked yes)
			(layer "F.Fab")
			(hide yes)
			(effects
				(font
					(size 1.016 1.016)
					(thickness 0.1524)
				)
			)
		)
		(property "Device Type" "R402H16"
			(at 0.064008 -5.517896 270)
			(unlocked yes)
			(layer "F.Fab")
			(hide yes)
			(effects
				(font
					(size 1.016 1.016)
					(thickness 0.1524)
				)
			)
		)
		(duplicate_pad_numbers_are_jumpers no)
		(fp_line
			(start -0.508 -0.9398)
			(end -0.508 0.9398)
			(stroke
				(width 0.1524)
				(type default)
			)
			(layer "F.SilkS")
		)
		(fp_line
			(start 0.508 -0.9398)
			(end -0.508 -0.9398)
			(stroke
				(width 0.1524)
				(type default)
			)
			(layer "F.SilkS")
		)
		(fp_rect
			(start -0.508 0.9398)
			(end 0.508 -0.9398)
			(stroke
				(width 0)
				(type default)
			)
			(fill no)
			(layer "F.CrtYd")
		)
		(fp_rect
			(start -0.508 0.9398)
			(end 0.508 -0.9398)
			(stroke
				(width 0)
				(type default)
			)
			(fill no)
			(layer "F.Fab")
		)
		(pad "1" smd custom
			(at 0 -0.4445 270)
			(size 0.1397 0.1397)
			(layers "F.Cu" "F.Mask" "F.Paste")
			(net "P5V_EN_R")
			(options
				(clearance outline)
				(anchor circle)
			)
			(primitives
				(gr_poly
					(pts
						(arc
							(start -0.1778 -0.2794)
							(mid -0.249642 -0.249642)
							(end -0.2794 -0.1778)
						)
						(arc
							(start -0.2794 0.1778)
							(mid -0.249642 0.249642)
							(end -0.1778 0.2794)
						)
						(arc
							(start 0.1778 0.2794)
							(mid 0.249642 0.249642)
							(end 0.2794 0.1778)
						)
						(arc
							(start 0.2794 -0.1778)
							(mid 0.249642 -0.249642)
							(end 0.1778 -0.2794)
						)
					)
					(width 0)
					(fill yes)
				)
			)
		)
		(pad "2" smd custom
			(at 0 0.4445 270)
			(size 0.1397 0.1397)
			(layers "F.Cu" "F.Mask" "F.Paste")
			(net "GND")
			(options
				(clearance outline)
				(anchor circle)
			)
			(primitives
				(gr_poly
					(pts
						(arc
							(start -0.1778 -0.2794)
							(mid -0.249642 -0.249642)
							(end -0.2794 -0.1778)
						)
						(arc
							(start -0.2794 0.1778)
							(mid -0.249642 0.249642)
							(end -0.1778 0.2794)
						)
						(arc
							(start 0.1778 0.2794)
							(mid 0.249642 0.249642)
							(end 0.2794 0.1778)
						)
						(arc
							(start 0.2794 -0.1778)
							(mid 0.249642 -0.249642)
							(end 0.1778 -0.2794)
						)
					)
					(width 0)
					(fill yes)
				)
			)
		)
	)
	(footprint ""
		(layer "F.Cu")
		(at 214.78875 -45.561758)
		(property "Reference" "C163"
			(at 0 0 0)
			(layer "F.SilkS")
			(hide yes)
			(effects
				(font
					(size 1.27 1.27)
				)
			)
		)
		(property "Value" "SC68P50V2JN-2-GP"
			(at 1.1811 -2.7051 0)
			(unlocked yes)
			(layer "F.Fab")
			(hide yes)
			(effects
				(font
					(size 1.016 1.016)
					(thickness 0.1524)
				)
			)
		)
		(property "Device Type" "C402H22"
			(at 1.1811 -4.2291 0)
			(unlocked yes)
			(layer "F.Fab")
			(hide yes)
			(effects
				(font
					(size 1.016 1.016)
					(thickness 0.1524)
				)
			)
		)
		(duplicate_pad_numbers_are_jumpers no)
		(fp_rect
			(start -0.4318 0.9525)
			(end 0.4318 -0.9525)
			(stroke
				(width 0)
				(type default)
			)
			(fill no)
			(layer "F.CrtYd")
		)
		(fp_rect
			(start -0.4318 0.9525)
			(end 0.4318 -0.9525)
			(stroke
				(width 0)
				(type default)
			)
			(fill no)
			(layer "F.Fab")
		)
		(pad "1" smd custom
			(at 0 -0.4445)
			(size 0.1524 0.1524)
			(layers "F.Cu" "F.Mask" "F.Paste")
			(net "P5V_VFB")
			(options
				(clearance outline)
				(anchor circle)
			)
			(primitives
				(gr_poly
					(pts
						(arc
							(start 0.3048 -0.2032)
							(mid 0.275042 -0.275042)
							(end 0.2032 -0.3048)
						)
						(arc
							(start -0.2032 -0.3048)
							(mid -0.275042 -0.275042)
							(end -0.3048 -0.2032)
						)
						(arc
							(start -0.3048 0.2032)
							(mid -0.275042 0.275042)
							(end -0.2032 0.3048)
						)
						(arc
							(start 0.2032 0.3048)
							(mid 0.275042 0.275042)
							(end 0.3048 0.2032)
						)
					)
					(width 0)
					(fill yes)
				)
			)
		)
		(pad "2" smd custom
			(at 0 0.4445)
			(size 0.1524 0.1524)
			(layers "F.Cu" "F.Mask" "F.Paste")
			(net "P5V_VFB_R")
			(options
				(clearance outline)
				(anchor circle)
			)
			(primitives
				(gr_poly
					(pts
						(arc
							(start 0.3048 -0.2032)
							(mid 0.275042 -0.275042)
							(end 0.2032 -0.3048)
						)
						(arc
							(start -0.2032 -0.3048)
							(mid -0.275042 -0.275042)
							(end -0.3048 -0.2032)
						)
						(arc
							(start -0.3048 0.2032)
							(mid -0.275042 0.275042)
							(end -0.2032 0.3048)
						)
						(arc
							(start 0.2032 0.3048)
							(mid 0.275042 0.275042)
							(end 0.3048 0.2032)
						)
					)
					(width 0)
					(fill yes)
				)
			)
		)
	)
	(footprint ""
		(layer "F.Cu")
		(at 206.019146 -120.771666)
		(property "Reference" "R811"
			(at 0 0 0)
			(layer "F.SilkS")
			(hide yes)
			(effects
				(font
					(size 1.27 1.27)
				)
			)
		)
		(property "Value" "4K7R2F-GP"
			(at 0.064008 -3.993896 0)
			(unlocked yes)
			(layer "F.Fab")
			(hide yes)
			(effects
				(font
					(size 1.016 1.016)
					(thickness 0.1524)
				)
			)
		)
		(property "Device Type" "R402H16"
			(at 0.064008 -5.517896 0)
			(unlocked yes)
			(layer "F.Fab")
			(hide yes)
			(effects
				(font
					(size 1.016 1.016)
					(thickness 0.1524)
				)
			)
		)
		(duplicate_pad_numbers_are_jumpers no)
		(fp_line
			(start -0.508 -0.9398)
			(end -0.508 0.9398)
			(stroke
				(width 0.1524)
				(type default)
			)
			(layer "F.SilkS")
		)
		(fp_line
			(start 0.508 -0.9398)
			(end -0.508 -0.9398)
			(stroke
				(width 0.1524)
				(type default)
			)
			(layer "F.SilkS")
		)
		(fp_rect
			(start -0.508 0.9398)
			(end 0.508 -0.9398)
			(stroke
				(width 0)
				(type default)
			)
			(fill no)
			(layer "F.CrtYd")
		)
		(fp_rect
			(start -0.508 0.9398)
			(end 0.508 -0.9398)
			(stroke
				(width 0)
				(type default)
			)
			(fill no)
			(layer "F.Fab")
		)
		(pad "1" smd custom
			(at 0 -0.4445)
			(size 0.1397 0.1397)
			(layers "F.Cu" "F.Mask" "F.Paste")
			(net "M2_1_ALERT#")
			(options
				(clearance outline)
				(anchor circle)
			)
			(primitives
				(gr_poly
					(pts
						(arc
							(start -0.1778 -0.2794)
							(mid -0.249642 -0.249642)
							(end -0.2794 -0.1778)
						)
						(arc
							(start -0.2794 0.1778)
							(mid -0.249642 0.249642)
							(end -0.1778 0.2794)
						)
						(arc
							(start 0.1778 0.2794)
							(mid 0.249642 0.249642)
							(end 0.2794 0.1778)
						)
						(arc
							(start 0.2794 -0.1778)
							(mid 0.249642 -0.249642)
							(end 0.1778 -0.2794)
						)
					)
					(width 0)
					(fill yes)
				)
			)
		)
		(pad "2" smd custom
			(at 0 0.4445)
			(size 0.1397 0.1397)
			(layers "F.Cu" "F.Mask" "F.Paste")
			(net "P1V8_STBY")
			(options
				(clearance outline)
				(anchor circle)
			)
			(primitives
				(gr_poly
					(pts
						(arc
							(start -0.1778 -0.2794)
							(mid -0.249642 -0.249642)
							(end -0.2794 -0.1778)
						)
						(arc
							(start -0.2794 0.1778)
							(mid -0.249642 0.249642)
							(end -0.1778 0.2794)
						)
						(arc
							(start 0.1778 0.2794)
							(mid 0.249642 0.249642)
							(end 0.2794 0.1778)
						)
						(arc
							(start 0.2794 -0.1778)
							(mid 0.249642 -0.249642)
							(end 0.1778 -0.2794)
						)
					)
					(width 0)
					(fill yes)
				)
			)
		)
	)
	(footprint ""
		(layer "F.Cu")
		(at 83.358228 -94.937072 90)
		(property "Reference" "VIA16"
			(at 0 0 90)
			(layer "F.SilkS")
			(hide yes)
			(effects
				(font
					(size 1.27 1.27)
				)
			)
		)
		(property "Value" "85OHM-8L-1D6MM-L16L18-GP"
			(at 4.064 0.6096 90)
			(unlocked yes)
			(layer "F.Fab")
			(hide yes)
			(effects
				(font
					(size 1.016 1.016)
					(thickness 0.1524)
				)
			)
		)
		(property "Device Type" "VIA-PCIE-4P-368076"
			(at 4.064 -0.9144 90)
			(unlocked yes)
			(layer "F.Fab")
			(hide yes)
			(effects
				(font
					(size 1.016 1.016)
					(thickness 0.1524)
				)
			)
		)
		(duplicate_pad_numbers_are_jumpers no)
		(fp_rect
			(start -1.8415 0.381)
			(end 1.8415 -0.381)
			(stroke
				(width 0)
				(type default)
			)
			(fill no)
			(layer "F.CrtYd")
		)
		(fp_rect
			(start -1.8415 0.381)
			(end 1.8415 -0.381)
			(stroke
				(width 0)
				(type default)
			)
			(fill no)
			(layer "F.Fab")
		)
		(pad "1" thru_hole circle
			(at -1.4605 0 90)
			(size 0.508 0.508)
			(drill 0.254)
			(layers "*.Cu" "*.Mask")
			(remove_unused_layers no)
			(net "GND")
			(clearance 0.127)
			(thermal_gap 0.127)
		)
		(pad "2" thru_hole circle
			(at -0.4445 0 90)
			(size 0.508 0.508)
			(drill 0.254)
			(layers "*.Cu" "*.Mask")
			(remove_unused_layers no)
			(net "PCIE_IOM_TO_COMP_23_DP")
			(clearance 0.127)
			(thermal_gap 0.127)
		)
		(pad "3" thru_hole circle
			(at 0.4445 0 90)
			(size 0.508 0.508)
			(drill 0.254)
			(layers "*.Cu" "*.Mask")
			(remove_unused_layers no)
			(net "PCIE_IOM_TO_COMP_23_DN")
			(clearance 0.127)
			(thermal_gap 0.127)
		)
		(pad "4" thru_hole circle
			(at 1.4605 0 90)
			(size 0.508 0.508)
			(drill 0.254)
			(layers "*.Cu" "*.Mask")
			(remove_unused_layers no)
			(net "GND")
			(clearance 0.127)
			(thermal_gap 0.127)
		)
	)
	(footprint ""
		(layer "F.Cu")
		(at 10.986008 -167.616886 90)
		(property "Reference" "C228"
			(at 0 0 90)
			(layer "F.SilkS")
			(hide yes)
			(effects
				(font
					(size 1.27 1.27)
				)
			)
		)
		(property "Value" "SC470P50V2KX-3GP"
			(at 1.1811 -2.7051 90)
			(unlocked yes)
			(layer "F.Fab")
			(hide yes)
			(effects
				(font
					(size 1.016 1.016)
					(thickness 0.1524)
				)
			)
		)
		(property "Device Type" "C402H22"
			(at 1.1811 -4.2291 90)
			(unlocked yes)
			(layer "F.Fab")
			(hide yes)
			(effects
				(font
					(size 1.016 1.016)
					(thickness 0.1524)
				)
			)
		)
		(duplicate_pad_numbers_are_jumpers no)
		(fp_rect
			(start -0.4318 0.9525)
			(end 0.4318 -0.9525)
			(stroke
				(width 0)
				(type default)
			)
			(fill no)
			(layer "F.CrtYd")
		)
		(fp_rect
			(start -0.4318 0.9525)
			(end 0.4318 -0.9525)
			(stroke
				(width 0)
				(type default)
			)
			(fill no)
			(layer "F.Fab")
		)
		(pad "1" smd custom
			(at 0 -0.4445 90)
			(size 0.1524 0.1524)
			(layers "F.Cu" "F.Mask" "F.Paste")
			(net "GND")
			(options
				(clearance outline)
				(anchor circle)
			)
			(primitives
				(gr_poly
					(pts
						(arc
							(start 0.3048 -0.2032)
							(mid 0.275042 -0.275042)
							(end 0.2032 -0.3048)
						)
						(arc
							(start -0.2032 -0.3048)
							(mid -0.275042 -0.275042)
							(end -0.3048 -0.2032)
						)
						(arc
							(start -0.3048 0.2032)
							(mid -0.275042 0.275042)
							(end -0.2032 0.3048)
						)
						(arc
							(start 0.2032 0.3048)
							(mid 0.275042 0.275042)
							(end 0.3048 0.2032)
						)
					)
					(width 0)
					(fill yes)
				)
			)
		)
		(pad "2" smd custom
			(at 0 0.4445 90)
			(size 0.1524 0.1524)
			(layers "F.Cu" "F.Mask" "F.Paste")
			(net "TPS74801_P1V2_STBY_SS")
			(options
				(clearance outline)
				(anchor circle)
			)
			(primitives
				(gr_poly
					(pts
						(arc
							(start 0.3048 -0.2032)
							(mid 0.275042 -0.275042)
							(end 0.2032 -0.3048)
						)
						(arc
							(start -0.2032 -0.3048)
							(mid -0.275042 -0.275042)
							(end -0.3048 -0.2032)
						)
						(arc
							(start -0.3048 0.2032)
							(mid -0.275042 0.275042)
							(end -0.2032 0.3048)
						)
						(arc
							(start 0.2032 0.3048)
							(mid 0.275042 0.275042)
							(end 0.3048 0.2032)
						)
					)
					(width 0)
					(fill yes)
				)
			)
		)
	)
	(footprint ""
		(layer "F.Cu")
		(at 67.945 -162.433 -90)
		(property "Reference" "R774"
			(at 0 0 270)
			(layer "F.SilkS")
			(hide yes)
			(effects
				(font
					(size 1.27 1.27)
				)
			)
		)
		(property "Value" "1KR2F-3-GP"
			(at 0.064008 -3.993896 270)
			(unlocked yes)
			(layer "F.Fab")
			(hide yes)
			(effects
				(font
					(size 1.016 1.016)
					(thickness 0.1524)
				)
			)
		)
		(property "Device Type" "R402H16"
			(at 0.064008 -5.517896 270)
			(unlocked yes)
			(layer "F.Fab")
			(hide yes)
			(effects
				(font
					(size 1.016 1.016)
					(thickness 0.1524)
				)
			)
		)
		(duplicate_pad_numbers_are_jumpers no)
		(fp_line
			(start -0.508 -0.9398)
			(end -0.508 0.9398)
			(stroke
				(width 0.1524)
				(type default)
			)
			(layer "F.SilkS")
		)
		(fp_line
			(start 0.508 -0.9398)
			(end -0.508 -0.9398)
			(stroke
				(width 0.1524)
				(type default)
			)
			(layer "F.SilkS")
		)
		(fp_rect
			(start -0.508 0.9398)
			(end 0.508 -0.9398)
			(stroke
				(width 0)
				(type default)
			)
			(fill no)
			(layer "F.CrtYd")
		)
		(fp_rect
			(start -0.508 0.9398)
			(end 0.508 -0.9398)
			(stroke
				(width 0)
				(type default)
			)
			(fill no)
			(layer "F.Fab")
		)
		(pad "1" smd custom
			(at 0 -0.4445 270)
			(size 0.1397 0.1397)
			(layers "F.Cu" "F.Mask" "F.Paste")
			(net "P1V15_STBY")
			(options
				(clearance outline)
				(anchor circle)
			)
			(primitives
				(gr_poly
					(pts
						(arc
							(start -0.1778 -0.2794)
							(mid -0.249642 -0.249642)
							(end -0.2794 -0.1778)
						)
						(arc
							(start -0.2794 0.1778)
							(mid -0.249642 0.249642)
							(end -0.1778 0.2794)
						)
						(arc
							(start 0.1778 0.2794)
							(mid 0.249642 0.249642)
							(end 0.2794 0.1778)
						)
						(arc
							(start 0.2794 -0.1778)
							(mid 0.249642 -0.249642)
							(end 0.1778 -0.2794)
						)
					)
					(width 0)
					(fill yes)
				)
			)
		)
		(pad "2" smd custom
			(at 0 0.4445 270)
			(size 0.1397 0.1397)
			(layers "F.Cu" "F.Mask" "F.Paste")
			(net "ADC_P1V15_STBY")
			(options
				(clearance outline)
				(anchor circle)
			)
			(primitives
				(gr_poly
					(pts
						(arc
							(start -0.1778 -0.2794)
							(mid -0.249642 -0.249642)
							(end -0.2794 -0.1778)
						)
						(arc
							(start -0.2794 0.1778)
							(mid -0.249642 0.249642)
							(end -0.1778 0.2794)
						)
						(arc
							(start 0.1778 0.2794)
							(mid 0.249642 0.249642)
							(end 0.2794 0.1778)
						)
						(arc
							(start 0.2794 -0.1778)
							(mid 0.249642 -0.249642)
							(end 0.1778 -0.2794)
						)
					)
					(width 0)
					(fill yes)
				)
			)
		)
	)
	(footprint ""
		(layer "F.Cu")
		(at 8.879332 -136.716516 90)
		(property "Reference" "R207"
			(at 0 0 90)
			(layer "F.SilkS")
			(hide yes)
			(effects
				(font
					(size 1.27 1.27)
				)
			)
		)
		(property "Value" "120R2F-GP"
			(at 0.064008 -3.993896 90)
			(unlocked yes)
			(layer "F.Fab")
			(hide yes)
			(effects
				(font
					(size 1.016 1.016)
					(thickness 0.1524)
				)
			)
		)
		(property "Device Type" "R402H16"
			(at 0.064008 -5.517896 90)
			(unlocked yes)
			(layer "F.Fab")
			(hide yes)
			(effects
				(font
					(size 1.016 1.016)
					(thickness 0.1524)
				)
			)
		)
		(duplicate_pad_numbers_are_jumpers no)
		(fp_line
			(start 0.508 -0.9398)
			(end -0.508 -0.9398)
			(stroke
				(width 0.1524)
				(type default)
			)
			(layer "F.SilkS")
		)
		(fp_line
			(start -0.508 -0.9398)
			(end -0.508 0.9398)
			(stroke
				(width 0.1524)
				(type default)
			)
			(layer "F.SilkS")
		)
		(fp_rect
			(start -0.508 0.9398)
			(end 0.508 -0.9398)
			(stroke
				(width 0)
				(type default)
			)
			(fill no)
			(layer "F.CrtYd")
		)
		(fp_rect
			(start -0.508 0.9398)
			(end 0.508 -0.9398)
			(stroke
				(width 0)
				(type default)
			)
			(fill no)
			(layer "F.Fab")
		)
		(pad "1" smd custom
			(at 0 -0.4445 90)
			(size 0.1397 0.1397)
			(layers "F.Cu" "F.Mask" "F.Paste")
			(net "GND")
			(options
				(clearance outline)
				(anchor circle)
			)
			(primitives
				(gr_poly
					(pts
						(arc
							(start -0.1778 -0.2794)
							(mid -0.249642 -0.249642)
							(end -0.2794 -0.1778)
						)
						(arc
							(start -0.2794 0.1778)
							(mid -0.249642 0.249642)
							(end -0.1778 0.2794)
						)
						(arc
							(start 0.1778 0.2794)
							(mid 0.249642 0.249642)
							(end 0.2794 0.1778)
						)
						(arc
							(start 0.2794 -0.1778)
							(mid 0.249642 -0.249642)
							(end 0.1778 -0.2794)
						)
					)
					(width 0)
					(fill yes)
				)
			)
		)
		(pad "2" smd custom
			(at 0 0.4445 90)
			(size 0.1397 0.1397)
			(layers "F.Cu" "F.Mask" "F.Paste")
			(net "DDR4_RST_N")
			(options
				(clearance outline)
				(anchor circle)
			)
			(primitives
				(gr_poly
					(pts
						(arc
							(start -0.1778 -0.2794)
							(mid -0.249642 -0.249642)
							(end -0.2794 -0.1778)
						)
						(arc
							(start -0.2794 0.1778)
							(mid -0.249642 0.249642)
							(end -0.1778 0.2794)
						)
						(arc
							(start 0.1778 0.2794)
							(mid 0.249642 0.249642)
							(end 0.2794 0.1778)
						)
						(arc
							(start 0.2794 -0.1778)
							(mid 0.249642 -0.249642)
							(end 0.1778 -0.2794)
						)
					)
					(width 0)
					(fill yes)
				)
			)
		)
	)
	(footprint ""
		(layer "F.Cu")
		(at 217.067384 -40.85209)
		(property "Reference" "R471"
			(at 0 0 0)
			(layer "F.SilkS")
			(hide yes)
			(effects
				(font
					(size 1.27 1.27)
				)
			)
		)
		(property "Value" "15KR2F-GP"
			(at 0.064008 -3.993896 0)
			(unlocked yes)
			(layer "F.Fab")
			(hide yes)
			(effects
				(font
					(size 1.016 1.016)
					(thickness 0.1524)
				)
			)
		)
		(property "Device Type" "R402H16"
			(at 0.064008 -5.517896 0)
			(unlocked yes)
			(layer "F.Fab")
			(hide yes)
			(effects
				(font
					(size 1.016 1.016)
					(thickness 0.1524)
				)
			)
		)
		(duplicate_pad_numbers_are_jumpers no)
		(fp_line
			(start -0.508 -0.9398)
			(end -0.508 0.9398)
			(stroke
				(width 0.1524)
				(type default)
			)
			(layer "F.SilkS")
		)
		(fp_line
			(start 0.508 -0.9398)
			(end -0.508 -0.9398)
			(stroke
				(width 0.1524)
				(type default)
			)
			(layer "F.SilkS")
		)
		(fp_rect
			(start -0.508 0.9398)
			(end 0.508 -0.9398)
			(stroke
				(width 0)
				(type default)
			)
			(fill no)
			(layer "F.CrtYd")
		)
		(fp_rect
			(start -0.508 0.9398)
			(end 0.508 -0.9398)
			(stroke
				(width 0)
				(type default)
			)
			(fill no)
			(layer "F.Fab")
		)
		(pad "1" smd custom
			(at 0 -0.4445)
			(size 0.1397 0.1397)
			(layers "F.Cu" "F.Mask" "F.Paste")
			(net "PWRGD_P5V_STBY")
			(options
				(clearance outline)
				(anchor circle)
			)
			(primitives
				(gr_poly
					(pts
						(arc
							(start -0.1778 -0.2794)
							(mid -0.249642 -0.249642)
							(end -0.2794 -0.1778)
						)
						(arc
							(start -0.2794 0.1778)
							(mid -0.249642 0.249642)
							(end -0.1778 0.2794)
						)
						(arc
							(start 0.1778 0.2794)
							(mid 0.249642 0.249642)
							(end 0.2794 0.1778)
						)
						(arc
							(start 0.2794 -0.1778)
							(mid 0.249642 -0.249642)
							(end 0.1778 -0.2794)
						)
					)
					(width 0)
					(fill yes)
				)
			)
		)
		(pad "2" smd custom
			(at 0 0.4445)
			(size 0.1397 0.1397)
			(layers "F.Cu" "F.Mask" "F.Paste")
			(net "GND")
			(options
				(clearance outline)
				(anchor circle)
			)
			(primitives
				(gr_poly
					(pts
						(arc
							(start -0.1778 -0.2794)
							(mid -0.249642 -0.249642)
							(end -0.2794 -0.1778)
						)
						(arc
							(start -0.2794 0.1778)
							(mid -0.249642 0.249642)
							(end -0.1778 0.2794)
						)
						(arc
							(start 0.1778 0.2794)
							(mid 0.249642 0.249642)
							(end 0.2794 0.1778)
						)
						(arc
							(start 0.2794 -0.1778)
							(mid 0.249642 -0.249642)
							(end 0.1778 -0.2794)
						)
					)
					(width 0)
					(fill yes)
				)
			)
		)
	)
	(footprint ""
		(layer "F.Cu")
		(at 211.473288 -44.367958 180)
		(property "Reference" "R473"
			(at 0 0 180)
			(layer "F.SilkS")
			(hide yes)
			(effects
				(font
					(size 1.27 1.27)
				)
			)
		)
		(property "Value" "10R3F-GP"
			(at -0.0254 -2.5146 180)
			(unlocked yes)
			(layer "F.Fab")
			(hide yes)
			(effects
				(font
					(size 1.016 1.016)
					(thickness 0.1524)
				)
			)
		)
		(property "Device Type" "R603H22"
			(at -0.0254 -4.0386 180)
			(unlocked yes)
			(layer "F.Fab")
			(hide yes)
			(effects
				(font
					(size 1.016 1.016)
					(thickness 0.1524)
				)
			)
		)
		(duplicate_pad_numbers_are_jumpers no)
		(fp_line
			(start 0.2032 0)
			(end 0.4826 0)
			(stroke
				(width 0.2032)
				(type default)
			)
			(layer "F.SilkS")
		)
		(fp_line
			(start -0.4826 0)
			(end -0.2032 0)
			(stroke
				(width 0.2032)
				(type default)
			)
			(layer "F.SilkS")
		)
		(fp_rect
			(start -0.5842 1.3335)
			(end 0.5842 -1.3335)
			(stroke
				(width 0)
				(type default)
			)
			(fill no)
			(layer "F.CrtYd")
		)
		(fp_rect
			(start -0.5842 1.3335)
			(end 0.5842 -1.3335)
			(stroke
				(width 0)
				(type default)
			)
			(fill no)
			(layer "F.Fab")
		)
		(pad "1" smd custom
			(at 0 -0.762 180)
			(size 0.2159 0.2159)
			(layers "F.Cu" "F.Mask" "F.Paste")
			(net "P5V_CC")
			(options
				(clearance outline)
				(anchor circle)
			)
			(primitives
				(gr_poly
					(pts
						(arc
							(start -0.3302 -0.4318)
							(mid -0.402042 -0.402042)
							(end -0.4318 -0.3302)
						)
						(arc
							(start -0.4318 0.3302)
							(mid -0.402042 0.402042)
							(end -0.3302 0.4318)
						)
						(arc
							(start 0.3302 0.4318)
							(mid 0.402042 0.402042)
							(end 0.4318 0.3302)
						)
						(arc
							(start 0.4318 -0.3302)
							(mid 0.402042 -0.402042)
							(end 0.3302 -0.4318)
						)
					)
					(width 0)
					(fill yes)
				)
			)
		)
		(pad "2" smd custom
			(at 0 0.762 180)
			(size 0.2159 0.2159)
			(layers "F.Cu" "F.Mask" "F.Paste")
			(net "P5V_VFB_R")
			(options
				(clearance outline)
				(anchor circle)
			)
			(primitives
				(gr_poly
					(pts
						(arc
							(start -0.3302 -0.4318)
							(mid -0.402042 -0.402042)
							(end -0.4318 -0.3302)
						)
						(arc
							(start -0.4318 0.3302)
							(mid -0.402042 0.402042)
							(end -0.3302 0.4318)
						)
						(arc
							(start 0.3302 0.4318)
							(mid 0.402042 0.402042)
							(end 0.4318 0.3302)
						)
						(arc
							(start 0.4318 -0.3302)
							(mid 0.402042 -0.402042)
							(end 0.3302 -0.4318)
						)
					)
					(width 0)
					(fill yes)
				)
			)
		)
	)
	(footprint ""
		(layer "F.Cu")
		(at 62.9666 -156.2354 180)
		(property "Reference" "R387"
			(at 0 0 180)
			(layer "F.SilkS")
			(hide yes)
			(effects
				(font
					(size 1.27 1.27)
				)
			)
		)
		(property "Value" "4K7R2F-GP"
			(at 0.064008 -3.993896 180)
			(unlocked yes)
			(layer "F.Fab")
			(hide yes)
			(effects
				(font
					(size 1.016 1.016)
					(thickness 0.1524)
				)
			)
		)
		(property "Device Type" "R402H16"
			(at 0.064008 -5.517896 180)
			(unlocked yes)
			(layer "F.Fab")
			(hide yes)
			(effects
				(font
					(size 1.016 1.016)
					(thickness 0.1524)
				)
			)
		)
		(duplicate_pad_numbers_are_jumpers no)
		(fp_line
			(start 0.508 -0.9398)
			(end -0.508 -0.9398)
			(stroke
				(width 0.1524)
				(type default)
			)
			(layer "F.SilkS")
		)
		(fp_line
			(start -0.508 -0.9398)
			(end -0.508 0.9398)
			(stroke
				(width 0.1524)
				(type default)
			)
			(layer "F.SilkS")
		)
		(fp_rect
			(start -0.508 0.9398)
			(end 0.508 -0.9398)
			(stroke
				(width 0)
				(type default)
			)
			(fill no)
			(layer "F.CrtYd")
		)
		(fp_rect
			(start -0.508 0.9398)
			(end 0.508 -0.9398)
			(stroke
				(width 0)
				(type default)
			)
			(fill no)
			(layer "F.Fab")
		)
		(pad "1" smd custom
			(at 0 -0.4445 180)
			(size 0.1397 0.1397)
			(layers "F.Cu" "F.Mask" "F.Paste")
			(net "GND")
			(options
				(clearance outline)
				(anchor circle)
			)
			(primitives
				(gr_poly
					(pts
						(arc
							(start -0.1778 -0.2794)
							(mid -0.249642 -0.249642)
							(end -0.2794 -0.1778)
						)
						(arc
							(start -0.2794 0.1778)
							(mid -0.249642 0.249642)
							(end -0.1778 0.2794)
						)
						(arc
							(start 0.1778 0.2794)
							(mid 0.249642 0.249642)
							(end 0.2794 0.1778)
						)
						(arc
							(start 0.2794 -0.1778)
							(mid 0.249642 -0.249642)
							(end 0.1778 -0.2794)
						)
					)
					(width 0)
					(fill yes)
				)
			)
		)
		(pad "2" smd custom
			(at 0 0.4445 180)
			(size 0.1397 0.1397)
			(layers "F.Cu" "F.Mask" "F.Paste")
			(net "NCSI_TXD1")
			(options
				(clearance outline)
				(anchor circle)
			)
			(primitives
				(gr_poly
					(pts
						(arc
							(start -0.1778 -0.2794)
							(mid -0.249642 -0.249642)
							(end -0.2794 -0.1778)
						)
						(arc
							(start -0.2794 0.1778)
							(mid -0.249642 0.249642)
							(end -0.1778 0.2794)
						)
						(arc
							(start 0.1778 0.2794)
							(mid 0.249642 0.249642)
							(end 0.2794 0.1778)
						)
						(arc
							(start 0.2794 -0.1778)
							(mid 0.249642 -0.249642)
							(end 0.1778 -0.2794)
						)
					)
					(width 0)
					(fill yes)
				)
			)
		)
	)
	(footprint ""
		(layer "F.Cu")
		(at 60.246006 -168.317418 90)
		(property "Reference" "R77"
			(at 0 0 90)
			(layer "F.SilkS")
			(hide yes)
			(effects
				(font
					(size 1.27 1.27)
				)
			)
		)
		(property "Value" "10KR2F-2-GP"
			(at 0.064008 -3.993896 90)
			(unlocked yes)
			(layer "F.Fab")
			(hide yes)
			(effects
				(font
					(size 1.016 1.016)
					(thickness 0.1524)
				)
			)
		)
		(property "Device Type" "R402H16"
			(at 0.064008 -5.517896 90)
			(unlocked yes)
			(layer "F.Fab")
			(hide yes)
			(effects
				(font
					(size 1.016 1.016)
					(thickness 0.1524)
				)
			)
		)
		(duplicate_pad_numbers_are_jumpers no)
		(fp_line
			(start 0.508 -0.9398)
			(end -0.508 -0.9398)
			(stroke
				(width 0.1524)
				(type default)
			)
			(layer "F.SilkS")
		)
		(fp_line
			(start -0.508 -0.9398)
			(end -0.508 0.9398)
			(stroke
				(width 0.1524)
				(type default)
			)
			(layer "F.SilkS")
		)
		(fp_rect
			(start -0.508 0.9398)
			(end 0.508 -0.9398)
			(stroke
				(width 0)
				(type default)
			)
			(fill no)
			(layer "F.CrtYd")
		)
		(fp_rect
			(start -0.508 0.9398)
			(end 0.508 -0.9398)
			(stroke
				(width 0)
				(type default)
			)
			(fill no)
			(layer "F.Fab")
		)
		(pad "1" smd custom
			(at 0 -0.4445 90)
			(size 0.1397 0.1397)
			(layers "F.Cu" "F.Mask" "F.Paste")
			(net "P3V3_STBY")
			(options
				(clearance outline)
				(anchor circle)
			)
			(primitives
				(gr_poly
					(pts
						(arc
							(start -0.1778 -0.2794)
							(mid -0.249642 -0.249642)
							(end -0.2794 -0.1778)
						)
						(arc
							(start -0.2794 0.1778)
							(mid -0.249642 0.249642)
							(end -0.1778 0.2794)
						)
						(arc
							(start 0.1778 0.2794)
							(mid 0.249642 0.249642)
							(end 0.2794 0.1778)
						)
						(arc
							(start 0.2794 -0.1778)
							(mid 0.249642 -0.249642)
							(end 0.1778 -0.2794)
						)
					)
					(width 0)
					(fill yes)
				)
			)
		)
		(pad "2" smd custom
			(at 0 0.4445 90)
			(size 0.1397 0.1397)
			(layers "F.Cu" "F.Mask" "F.Paste")
			(net "FM_TPM_PRSNT_RST_N")
			(options
				(clearance outline)
				(anchor circle)
			)
			(primitives
				(gr_poly
					(pts
						(arc
							(start -0.1778 -0.2794)
							(mid -0.249642 -0.249642)
							(end -0.2794 -0.1778)
						)
						(arc
							(start -0.2794 0.1778)
							(mid -0.249642 0.249642)
							(end -0.1778 0.2794)
						)
						(arc
							(start 0.1778 0.2794)
							(mid 0.249642 0.249642)
							(end 0.2794 0.1778)
						)
						(arc
							(start 0.2794 -0.1778)
							(mid 0.249642 -0.249642)
							(end 0.1778 -0.2794)
						)
					)
					(width 0)
					(fill yes)
				)
			)
		)
	)
	(footprint ""
		(layer "F.Cu")
		(at 27.559 -122.047 180)
		(property "Reference" "R84"
			(at 0 0 180)
			(layer "F.SilkS")
			(hide yes)
			(effects
				(font
					(size 1.27 1.27)
				)
			)
		)
		(property "Value" "4K7R2F-GP"
			(at 0.064008 -3.993896 180)
			(unlocked yes)
			(layer "F.Fab")
			(hide yes)
			(effects
				(font
					(size 1.016 1.016)
					(thickness 0.1524)
				)
			)
		)
		(property "Device Type" "R402H16"
			(at 0.064008 -5.517896 180)
			(unlocked yes)
			(layer "F.Fab")
			(hide yes)
			(effects
				(font
					(size 1.016 1.016)
					(thickness 0.1524)
				)
			)
		)
		(duplicate_pad_numbers_are_jumpers no)
		(fp_line
			(start 0.508 -0.9398)
			(end -0.508 -0.9398)
			(stroke
				(width 0.1524)
				(type default)
			)
			(layer "F.SilkS")
		)
		(fp_line
			(start -0.508 -0.9398)
			(end -0.508 0.9398)
			(stroke
				(width 0.1524)
				(type default)
			)
			(layer "F.SilkS")
		)
		(fp_rect
			(start -0.508 0.9398)
			(end 0.508 -0.9398)
			(stroke
				(width 0)
				(type default)
			)
			(fill no)
			(layer "F.CrtYd")
		)
		(fp_rect
			(start -0.508 0.9398)
			(end 0.508 -0.9398)
			(stroke
				(width 0)
				(type default)
			)
			(fill no)
			(layer "F.Fab")
		)
		(pad "1" smd custom
			(at 0 -0.4445 180)
			(size 0.1397 0.1397)
			(layers "F.Cu" "F.Mask" "F.Paste")
			(net "P3V3_STBY")
			(options
				(clearance outline)
				(anchor circle)
			)
			(primitives
				(gr_poly
					(pts
						(arc
							(start -0.1778 -0.2794)
							(mid -0.249642 -0.249642)
							(end -0.2794 -0.1778)
						)
						(arc
							(start -0.2794 0.1778)
							(mid -0.249642 0.249642)
							(end -0.1778 0.2794)
						)
						(arc
							(start 0.1778 0.2794)
							(mid 0.249642 0.249642)
							(end 0.2794 0.1778)
						)
						(arc
							(start 0.2794 -0.1778)
							(mid 0.249642 -0.249642)
							(end 0.1778 -0.2794)
						)
					)
					(width 0)
					(fill yes)
				)
			)
		)
		(pad "2" smd custom
			(at 0 0.4445 180)
			(size 0.1397 0.1397)
			(layers "F.Cu" "F.Mask" "F.Paste")
			(net "WP_DISABLE")
			(options
				(clearance outline)
				(anchor circle)
			)
			(primitives
				(gr_poly
					(pts
						(arc
							(start -0.1778 -0.2794)
							(mid -0.249642 -0.249642)
							(end -0.2794 -0.1778)
						)
						(arc
							(start -0.2794 0.1778)
							(mid -0.249642 0.249642)
							(end -0.1778 0.2794)
						)
						(arc
							(start 0.1778 0.2794)
							(mid 0.249642 0.249642)
							(end 0.2794 0.1778)
						)
						(arc
							(start 0.2794 -0.1778)
							(mid 0.249642 -0.249642)
							(end 0.1778 -0.2794)
						)
					)
					(width 0)
					(fill yes)
				)
			)
		)
	)
	(footprint ""
		(layer "F.Cu")
		(at 98.5774 -143.3576 90)
		(property "Reference" "R428"
			(at 0 0 90)
			(layer "F.SilkS")
			(hide yes)
			(effects
				(font
					(size 1.27 1.27)
				)
			)
		)
		(property "Value" "4K7R2F-GP"
			(at 0.064008 -3.993896 90)
			(unlocked yes)
			(layer "F.Fab")
			(hide yes)
			(effects
				(font
					(size 1.016 1.016)
					(thickness 0.1524)
				)
			)
		)
		(property "Device Type" "R402H16"
			(at 0.064008 -5.517896 90)
			(unlocked yes)
			(layer "F.Fab")
			(hide yes)
			(effects
				(font
					(size 1.016 1.016)
					(thickness 0.1524)
				)
			)
		)
		(duplicate_pad_numbers_are_jumpers no)
		(fp_line
			(start 0.508 -0.9398)
			(end -0.508 -0.9398)
			(stroke
				(width 0.1524)
				(type default)
			)
			(layer "F.SilkS")
		)
		(fp_line
			(start -0.508 -0.9398)
			(end -0.508 0.9398)
			(stroke
				(width 0.1524)
				(type default)
			)
			(layer "F.SilkS")
		)
		(fp_rect
			(start -0.508 0.9398)
			(end 0.508 -0.9398)
			(stroke
				(width 0)
				(type default)
			)
			(fill no)
			(layer "F.CrtYd")
		)
		(fp_rect
			(start -0.508 0.9398)
			(end 0.508 -0.9398)
			(stroke
				(width 0)
				(type default)
			)
			(fill no)
			(layer "F.Fab")
		)
		(pad "1" smd custom
			(at 0 -0.4445 90)
			(size 0.1397 0.1397)
			(layers "F.Cu" "F.Mask" "F.Paste")
			(net "TCA9555_A0")
			(options
				(clearance outline)
				(anchor circle)
			)
			(primitives
				(gr_poly
					(pts
						(arc
							(start -0.1778 -0.2794)
							(mid -0.249642 -0.249642)
							(end -0.2794 -0.1778)
						)
						(arc
							(start -0.2794 0.1778)
							(mid -0.249642 0.249642)
							(end -0.1778 0.2794)
						)
						(arc
							(start 0.1778 0.2794)
							(mid 0.249642 0.249642)
							(end 0.2794 0.1778)
						)
						(arc
							(start 0.2794 -0.1778)
							(mid 0.249642 -0.249642)
							(end 0.1778 -0.2794)
						)
					)
					(width 0)
					(fill yes)
				)
			)
		)
		(pad "2" smd custom
			(at 0 0.4445 90)
			(size 0.1397 0.1397)
			(layers "F.Cu" "F.Mask" "F.Paste")
			(net "GND")
			(options
				(clearance outline)
				(anchor circle)
			)
			(primitives
				(gr_poly
					(pts
						(arc
							(start -0.1778 -0.2794)
							(mid -0.249642 -0.249642)
							(end -0.2794 -0.1778)
						)
						(arc
							(start -0.2794 0.1778)
							(mid -0.249642 0.249642)
							(end -0.1778 0.2794)
						)
						(arc
							(start 0.1778 0.2794)
							(mid 0.249642 0.249642)
							(end 0.2794 0.1778)
						)
						(arc
							(start 0.2794 -0.1778)
							(mid 0.249642 -0.249642)
							(end 0.1778 -0.2794)
						)
					)
					(width 0)
					(fill yes)
				)
			)
		)
	)
	(footprint ""
		(layer "F.Cu")
		(at 186.817 -108.4072 90)
		(property "Reference" "R553"
			(at 0 0 90)
			(layer "F.SilkS")
			(hide yes)
			(effects
				(font
					(size 1.27 1.27)
				)
			)
		)
		(property "Value" "4K7R2F-GP"
			(at 0.064008 -3.993896 90)
			(unlocked yes)
			(layer "F.Fab")
			(hide yes)
			(effects
				(font
					(size 1.016 1.016)
					(thickness 0.1524)
				)
			)
		)
		(property "Device Type" "R402H16"
			(at 0.064008 -5.517896 90)
			(unlocked yes)
			(layer "F.Fab")
			(hide yes)
			(effects
				(font
					(size 1.016 1.016)
					(thickness 0.1524)
				)
			)
		)
		(duplicate_pad_numbers_are_jumpers no)
		(fp_line
			(start 0.508 -0.9398)
			(end -0.508 -0.9398)
			(stroke
				(width 0.1524)
				(type default)
			)
			(layer "F.SilkS")
		)
		(fp_line
			(start -0.508 -0.9398)
			(end -0.508 0.9398)
			(stroke
				(width 0.1524)
				(type default)
			)
			(layer "F.SilkS")
		)
		(fp_rect
			(start -0.508 0.9398)
			(end 0.508 -0.9398)
			(stroke
				(width 0)
				(type default)
			)
			(fill no)
			(layer "F.CrtYd")
		)
		(fp_rect
			(start -0.508 0.9398)
			(end 0.508 -0.9398)
			(stroke
				(width 0)
				(type default)
			)
			(fill no)
			(layer "F.Fab")
		)
		(pad "1" smd custom
			(at 0 -0.4445 90)
			(size 0.1397 0.1397)
			(layers "F.Cu" "F.Mask" "F.Paste")
			(net "TEMP_1_A2")
			(options
				(clearance outline)
				(anchor circle)
			)
			(primitives
				(gr_poly
					(pts
						(arc
							(start -0.1778 -0.2794)
							(mid -0.249642 -0.249642)
							(end -0.2794 -0.1778)
						)
						(arc
							(start -0.2794 0.1778)
							(mid -0.249642 0.249642)
							(end -0.1778 0.2794)
						)
						(arc
							(start 0.1778 0.2794)
							(mid 0.249642 0.249642)
							(end 0.2794 0.1778)
						)
						(arc
							(start 0.2794 -0.1778)
							(mid 0.249642 -0.249642)
							(end 0.1778 -0.2794)
						)
					)
					(width 0)
					(fill yes)
				)
			)
		)
		(pad "2" smd custom
			(at 0 0.4445 90)
			(size 0.1397 0.1397)
			(layers "F.Cu" "F.Mask" "F.Paste")
			(net "GND")
			(options
				(clearance outline)
				(anchor circle)
			)
			(primitives
				(gr_poly
					(pts
						(arc
							(start -0.1778 -0.2794)
							(mid -0.249642 -0.249642)
							(end -0.2794 -0.1778)
						)
						(arc
							(start -0.2794 0.1778)
							(mid -0.249642 0.249642)
							(end -0.1778 0.2794)
						)
						(arc
							(start 0.1778 0.2794)
							(mid 0.249642 0.249642)
							(end 0.2794 0.1778)
						)
						(arc
							(start 0.2794 -0.1778)
							(mid 0.249642 -0.249642)
							(end 0.1778 -0.2794)
						)
					)
					(width 0)
					(fill yes)
				)
			)
		)
	)
	(footprint ""
		(layer "F.Cu")
		(at 166.585138 -9.171178)
		(property "Reference" "C217"
			(at 0 0 0)
			(layer "F.SilkS")
			(hide yes)
			(effects
				(font
					(size 1.27 1.27)
				)
			)
		)
		(property "Value" "SC10U6D3V5KX-4GP"
			(at -0.0762 -6.1214 0)
			(unlocked yes)
			(layer "F.Fab")
			(hide yes)
			(effects
				(font
					(size 1.016 1.016)
					(thickness 0.1524)
				)
			)
		)
		(property "Device Type" "C805H58"
			(at -0.0762 -8.1534 0)
			(unlocked yes)
			(layer "F.Fab")
			(hide yes)
			(effects
				(font
					(size 1.016 1.016)
					(thickness 0.1524)
				)
			)
		)
		(duplicate_pad_numbers_are_jumpers no)
		(fp_line
			(start 0.635 0)
			(end -0.635 0)
			(stroke
				(width 0.508)
				(type default)
			)
			(layer "F.SilkS")
		)
		(fp_rect
			(start -0.9652 1.778)
			(end 0.9652 -1.778)
			(stroke
				(width 0)
				(type default)
			)
			(fill no)
			(layer "F.CrtYd")
		)
		(fp_poly
			(pts
				(xy -0.9652 -1.778) (xy 0.9652 -1.778) (xy 0.9652 1.778) (xy -0.9652 1.778)
			)
			(stroke
				(width 0)
				(type default)
			)
			(fill no)
			(layer "F.Fab")
		)
		(pad "1" smd rect
			(at 0 -0.9652)
			(size 1.397 1.143)
			(layers "F.Cu" "F.Mask" "F.Paste")
			(net "P1V8_STBY")
		)
		(pad "2" smd rect
			(at 0 0.9652)
			(size 1.397 1.143)
			(layers "F.Cu" "F.Mask" "F.Paste")
			(net "GND")
		)
	)
	(footprint ""
		(layer "F.Cu")
		(at 210.928204 -122.666506)
		(property "Reference" "TP212"
			(at 0 0 0)
			(layer "F.SilkS")
			(hide yes)
			(effects
				(font
					(size 1.27 1.27)
				)
			)
		)
		(property "Value" "TPAD28-2-GP"
			(at -0.0127 -1.6637 0)
			(unlocked yes)
			(layer "F.Fab")
			(hide yes)
			(effects
				(font
					(size 1.016 1.016)
					(thickness 0.1524)
				)
			)
		)
		(property "Device Type" "TPAD28"
			(at -0.0127 -3.1877 0)
			(unlocked yes)
			(layer "F.Fab")
			(hide yes)
			(effects
				(font
					(size 1.016 1.016)
					(thickness 0.1524)
				)
			)
		)
		(duplicate_pad_numbers_are_jumpers no)
		(fp_poly
			(pts
				(arc
					(start 0.3556 0)
					(mid -0.3556 0)
					(end 0.3556 0)
				)
			)
			(stroke
				(width 0)
				(type default)
			)
			(fill no)
			(layer "F.CrtYd")
		)
		(fp_poly
			(pts
				(arc
					(start 0.6096 0)
					(mid -0.6096 0)
					(end 0.6096 0)
				)
			)
			(stroke
				(width 0)
				(type default)
			)
			(fill no)
			(layer "F.Fab")
		)
		(pad "1" smd circle
			(at 0 0)
			(size 0.7112 0.7112)
			(layers "F.Cu" "F.Mask" "F.Paste")
			(net "TP_M2_1_MFG_DAT")
		)
	)
	(footprint ""
		(layer "F.Cu")
		(at 199.1614 -6.35 90)
		(property "Reference" "R737"
			(at 0 0 90)
			(layer "F.SilkS")
			(hide yes)
			(effects
				(font
					(size 1.27 1.27)
				)
			)
		)
		(property "Value" "120R3F-L-GP"
			(at -0.0254 -2.5146 90)
			(unlocked yes)
			(layer "F.Fab")
			(hide yes)
			(effects
				(font
					(size 1.016 1.016)
					(thickness 0.1524)
				)
			)
		)
		(property "Device Type" "R603H22"
			(at -0.0254 -4.0386 90)
			(unlocked yes)
			(layer "F.Fab")
			(hide yes)
			(effects
				(font
					(size 1.016 1.016)
					(thickness 0.1524)
				)
			)
		)
		(duplicate_pad_numbers_are_jumpers no)
		(fp_line
			(start 0.2032 0)
			(end 0.4826 0)
			(stroke
				(width 0.2032)
				(type default)
			)
			(layer "F.SilkS")
		)
		(fp_line
			(start -0.4826 0)
			(end -0.2032 0)
			(stroke
				(width 0.2032)
				(type default)
			)
			(layer "F.SilkS")
		)
		(fp_rect
			(start -0.5842 1.3335)
			(end 0.5842 -1.3335)
			(stroke
				(width 0)
				(type default)
			)
			(fill no)
			(layer "F.CrtYd")
		)
		(fp_rect
			(start -0.5842 1.3335)
			(end 0.5842 -1.3335)
			(stroke
				(width 0)
				(type default)
			)
			(fill no)
			(layer "F.Fab")
		)
		(pad "1" smd custom
			(at 0 -0.762 90)
			(size 0.2159 0.2159)
			(layers "F.Cu" "F.Mask" "F.Paste")
			(net "ML_PWR_YELLOW_LED")
			(options
				(clearance outline)
				(anchor circle)
			)
			(primitives
				(gr_poly
					(pts
						(arc
							(start -0.3302 -0.4318)
							(mid -0.402042 -0.402042)
							(end -0.4318 -0.3302)
						)
						(arc
							(start -0.4318 0.3302)
							(mid -0.402042 0.402042)
							(end -0.3302 0.4318)
						)
						(arc
							(start 0.3302 0.4318)
							(mid 0.402042 0.402042)
							(end 0.4318 0.3302)
						)
						(arc
							(start 0.4318 -0.3302)
							(mid 0.402042 -0.402042)
							(end 0.3302 -0.4318)
						)
					)
					(width 0)
					(fill yes)
				)
			)
		)
		(pad "2" smd custom
			(at 0 0.762 90)
			(size 0.2159 0.2159)
			(layers "F.Cu" "F.Mask" "F.Paste")
			(net "ML_PWR_YELLOW_LED_R")
			(options
				(clearance outline)
				(anchor circle)
			)
			(primitives
				(gr_poly
					(pts
						(arc
							(start -0.3302 -0.4318)
							(mid -0.402042 -0.402042)
							(end -0.4318 -0.3302)
						)
						(arc
							(start -0.4318 0.3302)
							(mid -0.402042 0.402042)
							(end -0.3302 0.4318)
						)
						(arc
							(start 0.3302 0.4318)
							(mid 0.402042 0.402042)
							(end 0.4318 0.3302)
						)
						(arc
							(start 0.4318 -0.3302)
							(mid 0.402042 -0.402042)
							(end 0.3302 -0.4318)
						)
					)
					(width 0)
					(fill yes)
				)
			)
		)
	)
	(footprint ""
		(layer "F.Cu")
		(at 29.806646 -176.618138 180)
		(property "Reference" "R494"
			(at 0 0 180)
			(layer "F.SilkS")
			(hide yes)
			(effects
				(font
					(size 1.27 1.27)
				)
			)
		)
		(property "Value" "57K6R2D-GP"
			(at 0.064008 -3.993896 180)
			(unlocked yes)
			(layer "F.Fab")
			(hide yes)
			(effects
				(font
					(size 1.016 1.016)
					(thickness 0.1524)
				)
			)
		)
		(property "Device Type" "R402H16"
			(at 0.064008 -5.517896 180)
			(unlocked yes)
			(layer "F.Fab")
			(hide yes)
			(effects
				(font
					(size 1.016 1.016)
					(thickness 0.1524)
				)
			)
		)
		(duplicate_pad_numbers_are_jumpers no)
		(fp_line
			(start 0.508 -0.9398)
			(end -0.508 -0.9398)
			(stroke
				(width 0.1524)
				(type default)
			)
			(layer "F.SilkS")
		)
		(fp_line
			(start -0.508 -0.9398)
			(end -0.508 0.9398)
			(stroke
				(width 0.1524)
				(type default)
			)
			(layer "F.SilkS")
		)
		(fp_rect
			(start -0.508 0.9398)
			(end 0.508 -0.9398)
			(stroke
				(width 0)
				(type default)
			)
			(fill no)
			(layer "F.CrtYd")
		)
		(fp_rect
			(start -0.508 0.9398)
			(end 0.508 -0.9398)
			(stroke
				(width 0)
				(type default)
			)
			(fill no)
			(layer "F.Fab")
		)
		(pad "1" smd custom
			(at 0 -0.4445 180)
			(size 0.1397 0.1397)
			(layers "F.Cu" "F.Mask" "F.Paste")
			(net "AGND_P3V3_STBY")
			(options
				(clearance outline)
				(anchor circle)
			)
			(primitives
				(gr_poly
					(pts
						(arc
							(start -0.1778 -0.2794)
							(mid -0.249642 -0.249642)
							(end -0.2794 -0.1778)
						)
						(arc
							(start -0.2794 0.1778)
							(mid -0.249642 0.249642)
							(end -0.1778 0.2794)
						)
						(arc
							(start 0.1778 0.2794)
							(mid 0.249642 0.249642)
							(end 0.2794 0.1778)
						)
						(arc
							(start 0.2794 -0.1778)
							(mid 0.249642 -0.249642)
							(end 0.1778 -0.2794)
						)
					)
					(width 0)
					(fill yes)
				)
			)
		)
		(pad "2" smd custom
			(at 0 0.4445 180)
			(size 0.1397 0.1397)
			(layers "F.Cu" "F.Mask" "F.Paste")
			(net "P3V3_STBY_TRIP")
			(options
				(clearance outline)
				(anchor circle)
			)
			(primitives
				(gr_poly
					(pts
						(arc
							(start -0.1778 -0.2794)
							(mid -0.249642 -0.249642)
							(end -0.2794 -0.1778)
						)
						(arc
							(start -0.2794 0.1778)
							(mid -0.249642 0.249642)
							(end -0.1778 0.2794)
						)
						(arc
							(start 0.1778 0.2794)
							(mid 0.249642 0.249642)
							(end 0.2794 0.1778)
						)
						(arc
							(start 0.2794 -0.1778)
							(mid 0.249642 -0.249642)
							(end 0.1778 -0.2794)
						)
					)
					(width 0)
					(fill yes)
				)
			)
		)
	)
	(footprint ""
		(layer "F.Cu")
		(at 77.283818 -93.355668 90)
		(property "Reference" "VIA8"
			(at 0 0 90)
			(layer "F.SilkS")
			(hide yes)
			(effects
				(font
					(size 1.27 1.27)
				)
			)
		)
		(property "Value" "85OHM-8L-1D6MM-L16L18-GP"
			(at 4.064 0.6096 90)
			(unlocked yes)
			(layer "F.Fab")
			(hide yes)
			(effects
				(font
					(size 1.016 1.016)
					(thickness 0.1524)
				)
			)
		)
		(property "Device Type" "VIA-PCIE-4P-368076"
			(at 4.064 -0.9144 90)
			(unlocked yes)
			(layer "F.Fab")
			(hide yes)
			(effects
				(font
					(size 1.016 1.016)
					(thickness 0.1524)
				)
			)
		)
		(duplicate_pad_numbers_are_jumpers no)
		(fp_rect
			(start -1.8415 0.381)
			(end 1.8415 -0.381)
			(stroke
				(width 0)
				(type default)
			)
			(fill no)
			(layer "F.CrtYd")
		)
		(fp_rect
			(start -1.8415 0.381)
			(end 1.8415 -0.381)
			(stroke
				(width 0)
				(type default)
			)
			(fill no)
			(layer "F.Fab")
		)
		(pad "1" thru_hole circle
			(at -1.4605 0 90)
			(size 0.508 0.508)
			(drill 0.254)
			(layers "*.Cu" "*.Mask")
			(remove_unused_layers no)
			(net "GND")
			(clearance 0.127)
			(thermal_gap 0.127)
		)
		(pad "2" thru_hole circle
			(at -0.4445 0 90)
			(size 0.508 0.508)
			(drill 0.254)
			(layers "*.Cu" "*.Mask")
			(remove_unused_layers no)
			(net "PCIE_COMP_TO_IOM_23_DP")
			(clearance 0.127)
			(thermal_gap 0.127)
		)
		(pad "3" thru_hole circle
			(at 0.4445 0 90)
			(size 0.508 0.508)
			(drill 0.254)
			(layers "*.Cu" "*.Mask")
			(remove_unused_layers no)
			(net "PCIE_COMP_TO_IOM_23_DN")
			(clearance 0.127)
			(thermal_gap 0.127)
		)
		(pad "4" thru_hole circle
			(at 1.4605 0 90)
			(size 0.508 0.508)
			(drill 0.254)
			(layers "*.Cu" "*.Mask")
			(remove_unused_layers no)
			(net "GND")
			(clearance 0.127)
			(thermal_gap 0.127)
		)
	)
	(footprint ""
		(layer "F.Cu")
		(at 77.355192 -67.756532 90)
		(property "Reference" "VIA25"
			(at 0 0 90)
			(layer "F.SilkS")
			(hide yes)
			(effects
				(font
					(size 1.27 1.27)
				)
			)
		)
		(property "Value" "85OHM-8L-1D6MM-L16L18-GP"
			(at 4.064 0.6096 90)
			(unlocked yes)
			(layer "F.Fab")
			(hide yes)
			(effects
				(font
					(size 1.016 1.016)
					(thickness 0.1524)
				)
			)
		)
		(property "Device Type" "VIA-PCIE-4P-368076"
			(at 4.064 -0.9144 90)
			(unlocked yes)
			(layer "F.Fab")
			(hide yes)
			(effects
				(font
					(size 1.016 1.016)
					(thickness 0.1524)
				)
			)
		)
		(duplicate_pad_numbers_are_jumpers no)
		(fp_rect
			(start -1.8415 0.381)
			(end 1.8415 -0.381)
			(stroke
				(width 0)
				(type default)
			)
			(fill no)
			(layer "F.CrtYd")
		)
		(fp_rect
			(start -1.8415 0.381)
			(end 1.8415 -0.381)
			(stroke
				(width 0)
				(type default)
			)
			(fill no)
			(layer "F.Fab")
		)
		(pad "1" thru_hole circle
			(at -1.4605 0 90)
			(size 0.508 0.508)
			(drill 0.254)
			(layers "*.Cu" "*.Mask")
			(remove_unused_layers no)
			(net "GND")
			(clearance 0.127)
			(thermal_gap 0.127)
		)
		(pad "2" thru_hole circle
			(at -0.4445 0 90)
			(size 0.508 0.508)
			(drill 0.254)
			(layers "*.Cu" "*.Mask")
			(remove_unused_layers no)
			(net "PCIE_COMP_TO_IOM_CLK_4_DP")
			(clearance 0.127)
			(thermal_gap 0.127)
		)
		(pad "3" thru_hole circle
			(at 0.4445 0 90)
			(size 0.508 0.508)
			(drill 0.254)
			(layers "*.Cu" "*.Mask")
			(remove_unused_layers no)
			(net "PCIE_COMP_TO_IOM_CLK_4_DN")
			(clearance 0.127)
			(thermal_gap 0.127)
		)
		(pad "4" thru_hole circle
			(at 1.4605 0 90)
			(size 0.508 0.508)
			(drill 0.254)
			(layers "*.Cu" "*.Mask")
			(remove_unused_layers no)
			(net "GND")
			(clearance 0.127)
			(thermal_gap 0.127)
		)
	)
	(footprint ""
		(layer "F.Cu")
		(at 152.132538 -16.816578 180)
		(property "Reference" "R511"
			(at 0 0 180)
			(layer "F.SilkS")
			(hide yes)
			(effects
				(font
					(size 1.27 1.27)
				)
			)
		)
		(property "Value" "2D2R3-1-U-GP"
			(at -0.0254 -2.5146 180)
			(unlocked yes)
			(layer "F.Fab")
			(hide yes)
			(effects
				(font
					(size 1.016 1.016)
					(thickness 0.1524)
				)
			)
		)
		(property "Device Type" "R603H22"
			(at -0.0254 -4.0386 180)
			(unlocked yes)
			(layer "F.Fab")
			(hide yes)
			(effects
				(font
					(size 1.016 1.016)
					(thickness 0.1524)
				)
			)
		)
		(duplicate_pad_numbers_are_jumpers no)
		(fp_line
			(start 0.2032 0)
			(end 0.4826 0)
			(stroke
				(width 0.2032)
				(type default)
			)
			(layer "F.SilkS")
		)
		(fp_line
			(start -0.4826 0)
			(end -0.2032 0)
			(stroke
				(width 0.2032)
				(type default)
			)
			(layer "F.SilkS")
		)
		(fp_rect
			(start -0.5842 1.3335)
			(end 0.5842 -1.3335)
			(stroke
				(width 0)
				(type default)
			)
			(fill no)
			(layer "F.CrtYd")
		)
		(fp_rect
			(start -0.5842 1.3335)
			(end 0.5842 -1.3335)
			(stroke
				(width 0)
				(type default)
			)
			(fill no)
			(layer "F.Fab")
		)
		(pad "1" smd custom
			(at 0 -0.762 180)
			(size 0.2159 0.2159)
			(layers "F.Cu" "F.Mask" "F.Paste")
			(net "P12V_STBY_VCC_PU4")
			(options
				(clearance outline)
				(anchor circle)
			)
			(primitives
				(gr_poly
					(pts
						(arc
							(start -0.3302 -0.4318)
							(mid -0.402042 -0.402042)
							(end -0.4318 -0.3302)
						)
						(arc
							(start -0.4318 0.3302)
							(mid -0.402042 0.402042)
							(end -0.3302 0.4318)
						)
						(arc
							(start 0.3302 0.4318)
							(mid 0.402042 0.402042)
							(end 0.4318 0.3302)
						)
						(arc
							(start 0.4318 -0.3302)
							(mid 0.402042 -0.402042)
							(end 0.3302 -0.4318)
						)
					)
					(width 0)
					(fill yes)
				)
			)
		)
		(pad "2" smd custom
			(at 0 0.762 180)
			(size 0.2159 0.2159)
			(layers "F.Cu" "F.Mask" "F.Paste")
			(net "P12V_STBY")
			(options
				(clearance outline)
				(anchor circle)
			)
			(primitives
				(gr_poly
					(pts
						(arc
							(start -0.3302 -0.4318)
							(mid -0.402042 -0.402042)
							(end -0.4318 -0.3302)
						)
						(arc
							(start -0.4318 0.3302)
							(mid -0.402042 0.402042)
							(end -0.3302 0.4318)
						)
						(arc
							(start 0.3302 0.4318)
							(mid 0.402042 0.402042)
							(end 0.4318 0.3302)
						)
						(arc
							(start 0.4318 -0.3302)
							(mid 0.402042 -0.402042)
							(end 0.3302 -0.4318)
						)
					)
					(width 0)
					(fill yes)
				)
			)
		)
	)
	(footprint ""
		(layer "F.Cu")
		(at 115.135152 -13.848588 -90)
		(property "Reference" "C128"
			(at 0 0 270)
			(layer "F.SilkS")
			(hide yes)
			(effects
				(font
					(size 1.27 1.27)
				)
			)
		)
		(property "Value" "SC1U25V3KX-GP"
			(at 0 -2.8194 270)
			(unlocked yes)
			(layer "F.Fab")
			(hide yes)
			(effects
				(font
					(size 1.016 1.016)
					(thickness 0.1524)
				)
			)
		)
		(property "Device Type" "C603H36"
			(at 0 -4.3434 270)
			(unlocked yes)
			(layer "F.Fab")
			(hide yes)
			(effects
				(font
					(size 1.016 1.016)
					(thickness 0.1524)
				)
			)
		)
		(duplicate_pad_numbers_are_jumpers no)
		(fp_line
			(start 0.508 0)
			(end -0.508 0)
			(stroke
				(width 0.2032)
				(type default)
			)
			(layer "F.SilkS")
		)
		(fp_rect
			(start -0.5842 1.3335)
			(end 0.5842 -1.3335)
			(stroke
				(width 0)
				(type default)
			)
			(fill no)
			(layer "F.CrtYd")
		)
		(fp_rect
			(start -0.5842 1.3335)
			(end 0.5842 -1.3335)
			(stroke
				(width 0)
				(type default)
			)
			(fill no)
			(layer "F.Fab")
		)
		(pad "1" smd custom
			(at 0 -0.762 270)
			(size 0.2159 0.2159)
			(layers "F.Cu" "F.Mask" "F.Paste")
			(net "MB0_VCC")
			(options
				(clearance outline)
				(anchor circle)
			)
			(primitives
				(gr_poly
					(pts
						(arc
							(start -0.3302 -0.4318)
							(mid -0.402042 -0.402042)
							(end -0.4318 -0.3302)
						)
						(arc
							(start -0.4318 0.3302)
							(mid -0.402042 0.402042)
							(end -0.3302 0.4318)
						)
						(arc
							(start 0.3302 0.4318)
							(mid 0.402042 0.402042)
							(end 0.4318 0.3302)
						)
						(arc
							(start 0.4318 -0.3302)
							(mid 0.402042 -0.402042)
							(end 0.3302 -0.4318)
						)
					)
					(width 0)
					(fill yes)
				)
			)
		)
		(pad "2" smd custom
			(at 0 0.762 270)
			(size 0.2159 0.2159)
			(layers "F.Cu" "F.Mask" "F.Paste")
			(net "AGND_CURRENT_MON")
			(options
				(clearance outline)
				(anchor circle)
			)
			(primitives
				(gr_poly
					(pts
						(arc
							(start -0.3302 -0.4318)
							(mid -0.402042 -0.402042)
							(end -0.4318 -0.3302)
						)
						(arc
							(start -0.4318 0.3302)
							(mid -0.402042 0.402042)
							(end -0.3302 0.4318)
						)
						(arc
							(start 0.3302 0.4318)
							(mid 0.402042 0.402042)
							(end 0.4318 0.3302)
						)
						(arc
							(start 0.4318 -0.3302)
							(mid 0.402042 -0.402042)
							(end 0.3302 -0.4318)
						)
					)
					(width 0)
					(fill yes)
				)
			)
		)
	)
	(footprint ""
		(layer "F.Cu")
		(at 12.2428 -172.030136)
		(property "Reference" "R534"
			(at 0 0 0)
			(layer "F.SilkS")
			(hide yes)
			(effects
				(font
					(size 1.27 1.27)
				)
			)
		)
		(property "Value" "4K75R2F-1-GP"
			(at 0.064008 -3.993896 0)
			(unlocked yes)
			(layer "F.Fab")
			(hide yes)
			(effects
				(font
					(size 1.016 1.016)
					(thickness 0.1524)
				)
			)
		)
		(property "Device Type" "R402H16"
			(at 0.064008 -5.517896 0)
			(unlocked yes)
			(layer "F.Fab")
			(hide yes)
			(effects
				(font
					(size 1.016 1.016)
					(thickness 0.1524)
				)
			)
		)
		(duplicate_pad_numbers_are_jumpers no)
		(fp_line
			(start -0.508 -0.9398)
			(end -0.508 0.9398)
			(stroke
				(width 0.1524)
				(type default)
			)
			(layer "F.SilkS")
		)
		(fp_line
			(start 0.508 -0.9398)
			(end -0.508 -0.9398)
			(stroke
				(width 0.1524)
				(type default)
			)
			(layer "F.SilkS")
		)
		(fp_rect
			(start -0.508 0.9398)
			(end 0.508 -0.9398)
			(stroke
				(width 0)
				(type default)
			)
			(fill no)
			(layer "F.CrtYd")
		)
		(fp_rect
			(start -0.508 0.9398)
			(end 0.508 -0.9398)
			(stroke
				(width 0)
				(type default)
			)
			(fill no)
			(layer "F.Fab")
		)
		(pad "1" smd custom
			(at 0 -0.4445)
			(size 0.1397 0.1397)
			(layers "F.Cu" "F.Mask" "F.Paste")
			(net "P3V3_STBY")
			(options
				(clearance outline)
				(anchor circle)
			)
			(primitives
				(gr_poly
					(pts
						(arc
							(start -0.1778 -0.2794)
							(mid -0.249642 -0.249642)
							(end -0.2794 -0.1778)
						)
						(arc
							(start -0.2794 0.1778)
							(mid -0.249642 0.249642)
							(end -0.1778 0.2794)
						)
						(arc
							(start 0.1778 0.2794)
							(mid 0.249642 0.249642)
							(end 0.2794 0.1778)
						)
						(arc
							(start 0.2794 -0.1778)
							(mid 0.249642 -0.249642)
							(end 0.1778 -0.2794)
						)
					)
					(width 0)
					(fill yes)
				)
			)
		)
		(pad "2" smd custom
			(at 0 0.4445)
			(size 0.1397 0.1397)
			(layers "F.Cu" "F.Mask" "F.Paste")
			(net "TPS74801_P1V2_STBY_EN")
			(options
				(clearance outline)
				(anchor circle)
			)
			(primitives
				(gr_poly
					(pts
						(arc
							(start -0.1778 -0.2794)
							(mid -0.249642 -0.249642)
							(end -0.2794 -0.1778)
						)
						(arc
							(start -0.2794 0.1778)
							(mid -0.249642 0.249642)
							(end -0.1778 0.2794)
						)
						(arc
							(start 0.1778 0.2794)
							(mid 0.249642 0.249642)
							(end 0.2794 0.1778)
						)
						(arc
							(start 0.2794 -0.1778)
							(mid 0.249642 -0.249642)
							(end 0.1778 -0.2794)
						)
					)
					(width 0)
					(fill yes)
				)
			)
		)
	)
	(footprint ""
		(layer "F.Cu")
		(at 54.0004 -131.7498)
		(property "Reference" "R147"
			(at 0 0 0)
			(layer "F.SilkS")
			(hide yes)
			(effects
				(font
					(size 1.27 1.27)
				)
			)
		)
		(property "Value" "100KR2F-L1-GP"
			(at 0.064008 -3.993896 0)
			(unlocked yes)
			(layer "F.Fab")
			(hide yes)
			(effects
				(font
					(size 1.016 1.016)
					(thickness 0.1524)
				)
			)
		)
		(property "Device Type" "R402H16"
			(at 0.064008 -5.517896 0)
			(unlocked yes)
			(layer "F.Fab")
			(hide yes)
			(effects
				(font
					(size 1.016 1.016)
					(thickness 0.1524)
				)
			)
		)
		(duplicate_pad_numbers_are_jumpers no)
		(fp_line
			(start -0.508 -0.9398)
			(end -0.508 0.9398)
			(stroke
				(width 0.1524)
				(type default)
			)
			(layer "F.SilkS")
		)
		(fp_line
			(start 0.508 -0.9398)
			(end -0.508 -0.9398)
			(stroke
				(width 0.1524)
				(type default)
			)
			(layer "F.SilkS")
		)
		(fp_rect
			(start -0.508 0.9398)
			(end 0.508 -0.9398)
			(stroke
				(width 0)
				(type default)
			)
			(fill no)
			(layer "F.CrtYd")
		)
		(fp_rect
			(start -0.508 0.9398)
			(end 0.508 -0.9398)
			(stroke
				(width 0)
				(type default)
			)
			(fill no)
			(layer "F.Fab")
		)
		(pad "1" smd custom
			(at 0 -0.4445)
			(size 0.1397 0.1397)
			(layers "F.Cu" "F.Mask" "F.Paste")
			(net "LPC_CPU_FRAME_N")
			(options
				(clearance outline)
				(anchor circle)
			)
			(primitives
				(gr_poly
					(pts
						(arc
							(start -0.1778 -0.2794)
							(mid -0.249642 -0.249642)
							(end -0.2794 -0.1778)
						)
						(arc
							(start -0.2794 0.1778)
							(mid -0.249642 0.249642)
							(end -0.1778 0.2794)
						)
						(arc
							(start 0.1778 0.2794)
							(mid 0.249642 0.249642)
							(end 0.2794 0.1778)
						)
						(arc
							(start 0.2794 -0.1778)
							(mid 0.249642 -0.249642)
							(end 0.1778 -0.2794)
						)
					)
					(width 0)
					(fill yes)
				)
			)
		)
		(pad "2" smd custom
			(at 0 0.4445)
			(size 0.1397 0.1397)
			(layers "F.Cu" "F.Mask" "F.Paste")
			(net "GND")
			(options
				(clearance outline)
				(anchor circle)
			)
			(primitives
				(gr_poly
					(pts
						(arc
							(start -0.1778 -0.2794)
							(mid -0.249642 -0.249642)
							(end -0.2794 -0.1778)
						)
						(arc
							(start -0.2794 0.1778)
							(mid -0.249642 0.249642)
							(end -0.1778 0.2794)
						)
						(arc
							(start 0.1778 0.2794)
							(mid 0.249642 0.249642)
							(end 0.2794 0.1778)
						)
						(arc
							(start 0.2794 -0.1778)
							(mid 0.249642 -0.249642)
							(end 0.1778 -0.2794)
						)
					)
					(width 0)
					(fill yes)
				)
			)
		)
	)
	(footprint ""
		(layer "F.Cu")
		(at 99.297744 -159.65932 -90)
		(property "Reference" "R20"
			(at 0 0 270)
			(layer "F.SilkS")
			(hide yes)
			(effects
				(font
					(size 1.27 1.27)
				)
			)
		)
		(property "Value" "4K7R2F-GP"
			(at 0.064008 -3.993896 270)
			(unlocked yes)
			(layer "F.Fab")
			(hide yes)
			(effects
				(font
					(size 1.016 1.016)
					(thickness 0.1524)
				)
			)
		)
		(property "Device Type" "R402H16"
			(at 0.064008 -5.517896 270)
			(unlocked yes)
			(layer "F.Fab")
			(hide yes)
			(effects
				(font
					(size 1.016 1.016)
					(thickness 0.1524)
				)
			)
		)
		(duplicate_pad_numbers_are_jumpers no)
		(fp_line
			(start -0.508 -0.9398)
			(end -0.508 0.9398)
			(stroke
				(width 0.1524)
				(type default)
			)
			(layer "F.SilkS")
		)
		(fp_line
			(start 0.508 -0.9398)
			(end -0.508 -0.9398)
			(stroke
				(width 0.1524)
				(type default)
			)
			(layer "F.SilkS")
		)
		(fp_rect
			(start -0.508 0.9398)
			(end 0.508 -0.9398)
			(stroke
				(width 0)
				(type default)
			)
			(fill no)
			(layer "F.CrtYd")
		)
		(fp_rect
			(start -0.508 0.9398)
			(end 0.508 -0.9398)
			(stroke
				(width 0)
				(type default)
			)
			(fill no)
			(layer "F.Fab")
		)
		(pad "1" smd custom
			(at 0 -0.4445 270)
			(size 0.1397 0.1397)
			(layers "F.Cu" "F.Mask" "F.Paste")
			(net "P3V3_STBY")
			(options
				(clearance outline)
				(anchor circle)
			)
			(primitives
				(gr_poly
					(pts
						(arc
							(start -0.1778 -0.2794)
							(mid -0.249642 -0.249642)
							(end -0.2794 -0.1778)
						)
						(arc
							(start -0.2794 0.1778)
							(mid -0.249642 0.249642)
							(end -0.1778 0.2794)
						)
						(arc
							(start 0.1778 0.2794)
							(mid 0.249642 0.249642)
							(end 0.2794 0.1778)
						)
						(arc
							(start 0.2794 -0.1778)
							(mid 0.249642 -0.249642)
							(end 0.1778 -0.2794)
						)
					)
					(width 0)
					(fill yes)
				)
			)
		)
		(pad "2" smd custom
			(at 0 0.4445 270)
			(size 0.1397 0.1397)
			(layers "F.Cu" "F.Mask" "F.Paste")
			(net "VBUS_DET")
			(options
				(clearance outline)
				(anchor circle)
			)
			(primitives
				(gr_poly
					(pts
						(arc
							(start -0.1778 -0.2794)
							(mid -0.249642 -0.249642)
							(end -0.2794 -0.1778)
						)
						(arc
							(start -0.2794 0.1778)
							(mid -0.249642 0.249642)
							(end -0.1778 0.2794)
						)
						(arc
							(start 0.1778 0.2794)
							(mid 0.249642 0.249642)
							(end 0.2794 0.1778)
						)
						(arc
							(start 0.2794 -0.1778)
							(mid 0.249642 -0.249642)
							(end 0.1778 -0.2794)
						)
					)
					(width 0)
					(fill yes)
				)
			)
		)
	)
	(footprint ""
		(layer "F.Cu")
		(at 49.440846 -131.737354 180)
		(property "Reference" "R178"
			(at 0 0 180)
			(layer "F.SilkS")
			(hide yes)
			(effects
				(font
					(size 1.27 1.27)
				)
			)
		)
		(property "Value" "0R2J-2-GP"
			(at 0.064008 -3.993896 180)
			(unlocked yes)
			(layer "F.Fab")
			(hide yes)
			(effects
				(font
					(size 1.016 1.016)
					(thickness 0.1524)
				)
			)
		)
		(property "Device Type" "R402H16"
			(at 0.064008 -5.517896 180)
			(unlocked yes)
			(layer "F.Fab")
			(hide yes)
			(effects
				(font
					(size 1.016 1.016)
					(thickness 0.1524)
				)
			)
		)
		(duplicate_pad_numbers_are_jumpers no)
		(fp_line
			(start 0.508 -0.9398)
			(end -0.508 -0.9398)
			(stroke
				(width 0.1524)
				(type default)
			)
			(layer "F.SilkS")
		)
		(fp_line
			(start -0.508 -0.9398)
			(end -0.508 0.9398)
			(stroke
				(width 0.1524)
				(type default)
			)
			(layer "F.SilkS")
		)
		(fp_rect
			(start -0.508 0.9398)
			(end 0.508 -0.9398)
			(stroke
				(width 0)
				(type default)
			)
			(fill no)
			(layer "F.CrtYd")
		)
		(fp_rect
			(start -0.508 0.9398)
			(end 0.508 -0.9398)
			(stroke
				(width 0)
				(type default)
			)
			(fill no)
			(layer "F.Fab")
		)
		(pad "1" smd custom
			(at 0 -0.4445 180)
			(size 0.1397 0.1397)
			(layers "F.Cu" "F.Mask" "F.Paste")
			(net "I2C_TPM_SDA")
			(options
				(clearance outline)
				(anchor circle)
			)
			(primitives
				(gr_poly
					(pts
						(arc
							(start -0.1778 -0.2794)
							(mid -0.249642 -0.249642)
							(end -0.2794 -0.1778)
						)
						(arc
							(start -0.2794 0.1778)
							(mid -0.249642 0.249642)
							(end -0.1778 0.2794)
						)
						(arc
							(start 0.1778 0.2794)
							(mid 0.249642 0.249642)
							(end 0.2794 0.1778)
						)
						(arc
							(start 0.2794 -0.1778)
							(mid 0.249642 -0.249642)
							(end 0.1778 -0.2794)
						)
					)
					(width 0)
					(fill yes)
				)
			)
		)
		(pad "2" smd custom
			(at 0 0.4445 180)
			(size 0.1397 0.1397)
			(layers "F.Cu" "F.Mask" "F.Paste")
			(net "BMC_SMB14_DAT")
			(options
				(clearance outline)
				(anchor circle)
			)
			(primitives
				(gr_poly
					(pts
						(arc
							(start -0.1778 -0.2794)
							(mid -0.249642 -0.249642)
							(end -0.2794 -0.1778)
						)
						(arc
							(start -0.2794 0.1778)
							(mid -0.249642 0.249642)
							(end -0.1778 0.2794)
						)
						(arc
							(start 0.1778 0.2794)
							(mid 0.249642 0.249642)
							(end 0.2794 0.1778)
						)
						(arc
							(start 0.2794 -0.1778)
							(mid 0.249642 -0.249642)
							(end 0.1778 -0.2794)
						)
					)
					(width 0)
					(fill yes)
				)
			)
		)
	)
	(footprint ""
		(layer "F.Cu")
		(at 17.7546 -129.1082 180)
		(property "Reference" "R220"
			(at 0 0 180)
			(layer "F.SilkS")
			(hide yes)
			(effects
				(font
					(size 1.27 1.27)
				)
			)
		)
		(property "Value" "120R2F-GP"
			(at 0.064008 -3.993896 180)
			(unlocked yes)
			(layer "F.Fab")
			(hide yes)
			(effects
				(font
					(size 1.016 1.016)
					(thickness 0.1524)
				)
			)
		)
		(property "Device Type" "R402H16"
			(at 0.064008 -5.517896 180)
			(unlocked yes)
			(layer "F.Fab")
			(hide yes)
			(effects
				(font
					(size 1.016 1.016)
					(thickness 0.1524)
				)
			)
		)
		(duplicate_pad_numbers_are_jumpers no)
		(fp_line
			(start 0.508 -0.9398)
			(end -0.508 -0.9398)
			(stroke
				(width 0.1524)
				(type default)
			)
			(layer "F.SilkS")
		)
		(fp_line
			(start -0.508 -0.9398)
			(end -0.508 0.9398)
			(stroke
				(width 0.1524)
				(type default)
			)
			(layer "F.SilkS")
		)
		(fp_rect
			(start -0.508 0.9398)
			(end 0.508 -0.9398)
			(stroke
				(width 0)
				(type default)
			)
			(fill no)
			(layer "F.CrtYd")
		)
		(fp_rect
			(start -0.508 0.9398)
			(end 0.508 -0.9398)
			(stroke
				(width 0)
				(type default)
			)
			(fill no)
			(layer "F.Fab")
		)
		(pad "1" smd custom
			(at 0 -0.4445 180)
			(size 0.1397 0.1397)
			(layers "F.Cu" "F.Mask" "F.Paste")
			(net "GND")
			(options
				(clearance outline)
				(anchor circle)
			)
			(primitives
				(gr_poly
					(pts
						(arc
							(start -0.1778 -0.2794)
							(mid -0.249642 -0.249642)
							(end -0.2794 -0.1778)
						)
						(arc
							(start -0.2794 0.1778)
							(mid -0.249642 0.249642)
							(end -0.1778 0.2794)
						)
						(arc
							(start 0.1778 0.2794)
							(mid 0.249642 0.249642)
							(end 0.2794 0.1778)
						)
						(arc
							(start 0.2794 -0.1778)
							(mid 0.249642 -0.249642)
							(end 0.1778 -0.2794)
						)
					)
					(width 0)
					(fill yes)
				)
			)
		)
		(pad "2" smd custom
			(at 0 0.4445 180)
			(size 0.1397 0.1397)
			(layers "F.Cu" "F.Mask" "F.Paste")
			(net "DDR4_ACT")
			(options
				(clearance outline)
				(anchor circle)
			)
			(primitives
				(gr_poly
					(pts
						(arc
							(start -0.1778 -0.2794)
							(mid -0.249642 -0.249642)
							(end -0.2794 -0.1778)
						)
						(arc
							(start -0.2794 0.1778)
							(mid -0.249642 0.249642)
							(end -0.1778 0.2794)
						)
						(arc
							(start 0.1778 0.2794)
							(mid 0.249642 0.249642)
							(end 0.2794 0.1778)
						)
						(arc
							(start 0.2794 -0.1778)
							(mid 0.249642 -0.249642)
							(end 0.1778 -0.2794)
						)
					)
					(width 0)
					(fill yes)
				)
			)
		)
	)
	(footprint ""
		(layer "F.Cu")
		(at 39.839646 -180.64861 90)
		(property "Reference" "R498"
			(at 0 0 90)
			(layer "F.SilkS")
			(hide yes)
			(effects
				(font
					(size 1.27 1.27)
				)
			)
		)
		(property "Value" "0R2J-2-GP"
			(at 0.064008 -3.993896 90)
			(unlocked yes)
			(layer "F.Fab")
			(hide yes)
			(effects
				(font
					(size 1.016 1.016)
					(thickness 0.1524)
				)
			)
		)
		(property "Device Type" "R402H16"
			(at 0.064008 -5.517896 90)
			(unlocked yes)
			(layer "F.Fab")
			(hide yes)
			(effects
				(font
					(size 1.016 1.016)
					(thickness 0.1524)
				)
			)
		)
		(duplicate_pad_numbers_are_jumpers no)
		(fp_line
			(start 0.508 -0.9398)
			(end -0.508 -0.9398)
			(stroke
				(width 0.1524)
				(type default)
			)
			(layer "F.SilkS")
		)
		(fp_line
			(start -0.508 -0.9398)
			(end -0.508 0.9398)
			(stroke
				(width 0.1524)
				(type default)
			)
			(layer "F.SilkS")
		)
		(fp_rect
			(start -0.508 0.9398)
			(end 0.508 -0.9398)
			(stroke
				(width 0)
				(type default)
			)
			(fill no)
			(layer "F.CrtYd")
		)
		(fp_rect
			(start -0.508 0.9398)
			(end 0.508 -0.9398)
			(stroke
				(width 0)
				(type default)
			)
			(fill no)
			(layer "F.Fab")
		)
		(pad "1" smd custom
			(at 0 -0.4445 90)
			(size 0.1397 0.1397)
			(layers "F.Cu" "F.Mask" "F.Paste")
			(net "P3V3_STBY_ROVP")
			(options
				(clearance outline)
				(anchor circle)
			)
			(primitives
				(gr_poly
					(pts
						(arc
							(start -0.1778 -0.2794)
							(mid -0.249642 -0.249642)
							(end -0.2794 -0.1778)
						)
						(arc
							(start -0.2794 0.1778)
							(mid -0.249642 0.249642)
							(end -0.1778 0.2794)
						)
						(arc
							(start 0.1778 0.2794)
							(mid 0.249642 0.249642)
							(end 0.2794 0.1778)
						)
						(arc
							(start 0.2794 -0.1778)
							(mid 0.249642 -0.249642)
							(end 0.1778 -0.2794)
						)
					)
					(width 0)
					(fill yes)
				)
			)
		)
		(pad "2" smd custom
			(at 0 0.4445 90)
			(size 0.1397 0.1397)
			(layers "F.Cu" "F.Mask" "F.Paste")
			(net "AGND_P3V3_STBY")
			(options
				(clearance outline)
				(anchor circle)
			)
			(primitives
				(gr_poly
					(pts
						(arc
							(start -0.1778 -0.2794)
							(mid -0.249642 -0.249642)
							(end -0.2794 -0.1778)
						)
						(arc
							(start -0.2794 0.1778)
							(mid -0.249642 0.249642)
							(end -0.1778 0.2794)
						)
						(arc
							(start 0.1778 0.2794)
							(mid 0.249642 0.249642)
							(end 0.2794 0.1778)
						)
						(arc
							(start 0.2794 -0.1778)
							(mid 0.249642 -0.249642)
							(end 0.1778 -0.2794)
						)
					)
					(width 0)
					(fill yes)
				)
			)
		)
	)
	(footprint ""
		(layer "F.Cu")
		(at 167.426132 -137.220198 -135)
		(property "Reference" "VIA65"
			(at 0 0 225)
			(layer "F.SilkS")
			(hide yes)
			(effects
				(font
					(size 1.27 1.27)
				)
			)
		)
		(property "Value" "85OHM-8L-1D6MM-L16L18-GP"
			(at 4.064105 0.609655 225)
			(unlocked yes)
			(layer "F.Fab")
			(hide yes)
			(effects
				(font
					(size 1.016 1.016)
					(thickness 0.1524)
				)
			)
		)
		(property "Device Type" "VIA-PCIE-4P-368076"
			(at 4.064105 -0.914474 225)
			(unlocked yes)
			(layer "F.Fab")
			(hide yes)
			(effects
				(font
					(size 1.016 1.016)
					(thickness 0.1524)
				)
			)
		)
		(duplicate_pad_numbers_are_jumpers no)
		(fp_poly
			(pts
				(xy -1.841491 -0.381057) (xy 1.841509 -0.381058) (xy 1.841508 0.380942) (xy -1.841491 0.380942)
			)
			(stroke
				(width 0)
				(type default)
			)
			(fill no)
			(layer "F.CrtYd")
		)
		(fp_poly
			(pts
				(xy -1.841491 -0.381057) (xy 1.841509 -0.381058) (xy 1.841508 0.380942) (xy -1.841491 0.380942)
			)
			(stroke
				(width 0)
				(type default)
			)
			(fill no)
			(layer "F.Fab")
		)
		(pad "1" thru_hole circle
			(at -1.460499 0 225)
			(size 0.508 0.508)
			(drill 0.254)
			(layers "*.Cu" "*.Mask")
			(remove_unused_layers no)
			(net "GND")
			(clearance 0.127)
			(thermal_gap 0.127)
		)
		(pad "2" thru_hole circle
			(at -0.4445 0 225)
			(size 0.508 0.508)
			(drill 0.254)
			(layers "*.Cu" "*.Mask")
			(remove_unused_layers no)
			(net "PCIE_IOM_TO_COMP_15_DP")
			(clearance 0.127)
			(thermal_gap 0.127)
		)
		(pad "3" thru_hole circle
			(at 0.4445 0 225)
			(size 0.508 0.508)
			(drill 0.254)
			(layers "*.Cu" "*.Mask")
			(remove_unused_layers no)
			(net "PCIE_IOM_TO_COMP_15_DN")
			(clearance 0.127)
			(thermal_gap 0.127)
		)
		(pad "4" thru_hole circle
			(at 1.460499 0 225)
			(size 0.508 0.508)
			(drill 0.254)
			(layers "*.Cu" "*.Mask")
			(remove_unused_layers no)
			(net "GND")
			(clearance 0.127)
			(thermal_gap 0.127)
		)
	)
	(footprint ""
		(layer "F.Cu")
		(at 99.03333 -144.381474 -90)
		(property "Reference" "R427"
			(at 0 0 270)
			(layer "F.SilkS")
			(hide yes)
			(effects
				(font
					(size 1.27 1.27)
				)
			)
		)
		(property "Value" "0R2J-2-GP"
			(at 0.064008 -3.993896 270)
			(unlocked yes)
			(layer "F.Fab")
			(hide yes)
			(effects
				(font
					(size 1.016 1.016)
					(thickness 0.1524)
				)
			)
		)
		(property "Device Type" "R402H16"
			(at 0.064008 -5.517896 270)
			(unlocked yes)
			(layer "F.Fab")
			(hide yes)
			(effects
				(font
					(size 1.016 1.016)
					(thickness 0.1524)
				)
			)
		)
		(duplicate_pad_numbers_are_jumpers no)
		(fp_line
			(start -0.508 -0.9398)
			(end -0.508 0.9398)
			(stroke
				(width 0.1524)
				(type default)
			)
			(layer "F.SilkS")
		)
		(fp_line
			(start 0.508 -0.9398)
			(end -0.508 -0.9398)
			(stroke
				(width 0.1524)
				(type default)
			)
			(layer "F.SilkS")
		)
		(fp_rect
			(start -0.508 0.9398)
			(end 0.508 -0.9398)
			(stroke
				(width 0)
				(type default)
			)
			(fill no)
			(layer "F.CrtYd")
		)
		(fp_rect
			(start -0.508 0.9398)
			(end 0.508 -0.9398)
			(stroke
				(width 0)
				(type default)
			)
			(fill no)
			(layer "F.Fab")
		)
		(pad "1" smd custom
			(at 0 -0.4445 270)
			(size 0.1397 0.1397)
			(layers "F.Cu" "F.Mask" "F.Paste")
			(net "I2C_DEBUG_SCL_L")
			(options
				(clearance outline)
				(anchor circle)
			)
			(primitives
				(gr_poly
					(pts
						(arc
							(start -0.1778 -0.2794)
							(mid -0.249642 -0.249642)
							(end -0.2794 -0.1778)
						)
						(arc
							(start -0.2794 0.1778)
							(mid -0.249642 0.249642)
							(end -0.1778 0.2794)
						)
						(arc
							(start 0.1778 0.2794)
							(mid 0.249642 0.249642)
							(end 0.2794 0.1778)
						)
						(arc
							(start 0.2794 -0.1778)
							(mid 0.249642 -0.249642)
							(end 0.1778 -0.2794)
						)
					)
					(width 0)
					(fill yes)
				)
			)
		)
		(pad "2" smd custom
			(at 0 0.4445 270)
			(size 0.1397 0.1397)
			(layers "F.Cu" "F.Mask" "F.Paste")
			(net "I2C_DEBUG_SCL_R")
			(options
				(clearance outline)
				(anchor circle)
			)
			(primitives
				(gr_poly
					(pts
						(arc
							(start -0.1778 -0.2794)
							(mid -0.249642 -0.249642)
							(end -0.2794 -0.1778)
						)
						(arc
							(start -0.2794 0.1778)
							(mid -0.249642 0.249642)
							(end -0.1778 0.2794)
						)
						(arc
							(start 0.1778 0.2794)
							(mid 0.249642 0.249642)
							(end 0.2794 0.1778)
						)
						(arc
							(start 0.2794 -0.1778)
							(mid 0.249642 -0.249642)
							(end 0.1778 -0.2794)
						)
					)
					(width 0)
					(fill yes)
				)
			)
		)
	)
	(footprint ""
		(layer "F.Cu")
		(at 62.8142 -138.176 90)
		(property "Reference" "TP74"
			(at 0 0 90)
			(layer "F.SilkS")
			(hide yes)
			(effects
				(font
					(size 1.27 1.27)
				)
			)
		)
		(property "Value" "TPAD28-2-GP"
			(at -0.0127 -1.6637 90)
			(unlocked yes)
			(layer "F.Fab")
			(hide yes)
			(effects
				(font
					(size 1.016 1.016)
					(thickness 0.1524)
				)
			)
		)
		(property "Device Type" "TPAD28"
			(at -0.0127 -3.1877 90)
			(unlocked yes)
			(layer "F.Fab")
			(hide yes)
			(effects
				(font
					(size 1.016 1.016)
					(thickness 0.1524)
				)
			)
		)
		(duplicate_pad_numbers_are_jumpers no)
		(fp_poly
			(pts
				(arc
					(start 0 0.3556)
					(mid 0 -0.3556)
					(end 0 0.3556)
				)
			)
			(stroke
				(width 0)
				(type default)
			)
			(fill no)
			(layer "F.CrtYd")
		)
		(fp_poly
			(pts
				(arc
					(start 0 0.6096)
					(mid 0 -0.6096)
					(end 0 0.6096)
				)
			)
			(stroke
				(width 0)
				(type default)
			)
			(fill no)
			(layer "F.Fab")
		)
		(pad "1" smd circle
			(at 0 0 90)
			(size 0.7112 0.7112)
			(layers "F.Cu" "F.Mask" "F.Paste")
			(net "TP_BMC_GPIOI2")
		)
	)
	(footprint ""
		(layer "F.Cu")
		(at 88.814148 -61.517022 -90)
		(property "Reference" "R5"
			(at 0 0 270)
			(layer "F.SilkS")
			(hide yes)
			(effects
				(font
					(size 1.27 1.27)
				)
			)
		)
		(property "Value" "0R2J-2-GP"
			(at 0.064008 -3.993896 270)
			(unlocked yes)
			(layer "F.Fab")
			(hide yes)
			(effects
				(font
					(size 1.016 1.016)
					(thickness 0.1524)
				)
			)
		)
		(property "Device Type" "R402H16"
			(at 0.064008 -5.517896 270)
			(unlocked yes)
			(layer "F.Fab")
			(hide yes)
			(effects
				(font
					(size 1.016 1.016)
					(thickness 0.1524)
				)
			)
		)
		(duplicate_pad_numbers_are_jumpers no)
		(fp_line
			(start -0.508 -0.9398)
			(end -0.508 0.9398)
			(stroke
				(width 0.1524)
				(type default)
			)
			(layer "F.SilkS")
		)
		(fp_line
			(start 0.508 -0.9398)
			(end -0.508 -0.9398)
			(stroke
				(width 0.1524)
				(type default)
			)
			(layer "F.SilkS")
		)
		(fp_rect
			(start -0.508 0.9398)
			(end 0.508 -0.9398)
			(stroke
				(width 0)
				(type default)
			)
			(fill no)
			(layer "F.CrtYd")
		)
		(fp_rect
			(start -0.508 0.9398)
			(end 0.508 -0.9398)
			(stroke
				(width 0)
				(type default)
			)
			(fill no)
			(layer "F.Fab")
		)
		(pad "1" smd custom
			(at 0 -0.4445 270)
			(size 0.1397 0.1397)
			(layers "F.Cu" "F.Mask" "F.Paste")
			(net "NCSI_RCSDV")
			(options
				(clearance outline)
				(anchor circle)
			)
			(primitives
				(gr_poly
					(pts
						(arc
							(start -0.1778 -0.2794)
							(mid -0.249642 -0.249642)
							(end -0.2794 -0.1778)
						)
						(arc
							(start -0.2794 0.1778)
							(mid -0.249642 0.249642)
							(end -0.1778 0.2794)
						)
						(arc
							(start 0.1778 0.2794)
							(mid 0.249642 0.249642)
							(end 0.2794 0.1778)
						)
						(arc
							(start 0.2794 -0.1778)
							(mid 0.249642 -0.249642)
							(end 0.1778 -0.2794)
						)
					)
					(width 0)
					(fill yes)
				)
			)
		)
		(pad "2" smd custom
			(at 0 0.4445 270)
			(size 0.1397 0.1397)
			(layers "F.Cu" "F.Mask" "F.Paste")
			(net "NCSI_RCSDV_R")
			(options
				(clearance outline)
				(anchor circle)
			)
			(primitives
				(gr_poly
					(pts
						(arc
							(start -0.1778 -0.2794)
							(mid -0.249642 -0.249642)
							(end -0.2794 -0.1778)
						)
						(arc
							(start -0.2794 0.1778)
							(mid -0.249642 0.249642)
							(end -0.1778 0.2794)
						)
						(arc
							(start 0.1778 0.2794)
							(mid 0.249642 0.249642)
							(end 0.2794 0.1778)
						)
						(arc
							(start 0.2794 -0.1778)
							(mid 0.249642 -0.249642)
							(end 0.1778 -0.2794)
						)
					)
					(width 0)
					(fill yes)
				)
			)
		)
	)
	(footprint ""
		(layer "F.Cu")
		(at 18.737072 -15.68577 180)
		(property "Reference" "C26"
			(at 0 0 180)
			(layer "F.SilkS")
			(hide yes)
			(effects
				(font
					(size 1.27 1.27)
				)
			)
		)
		(property "Value" "SC1U16V3KX-5GP"
			(at 0 -2.8194 180)
			(unlocked yes)
			(layer "F.Fab")
			(hide yes)
			(effects
				(font
					(size 1.016 1.016)
					(thickness 0.1524)
				)
			)
		)
		(property "Device Type" "C603H36"
			(at 0 -4.3434 180)
			(unlocked yes)
			(layer "F.Fab")
			(hide yes)
			(effects
				(font
					(size 1.016 1.016)
					(thickness 0.1524)
				)
			)
		)
		(duplicate_pad_numbers_are_jumpers no)
		(fp_line
			(start 0.508 0)
			(end -0.508 0)
			(stroke
				(width 0.2032)
				(type default)
			)
			(layer "F.SilkS")
		)
		(fp_rect
			(start -0.5842 1.3335)
			(end 0.5842 -1.3335)
			(stroke
				(width 0)
				(type default)
			)
			(fill no)
			(layer "F.CrtYd")
		)
		(fp_rect
			(start -0.5842 1.3335)
			(end 0.5842 -1.3335)
			(stroke
				(width 0)
				(type default)
			)
			(fill no)
			(layer "F.Fab")
		)
		(pad "1" smd custom
			(at 0 -0.762 180)
			(size 0.2159 0.2159)
			(layers "F.Cu" "F.Mask" "F.Paste")
			(net "FP_PWR_BTN_N")
			(options
				(clearance outline)
				(anchor circle)
			)
			(primitives
				(gr_poly
					(pts
						(arc
							(start -0.3302 -0.4318)
							(mid -0.402042 -0.402042)
							(end -0.4318 -0.3302)
						)
						(arc
							(start -0.4318 0.3302)
							(mid -0.402042 0.402042)
							(end -0.3302 0.4318)
						)
						(arc
							(start 0.3302 0.4318)
							(mid 0.402042 0.402042)
							(end 0.4318 0.3302)
						)
						(arc
							(start 0.4318 -0.3302)
							(mid 0.402042 -0.402042)
							(end 0.3302 -0.4318)
						)
					)
					(width 0)
					(fill yes)
				)
			)
		)
		(pad "2" smd custom
			(at 0 0.762 180)
			(size 0.2159 0.2159)
			(layers "F.Cu" "F.Mask" "F.Paste")
			(net "GND")
			(options
				(clearance outline)
				(anchor circle)
			)
			(primitives
				(gr_poly
					(pts
						(arc
							(start -0.3302 -0.4318)
							(mid -0.402042 -0.402042)
							(end -0.4318 -0.3302)
						)
						(arc
							(start -0.4318 0.3302)
							(mid -0.402042 0.402042)
							(end -0.3302 0.4318)
						)
						(arc
							(start 0.3302 0.4318)
							(mid 0.402042 0.402042)
							(end 0.4318 0.3302)
						)
						(arc
							(start 0.4318 -0.3302)
							(mid 0.402042 -0.402042)
							(end 0.3302 -0.4318)
						)
					)
					(width 0)
					(fill yes)
				)
			)
		)
	)
	(footprint ""
		(layer "F.Cu")
		(at 219.79382 -54.676548 -90)
		(property "Reference" "R476"
			(at 0 0 270)
			(layer "F.SilkS")
			(hide yes)
			(effects
				(font
					(size 1.27 1.27)
				)
			)
		)
		(property "Value" "866KR2F-GP"
			(at 0.064008 -3.993896 270)
			(unlocked yes)
			(layer "F.Fab")
			(hide yes)
			(effects
				(font
					(size 1.016 1.016)
					(thickness 0.1524)
				)
			)
		)
		(property "Device Type" "R402H16"
			(at 0.064008 -5.517896 270)
			(unlocked yes)
			(layer "F.Fab")
			(hide yes)
			(effects
				(font
					(size 1.016 1.016)
					(thickness 0.1524)
				)
			)
		)
		(duplicate_pad_numbers_are_jumpers no)
		(fp_line
			(start -0.508 -0.9398)
			(end -0.508 0.9398)
			(stroke
				(width 0.1524)
				(type default)
			)
			(layer "F.SilkS")
		)
		(fp_line
			(start 0.508 -0.9398)
			(end -0.508 -0.9398)
			(stroke
				(width 0.1524)
				(type default)
			)
			(layer "F.SilkS")
		)
		(fp_rect
			(start -0.508 0.9398)
			(end 0.508 -0.9398)
			(stroke
				(width 0)
				(type default)
			)
			(fill no)
			(layer "F.CrtYd")
		)
		(fp_rect
			(start -0.508 0.9398)
			(end 0.508 -0.9398)
			(stroke
				(width 0)
				(type default)
			)
			(fill no)
			(layer "F.Fab")
		)
		(pad "1" smd custom
			(at 0 -0.4445 270)
			(size 0.1397 0.1397)
			(layers "F.Cu" "F.Mask" "F.Paste")
			(net "P5V_STBY_VREG")
			(options
				(clearance outline)
				(anchor circle)
			)
			(primitives
				(gr_poly
					(pts
						(arc
							(start -0.1778 -0.2794)
							(mid -0.249642 -0.249642)
							(end -0.2794 -0.1778)
						)
						(arc
							(start -0.2794 0.1778)
							(mid -0.249642 0.249642)
							(end -0.1778 0.2794)
						)
						(arc
							(start 0.1778 0.2794)
							(mid 0.249642 0.249642)
							(end 0.2794 0.1778)
						)
						(arc
							(start 0.2794 -0.1778)
							(mid 0.249642 -0.249642)
							(end 0.1778 -0.2794)
						)
					)
					(width 0)
					(fill yes)
				)
			)
		)
		(pad "2" smd custom
			(at 0 0.4445 270)
			(size 0.1397 0.1397)
			(layers "F.Cu" "F.Mask" "F.Paste")
			(net "P5V_RF")
			(options
				(clearance outline)
				(anchor circle)
			)
			(primitives
				(gr_poly
					(pts
						(arc
							(start -0.1778 -0.2794)
							(mid -0.249642 -0.249642)
							(end -0.2794 -0.1778)
						)
						(arc
							(start -0.2794 0.1778)
							(mid -0.249642 0.249642)
							(end -0.1778 0.2794)
						)
						(arc
							(start 0.1778 0.2794)
							(mid 0.249642 0.249642)
							(end 0.2794 0.1778)
						)
						(arc
							(start 0.2794 -0.1778)
							(mid 0.249642 -0.249642)
							(end 0.1778 -0.2794)
						)
					)
					(width 0)
					(fill yes)
				)
			)
		)
	)
	(footprint ""
		(layer "F.Cu")
		(at 61.289184 -143.382492 90)
		(property "Reference" "R155"
			(at 0 0 90)
			(layer "F.SilkS")
			(hide yes)
			(effects
				(font
					(size 1.27 1.27)
				)
			)
		)
		(property "Value" "0R2J-2-GP"
			(at 0.064008 -3.993896 90)
			(unlocked yes)
			(layer "F.Fab")
			(hide yes)
			(effects
				(font
					(size 1.016 1.016)
					(thickness 0.1524)
				)
			)
		)
		(property "Device Type" "R402H16"
			(at 0.064008 -5.517896 90)
			(unlocked yes)
			(layer "F.Fab")
			(hide yes)
			(effects
				(font
					(size 1.016 1.016)
					(thickness 0.1524)
				)
			)
		)
		(duplicate_pad_numbers_are_jumpers no)
		(fp_line
			(start 0.508 -0.9398)
			(end -0.508 -0.9398)
			(stroke
				(width 0.1524)
				(type default)
			)
			(layer "F.SilkS")
		)
		(fp_line
			(start -0.508 -0.9398)
			(end -0.508 0.9398)
			(stroke
				(width 0.1524)
				(type default)
			)
			(layer "F.SilkS")
		)
		(fp_rect
			(start -0.508 0.9398)
			(end 0.508 -0.9398)
			(stroke
				(width 0)
				(type default)
			)
			(fill no)
			(layer "F.CrtYd")
		)
		(fp_rect
			(start -0.508 0.9398)
			(end 0.508 -0.9398)
			(stroke
				(width 0)
				(type default)
			)
			(fill no)
			(layer "F.Fab")
		)
		(pad "1" smd custom
			(at 0 -0.4445 90)
			(size 0.1397 0.1397)
			(layers "F.Cu" "F.Mask" "F.Paste")
			(net "BMC_SMB11_CLK")
			(options
				(clearance outline)
				(anchor circle)
			)
			(primitives
				(gr_poly
					(pts
						(arc
							(start -0.1778 -0.2794)
							(mid -0.249642 -0.249642)
							(end -0.2794 -0.1778)
						)
						(arc
							(start -0.2794 0.1778)
							(mid -0.249642 0.249642)
							(end -0.1778 0.2794)
						)
						(arc
							(start 0.1778 0.2794)
							(mid 0.249642 0.249642)
							(end 0.2794 0.1778)
						)
						(arc
							(start 0.2794 -0.1778)
							(mid 0.249642 -0.249642)
							(end 0.1778 -0.2794)
						)
					)
					(width 0)
					(fill yes)
				)
			)
		)
		(pad "2" smd custom
			(at 0 0.4445 90)
			(size 0.1397 0.1397)
			(layers "F.Cu" "F.Mask" "F.Paste")
			(net "I2C_EXP_RMT_SCL_OUT")
			(options
				(clearance outline)
				(anchor circle)
			)
			(primitives
				(gr_poly
					(pts
						(arc
							(start -0.1778 -0.2794)
							(mid -0.249642 -0.249642)
							(end -0.2794 -0.1778)
						)
						(arc
							(start -0.2794 0.1778)
							(mid -0.249642 0.249642)
							(end -0.1778 0.2794)
						)
						(arc
							(start 0.1778 0.2794)
							(mid 0.249642 0.249642)
							(end 0.2794 0.1778)
						)
						(arc
							(start 0.2794 -0.1778)
							(mid 0.249642 -0.249642)
							(end 0.1778 -0.2794)
						)
					)
					(width 0)
					(fill yes)
				)
			)
		)
	)
	(footprint ""
		(layer "F.Cu")
		(at 23.999952 -8.750046)
		(property "Reference" "PWR1"
			(at 0 0 0)
			(layer "F.SilkS")
			(hide yes)
			(effects
				(font
					(size 1.27 1.27)
				)
			)
		)
		(property "Value" "SW-TACT-4P-169-GP"
			(at -5.715 -0.8509 0)
			(unlocked yes)
			(layer "F.Fab")
			(hide yes)
			(effects
				(font
					(size 1.016 1.016)
					(thickness 0.1524)
				)
			)
		)
		(property "Device Type" "DTSA-65N-K-S-V-676-K"
			(at -5.715 -2.3749 0)
			(unlocked yes)
			(layer "F.Fab")
			(hide yes)
			(effects
				(font
					(size 1.016 1.016)
					(thickness 0.1524)
				)
			)
		)
		(duplicate_pad_numbers_are_jumpers no)
		(fp_line
			(start -4.4958 -4.2418)
			(end -2.54 -4.2418)
			(stroke
				(width 0.1524)
				(type default)
			)
			(layer "F.SilkS")
		)
		(fp_line
			(start -4.4958 -1.5367)
			(end -4.4958 -4.2418)
			(stroke
				(width 0.1524)
				(type default)
			)
			(layer "F.SilkS")
		)
		(fp_line
			(start -3.9497 -1.5367)
			(end -4.4958 -1.5367)
			(stroke
				(width 0.1524)
				(type default)
			)
			(layer "F.SilkS")
		)
		(fp_line
			(start -3.9497 3.2004)
			(end -3.9497 -1.5367)
			(stroke
				(width 0.1524)
				(type default)
			)
			(layer "F.SilkS")
		)
		(fp_line
			(start -2.54 -4.2418)
			(end -2.54 -2.0574)
			(stroke
				(width 0.1524)
				(type default)
			)
			(layer "F.SilkS")
		)
		(fp_line
			(start -2.54 -2.0574)
			(end 2.54 -2.0574)
			(stroke
				(width 0.1524)
				(type default)
			)
			(layer "F.SilkS")
		)
		(fp_line
			(start -2.0066 3.2004)
			(end -3.9497 3.2004)
			(stroke
				(width 0.1524)
				(type default)
			)
			(layer "F.SilkS")
		)
		(fp_line
			(start -2.0066 8.6106)
			(end -2.0066 3.2004)
			(stroke
				(width 0.1524)
				(type default)
			)
			(layer "F.SilkS")
		)
		(fp_line
			(start 2.0066 3.2004)
			(end 2.0066 8.6106)
			(stroke
				(width 0.1524)
				(type default)
			)
			(layer "F.SilkS")
		)
		(fp_line
			(start 2.0066 8.6106)
			(end -2.0066 8.6106)
			(stroke
				(width 0.1524)
				(type default)
			)
			(layer "F.SilkS")
		)
		(fp_line
			(start 2.54 -4.2418)
			(end 4.4958 -4.2418)
			(stroke
				(width 0.1524)
				(type default)
			)
			(layer "F.SilkS")
		)
		(fp_line
			(start 2.54 -2.0574)
			(end 2.54 -4.2418)
			(stroke
				(width 0.1524)
				(type default)
			)
			(layer "F.SilkS")
		)
		(fp_line
			(start 3.9497 -1.5367)
			(end 3.9497 3.2004)
			(stroke
				(width 0.1524)
				(type default)
			)
			(layer "F.SilkS")
		)
		(fp_line
			(start 3.9497 3.2004)
			(end 2.0066 3.2004)
			(stroke
				(width 0.1524)
				(type default)
			)
			(layer "F.SilkS")
		)
		(fp_line
			(start 4.4958 -4.2418)
			(end 4.4958 -1.5367)
			(stroke
				(width 0.1524)
				(type default)
			)
			(layer "F.SilkS")
		)
		(fp_line
			(start 4.4958 -1.5367)
			(end 3.9497 -1.5367)
			(stroke
				(width 0.1524)
				(type default)
			)
			(layer "F.SilkS")
		)
		(fp_circle
			(center -3.50012 -2.500122)
			(end -2.43332 -2.500122)
			(stroke
				(width 0.3048)
				(type default)
			)
			(fill no)
			(layer "F.SilkS")
		)
		(fp_circle
			(center -2.249932 0)
			(end -1.183132 0)
			(stroke
				(width 0.3048)
				(type default)
			)
			(fill no)
			(layer "F.SilkS")
		)
		(fp_circle
			(center 2.249932 0)
			(end 3.316732 0)
			(stroke
				(width 0.3048)
				(type default)
			)
			(fill no)
			(layer "F.SilkS")
		)
		(fp_circle
			(center 3.50012 -2.500122)
			(end 4.56692 -2.500122)
			(stroke
				(width 0.3048)
				(type default)
			)
			(fill no)
			(layer "F.SilkS")
		)
		(fp_poly
			(pts
				(xy -1.7526 8.3566) (xy -1.7526 2.9464) (xy -3.6957 2.9464) (xy -3.6957 -2.144522) (xy -4.2418 -2.144522)
				(xy -4.2418 -2.855722) (xy -3.6957 -2.855722) (xy -3.6957 -3.9878) (xy -3.302 -3.9878) (xy -3.302 -1.7907)
				(xy 3.302 -1.7907) (xy 3.302 -3.9878) (xy 3.6957 -3.9878) (xy 3.6957 -2.855722) (xy 4.2418 -2.855722)
				(xy 4.2418 -2.144522) (xy 3.6957 -2.144522) (xy 3.6957 2.9464) (xy 1.7526 2.9464) (xy 1.7526 8.3566)
			)
			(stroke
				(width 0)
				(type default)
			)
			(fill no)
			(layer "F.CrtYd")
		)
		(fp_poly
			(pts
				(xy -2.2606 8.8646) (xy -2.2606 3.4544) (xy -4.2037 3.4544) (xy -4.2037 -1.2827) (xy -4.7498 -1.2827)
				(xy -4.7498 -4.4958) (xy -2.286 -4.4958) (xy -2.286 -2.3114) (xy 2.286 -2.3114) (xy 2.286 -4.4958)
				(xy 4.7498 -4.4958) (xy 4.7498 -1.2827) (xy 4.2037 -1.2827) (xy 4.2037 -0.5588) (xy 3.695954 -0.5588)
				(xy 3.695954 -2.144268) (xy 4.2418 -2.144268) (xy 4.2418 -2.855976) (xy 3.695954 -2.855976) (xy 3.695954 -3.988054)
				(xy 3.301746 -3.988054) (xy 3.301746 -1.7907) (xy -3.301746 -1.7907) (xy -3.301746 -3.988054) (xy -3.695954 -3.988054)
				(xy -3.695954 -2.855976) (xy -4.2418 -2.855976) (xy -4.2418 -2.144268) (xy -3.695954 -2.144268)
				(xy -3.695954 2.9464) (xy -1.752854 2.9464) (xy -1.752854 8.3566) (xy 1.752854 8.3566) (xy 1.752854 2.9464)
				(xy 3.695954 2.9464) (xy 3.695954 -0.5461) (xy 4.2037 -0.5461) (xy 4.2037 3.4544) (xy 2.2606 3.4544)
				(xy 2.2606 8.8646)
			)
			(stroke
				(width 0)
				(type default)
			)
			(fill no)
			(layer "F.CrtYd")
		)
		(fp_poly
			(pts
				(xy 2.2606 8.8646) (xy -2.2606 8.8646) (xy -2.2606 3.4544) (xy -4.2037 3.4544) (xy -4.2037 -1.2827)
				(xy -4.7498 -1.2827) (xy -4.7498 -4.4958) (xy -2.286 -4.4958) (xy -2.286 -2.3114) (xy 2.286 -2.3114)
				(xy 2.286 -4.4958) (xy 4.7498 -4.4958) (xy 4.7498 -1.2827) (xy 4.2037 -1.2827) (xy 4.2037 3.4544)
				(xy 2.2606 3.4544)
			)
			(stroke
				(width 0)
				(type default)
			)
			(fill no)
			(layer "F.Fab")
		)
		(pad "1" thru_hole circle
			(at -2.249932 0)
			(size 1.4224 1.4224)
			(drill 1.016)
			(layers "*.Cu" "*.Mask")
			(remove_unused_layers no)
			(net "FP_PWR_BTN_N")
			(clearance 0.1524)
			(thermal_gap 0.1524)
		)
		(pad "2" thru_hole circle
			(at 2.249932 0)
			(size 1.4224 1.4224)
			(drill 1.016)
			(layers "*.Cu" "*.Mask")
			(remove_unused_layers no)
			(net "GND")
			(clearance 0.1524)
			(thermal_gap 0.1524)
		)
		(pad "3" thru_hole circle
			(at -3.50012 -2.500122)
			(size 1.4224 1.4224)
			(drill 1.016)
			(layers "*.Cu" "*.Mask")
			(remove_unused_layers no)
			(net "PWR_BTN_GND")
			(clearance 0.1524)
			(thermal_gap 0.1524)
		)
		(pad "4" thru_hole circle
			(at 3.50012 -2.500122)
			(size 1.4224 1.4224)
			(drill 1.016)
			(layers "*.Cu" "*.Mask")
			(remove_unused_layers no)
			(net "PWR_BTN_GND")
			(clearance 0.1524)
			(thermal_gap 0.1524)
		)
	)
	(footprint ""
		(layer "F.Cu")
		(at 72.4662 -135.89 90)
		(property "Reference" "R98"
			(at 0 0 90)
			(layer "F.SilkS")
			(hide yes)
			(effects
				(font
					(size 1.27 1.27)
				)
			)
		)
		(property "Value" "0R2J-2-GP"
			(at 0.064008 -3.993896 90)
			(unlocked yes)
			(layer "F.Fab")
			(hide yes)
			(effects
				(font
					(size 1.016 1.016)
					(thickness 0.1524)
				)
			)
		)
		(property "Device Type" "R402H16"
			(at 0.064008 -5.517896 90)
			(unlocked yes)
			(layer "F.Fab")
			(hide yes)
			(effects
				(font
					(size 1.016 1.016)
					(thickness 0.1524)
				)
			)
		)
		(duplicate_pad_numbers_are_jumpers no)
		(fp_line
			(start 0.508 -0.9398)
			(end -0.508 -0.9398)
			(stroke
				(width 0.1524)
				(type default)
			)
			(layer "F.SilkS")
		)
		(fp_line
			(start -0.508 -0.9398)
			(end -0.508 0.9398)
			(stroke
				(width 0.1524)
				(type default)
			)
			(layer "F.SilkS")
		)
		(fp_rect
			(start -0.508 0.9398)
			(end 0.508 -0.9398)
			(stroke
				(width 0)
				(type default)
			)
			(fill no)
			(layer "F.CrtYd")
		)
		(fp_rect
			(start -0.508 0.9398)
			(end 0.508 -0.9398)
			(stroke
				(width 0)
				(type default)
			)
			(fill no)
			(layer "F.Fab")
		)
		(pad "1" smd custom
			(at 0 -0.4445 90)
			(size 0.1397 0.1397)
			(layers "F.Cu" "F.Mask" "F.Paste")
			(net "UART_SEL_MUX")
			(options
				(clearance outline)
				(anchor circle)
			)
			(primitives
				(gr_poly
					(pts
						(arc
							(start -0.1778 -0.2794)
							(mid -0.249642 -0.249642)
							(end -0.2794 -0.1778)
						)
						(arc
							(start -0.2794 0.1778)
							(mid -0.249642 0.249642)
							(end -0.1778 0.2794)
						)
						(arc
							(start 0.1778 0.2794)
							(mid 0.249642 0.249642)
							(end 0.2794 0.1778)
						)
						(arc
							(start 0.2794 -0.1778)
							(mid 0.249642 -0.249642)
							(end 0.1778 -0.2794)
						)
					)
					(width 0)
					(fill yes)
				)
			)
		)
		(pad "2" smd custom
			(at 0 0.4445 90)
			(size 0.1397 0.1397)
			(layers "F.Cu" "F.Mask" "F.Paste")
			(net "D_FLIP_Q")
			(options
				(clearance outline)
				(anchor circle)
			)
			(primitives
				(gr_poly
					(pts
						(arc
							(start -0.1778 -0.2794)
							(mid -0.249642 -0.249642)
							(end -0.2794 -0.1778)
						)
						(arc
							(start -0.2794 0.1778)
							(mid -0.249642 0.249642)
							(end -0.1778 0.2794)
						)
						(arc
							(start 0.1778 0.2794)
							(mid 0.249642 0.249642)
							(end 0.2794 0.1778)
						)
						(arc
							(start 0.2794 -0.1778)
							(mid 0.249642 -0.249642)
							(end 0.1778 -0.2794)
						)
					)
					(width 0)
					(fill yes)
				)
			)
		)
	)
	(footprint ""
		(layer "F.Cu")
		(at 124.841 -9.652 90)
		(property "Reference" "C130"
			(at 0 0 90)
			(layer "F.SilkS")
			(hide yes)
			(effects
				(font
					(size 1.27 1.27)
				)
			)
		)
		(property "Value" "SCD1U16V2KX-3GP"
			(at 1.1811 -2.7051 90)
			(unlocked yes)
			(layer "F.Fab")
			(hide yes)
			(effects
				(font
					(size 1.016 1.016)
					(thickness 0.1524)
				)
			)
		)
		(property "Device Type" "C402H22"
			(at 1.1811 -4.2291 90)
			(unlocked yes)
			(layer "F.Fab")
			(hide yes)
			(effects
				(font
					(size 1.016 1.016)
					(thickness 0.1524)
				)
			)
		)
		(duplicate_pad_numbers_are_jumpers no)
		(fp_rect
			(start -0.4318 0.9525)
			(end 0.4318 -0.9525)
			(stroke
				(width 0)
				(type default)
			)
			(fill no)
			(layer "F.CrtYd")
		)
		(fp_rect
			(start -0.4318 0.9525)
			(end 0.4318 -0.9525)
			(stroke
				(width 0)
				(type default)
			)
			(fill no)
			(layer "F.Fab")
		)
		(pad "1" smd custom
			(at 0 -0.4445 90)
			(size 0.1524 0.1524)
			(layers "F.Cu" "F.Mask" "F.Paste")
			(net "MB0_CM_VOUT_R")
			(options
				(clearance outline)
				(anchor circle)
			)
			(primitives
				(gr_poly
					(pts
						(arc
							(start 0.3048 -0.2032)
							(mid 0.275042 -0.275042)
							(end 0.2032 -0.3048)
						)
						(arc
							(start -0.2032 -0.3048)
							(mid -0.275042 -0.275042)
							(end -0.3048 -0.2032)
						)
						(arc
							(start -0.3048 0.2032)
							(mid -0.275042 0.275042)
							(end -0.2032 0.3048)
						)
						(arc
							(start 0.2032 0.3048)
							(mid 0.275042 0.275042)
							(end 0.3048 0.2032)
						)
					)
					(width 0)
					(fill yes)
				)
			)
		)
		(pad "2" smd custom
			(at 0 0.4445 90)
			(size 0.1524 0.1524)
			(layers "F.Cu" "F.Mask" "F.Paste")
			(net "AGND_CURRENT_MON")
			(options
				(clearance outline)
				(anchor circle)
			)
			(primitives
				(gr_poly
					(pts
						(arc
							(start 0.3048 -0.2032)
							(mid 0.275042 -0.275042)
							(end 0.2032 -0.3048)
						)
						(arc
							(start -0.2032 -0.3048)
							(mid -0.275042 -0.275042)
							(end -0.3048 -0.2032)
						)
						(arc
							(start -0.3048 0.2032)
							(mid -0.275042 0.275042)
							(end -0.2032 0.3048)
						)
						(arc
							(start 0.2032 0.3048)
							(mid 0.275042 0.275042)
							(end 0.3048 0.2032)
						)
					)
					(width 0)
					(fill yes)
				)
			)
		)
	)
	(footprint ""
		(layer "F.Cu")
		(at 67.948556 -137.74039)
		(property "Reference" "R59"
			(at 0 0 0)
			(layer "F.SilkS")
			(hide yes)
			(effects
				(font
					(size 1.27 1.27)
				)
			)
		)
		(property "Value" "33R2F-3-GP"
			(at 0.064008 -3.993896 0)
			(unlocked yes)
			(layer "F.Fab")
			(hide yes)
			(effects
				(font
					(size 1.016 1.016)
					(thickness 0.1524)
				)
			)
		)
		(property "Device Type" "R402H16"
			(at 0.064008 -5.517896 0)
			(unlocked yes)
			(layer "F.Fab")
			(hide yes)
			(effects
				(font
					(size 1.016 1.016)
					(thickness 0.1524)
				)
			)
		)
		(duplicate_pad_numbers_are_jumpers no)
		(fp_line
			(start -0.508 -0.9398)
			(end -0.508 0.9398)
			(stroke
				(width 0.1524)
				(type default)
			)
			(layer "F.SilkS")
		)
		(fp_line
			(start 0.508 -0.9398)
			(end -0.508 -0.9398)
			(stroke
				(width 0.1524)
				(type default)
			)
			(layer "F.SilkS")
		)
		(fp_rect
			(start -0.508 0.9398)
			(end 0.508 -0.9398)
			(stroke
				(width 0)
				(type default)
			)
			(fill no)
			(layer "F.CrtYd")
		)
		(fp_rect
			(start -0.508 0.9398)
			(end 0.508 -0.9398)
			(stroke
				(width 0)
				(type default)
			)
			(fill no)
			(layer "F.Fab")
		)
		(pad "1" smd custom
			(at 0 -0.4445)
			(size 0.1397 0.1397)
			(layers "F.Cu" "F.Mask" "F.Paste")
			(net "FP_RETBTN")
			(options
				(clearance outline)
				(anchor circle)
			)
			(primitives
				(gr_poly
					(pts
						(arc
							(start -0.1778 -0.2794)
							(mid -0.249642 -0.249642)
							(end -0.2794 -0.1778)
						)
						(arc
							(start -0.2794 0.1778)
							(mid -0.249642 0.249642)
							(end -0.1778 0.2794)
						)
						(arc
							(start 0.1778 0.2794)
							(mid 0.249642 0.249642)
							(end 0.2794 0.1778)
						)
						(arc
							(start 0.2794 -0.1778)
							(mid 0.249642 -0.249642)
							(end 0.1778 -0.2794)
						)
					)
					(width 0)
					(fill yes)
				)
			)
		)
		(pad "2" smd custom
			(at 0 0.4445)
			(size 0.1397 0.1397)
			(layers "F.Cu" "F.Mask" "F.Paste")
			(net "RSTBTN_OUT_N")
			(options
				(clearance outline)
				(anchor circle)
			)
			(primitives
				(gr_poly
					(pts
						(arc
							(start -0.1778 -0.2794)
							(mid -0.249642 -0.249642)
							(end -0.2794 -0.1778)
						)
						(arc
							(start -0.2794 0.1778)
							(mid -0.249642 0.249642)
							(end -0.1778 0.2794)
						)
						(arc
							(start 0.1778 0.2794)
							(mid 0.249642 0.249642)
							(end 0.2794 0.1778)
						)
						(arc
							(start 0.2794 -0.1778)
							(mid 0.249642 -0.249642)
							(end 0.1778 -0.2794)
						)
					)
					(width 0)
					(fill yes)
				)
			)
		)
	)
	(footprint ""
		(layer "F.Cu")
		(at 72.22998 -165.619176 90)
		(property "Reference" "R542"
			(at 0 0 90)
			(layer "F.SilkS")
			(hide yes)
			(effects
				(font
					(size 1.27 1.27)
				)
			)
		)
		(property "Value" "0R2J-2-GP"
			(at 0.064008 -3.993896 90)
			(unlocked yes)
			(layer "F.Fab")
			(hide yes)
			(effects
				(font
					(size 1.016 1.016)
					(thickness 0.1524)
				)
			)
		)
		(property "Device Type" "R402H16"
			(at 0.064008 -5.517896 90)
			(unlocked yes)
			(layer "F.Fab")
			(hide yes)
			(effects
				(font
					(size 1.016 1.016)
					(thickness 0.1524)
				)
			)
		)
		(duplicate_pad_numbers_are_jumpers no)
		(fp_line
			(start 0.508 -0.9398)
			(end -0.508 -0.9398)
			(stroke
				(width 0.1524)
				(type default)
			)
			(layer "F.SilkS")
		)
		(fp_line
			(start -0.508 -0.9398)
			(end -0.508 0.9398)
			(stroke
				(width 0.1524)
				(type default)
			)
			(layer "F.SilkS")
		)
		(fp_rect
			(start -0.508 0.9398)
			(end 0.508 -0.9398)
			(stroke
				(width 0)
				(type default)
			)
			(fill no)
			(layer "F.CrtYd")
		)
		(fp_rect
			(start -0.508 0.9398)
			(end 0.508 -0.9398)
			(stroke
				(width 0)
				(type default)
			)
			(fill no)
			(layer "F.Fab")
		)
		(pad "1" smd custom
			(at 0 -0.4445 90)
			(size 0.1397 0.1397)
			(layers "F.Cu" "F.Mask" "F.Paste")
			(net "PWRGD_P1V2_STBY")
			(options
				(clearance outline)
				(anchor circle)
			)
			(primitives
				(gr_poly
					(pts
						(arc
							(start -0.1778 -0.2794)
							(mid -0.249642 -0.249642)
							(end -0.2794 -0.1778)
						)
						(arc
							(start -0.2794 0.1778)
							(mid -0.249642 0.249642)
							(end -0.1778 0.2794)
						)
						(arc
							(start 0.1778 0.2794)
							(mid 0.249642 0.249642)
							(end 0.2794 0.1778)
						)
						(arc
							(start 0.2794 -0.1778)
							(mid 0.249642 -0.249642)
							(end 0.1778 -0.2794)
						)
					)
					(width 0)
					(fill yes)
				)
			)
		)
		(pad "2" smd custom
			(at 0 0.4445 90)
			(size 0.1397 0.1397)
			(layers "F.Cu" "F.Mask" "F.Paste")
			(net "TPS74801_P1V15_STBY_EN")
			(options
				(clearance outline)
				(anchor circle)
			)
			(primitives
				(gr_poly
					(pts
						(arc
							(start -0.1778 -0.2794)
							(mid -0.249642 -0.249642)
							(end -0.2794 -0.1778)
						)
						(arc
							(start -0.2794 0.1778)
							(mid -0.249642 0.249642)
							(end -0.1778 0.2794)
						)
						(arc
							(start 0.1778 0.2794)
							(mid 0.249642 0.249642)
							(end 0.2794 0.1778)
						)
						(arc
							(start 0.2794 -0.1778)
							(mid 0.249642 -0.249642)
							(end 0.1778 -0.2794)
						)
					)
					(width 0)
					(fill yes)
				)
			)
		)
	)
	(footprint ""
		(layer "F.Cu")
		(at 174.25797 -138.239246 -135)
		(property "Reference" "VIA63"
			(at 0 0 225)
			(layer "F.SilkS")
			(hide yes)
			(effects
				(font
					(size 1.27 1.27)
				)
			)
		)
		(property "Value" "85OHM-8L-1D6MM-L16L18-GP"
			(at 4.064105 0.609655 225)
			(unlocked yes)
			(layer "F.Fab")
			(hide yes)
			(effects
				(font
					(size 1.016 1.016)
					(thickness 0.1524)
				)
			)
		)
		(property "Device Type" "VIA-PCIE-4P-368076"
			(at 4.064105 -0.914474 225)
			(unlocked yes)
			(layer "F.Fab")
			(hide yes)
			(effects
				(font
					(size 1.016 1.016)
					(thickness 0.1524)
				)
			)
		)
		(duplicate_pad_numbers_are_jumpers no)
		(fp_poly
			(pts
				(xy -1.841491 -0.381057) (xy 1.841509 -0.381058) (xy 1.841508 0.380942) (xy -1.841491 0.380942)
			)
			(stroke
				(width 0)
				(type default)
			)
			(fill no)
			(layer "F.CrtYd")
		)
		(fp_poly
			(pts
				(xy -1.841491 -0.381057) (xy 1.841509 -0.381058) (xy 1.841508 0.380942) (xy -1.841491 0.380942)
			)
			(stroke
				(width 0)
				(type default)
			)
			(fill no)
			(layer "F.Fab")
		)
		(pad "1" thru_hole circle
			(at -1.460499 0 225)
			(size 0.508 0.508)
			(drill 0.254)
			(layers "*.Cu" "*.Mask")
			(remove_unused_layers no)
			(net "GND")
			(clearance 0.127)
			(thermal_gap 0.127)
		)
		(pad "2" thru_hole circle
			(at -0.4445 0 225)
			(size 0.508 0.508)
			(drill 0.254)
			(layers "*.Cu" "*.Mask")
			(remove_unused_layers no)
			(net "PCIE_IOM_TO_COMP_14_DP")
			(clearance 0.127)
			(thermal_gap 0.127)
		)
		(pad "3" thru_hole circle
			(at 0.4445 0 225)
			(size 0.508 0.508)
			(drill 0.254)
			(layers "*.Cu" "*.Mask")
			(remove_unused_layers no)
			(net "PCIE_IOM_TO_COMP_14_DN")
			(clearance 0.127)
			(thermal_gap 0.127)
		)
		(pad "4" thru_hole circle
			(at 1.460499 0 225)
			(size 0.508 0.508)
			(drill 0.254)
			(layers "*.Cu" "*.Mask")
			(remove_unused_layers no)
			(net "GND")
			(clearance 0.127)
			(thermal_gap 0.127)
		)
	)
	(footprint ""
		(layer "F.Cu")
		(at 84.900262 -146.519646 -90)
		(property "Reference" "R129"
			(at 0 0 270)
			(layer "F.SilkS")
			(hide yes)
			(effects
				(font
					(size 1.27 1.27)
				)
			)
		)
		(property "Value" "0R2J-2-GP"
			(at 0.064008 -3.993896 270)
			(unlocked yes)
			(layer "F.Fab")
			(hide yes)
			(effects
				(font
					(size 1.016 1.016)
					(thickness 0.1524)
				)
			)
		)
		(property "Device Type" "R402H16"
			(at 0.064008 -5.517896 270)
			(unlocked yes)
			(layer "F.Fab")
			(hide yes)
			(effects
				(font
					(size 1.016 1.016)
					(thickness 0.1524)
				)
			)
		)
		(duplicate_pad_numbers_are_jumpers no)
		(fp_line
			(start -0.508 -0.9398)
			(end -0.508 0.9398)
			(stroke
				(width 0.1524)
				(type default)
			)
			(layer "F.SilkS")
		)
		(fp_line
			(start 0.508 -0.9398)
			(end -0.508 -0.9398)
			(stroke
				(width 0.1524)
				(type default)
			)
			(layer "F.SilkS")
		)
		(fp_rect
			(start -0.508 0.9398)
			(end 0.508 -0.9398)
			(stroke
				(width 0)
				(type default)
			)
			(fill no)
			(layer "F.CrtYd")
		)
		(fp_rect
			(start -0.508 0.9398)
			(end 0.508 -0.9398)
			(stroke
				(width 0)
				(type default)
			)
			(fill no)
			(layer "F.Fab")
		)
		(pad "1" smd custom
			(at 0 -0.4445 270)
			(size 0.1397 0.1397)
			(layers "F.Cu" "F.Mask" "F.Paste")
			(net "I2C_EXP_RMT_SCL")
			(options
				(clearance outline)
				(anchor circle)
			)
			(primitives
				(gr_poly
					(pts
						(arc
							(start -0.1778 -0.2794)
							(mid -0.249642 -0.249642)
							(end -0.2794 -0.1778)
						)
						(arc
							(start -0.2794 0.1778)
							(mid -0.249642 0.249642)
							(end -0.1778 0.2794)
						)
						(arc
							(start 0.1778 0.2794)
							(mid 0.249642 0.249642)
							(end 0.2794 0.1778)
						)
						(arc
							(start 0.2794 -0.1778)
							(mid 0.249642 -0.249642)
							(end 0.1778 -0.2794)
						)
					)
					(width 0)
					(fill yes)
				)
			)
		)
		(pad "2" smd custom
			(at 0 0.4445 270)
			(size 0.1397 0.1397)
			(layers "F.Cu" "F.Mask" "F.Paste")
			(net "I2C_EXP_RMT_SCL_R")
			(options
				(clearance outline)
				(anchor circle)
			)
			(primitives
				(gr_poly
					(pts
						(arc
							(start -0.1778 -0.2794)
							(mid -0.249642 -0.249642)
							(end -0.2794 -0.1778)
						)
						(arc
							(start -0.2794 0.1778)
							(mid -0.249642 0.249642)
							(end -0.1778 0.2794)
						)
						(arc
							(start 0.1778 0.2794)
							(mid 0.249642 0.249642)
							(end 0.2794 0.1778)
						)
						(arc
							(start 0.2794 -0.1778)
							(mid 0.249642 -0.249642)
							(end 0.1778 -0.2794)
						)
					)
					(width 0)
					(fill yes)
				)
			)
		)
	)
	(footprint ""
		(layer "F.Cu")
		(at 34.03473 -156.807916 -90)
		(property "Reference" "R320"
			(at 0 0 270)
			(layer "F.SilkS")
			(hide yes)
			(effects
				(font
					(size 1.27 1.27)
				)
			)
		)
		(property "Value" "0R2J-2-GP"
			(at 0.064008 -3.993896 270)
			(unlocked yes)
			(layer "F.Fab")
			(hide yes)
			(effects
				(font
					(size 1.016 1.016)
					(thickness 0.1524)
				)
			)
		)
		(property "Device Type" "R402H16"
			(at 0.064008 -5.517896 270)
			(unlocked yes)
			(layer "F.Fab")
			(hide yes)
			(effects
				(font
					(size 1.016 1.016)
					(thickness 0.1524)
				)
			)
		)
		(duplicate_pad_numbers_are_jumpers no)
		(fp_line
			(start -0.508 -0.9398)
			(end -0.508 0.9398)
			(stroke
				(width 0.1524)
				(type default)
			)
			(layer "F.SilkS")
		)
		(fp_line
			(start 0.508 -0.9398)
			(end -0.508 -0.9398)
			(stroke
				(width 0.1524)
				(type default)
			)
			(layer "F.SilkS")
		)
		(fp_rect
			(start -0.508 0.9398)
			(end 0.508 -0.9398)
			(stroke
				(width 0)
				(type default)
			)
			(fill no)
			(layer "F.CrtYd")
		)
		(fp_rect
			(start -0.508 0.9398)
			(end 0.508 -0.9398)
			(stroke
				(width 0)
				(type default)
			)
			(fill no)
			(layer "F.Fab")
		)
		(pad "1" smd custom
			(at 0 -0.4445 270)
			(size 0.1397 0.1397)
			(layers "F.Cu" "F.Mask" "F.Paste")
			(net "SCC_A_HB_IN_R")
			(options
				(clearance outline)
				(anchor circle)
			)
			(primitives
				(gr_poly
					(pts
						(arc
							(start -0.1778 -0.2794)
							(mid -0.249642 -0.249642)
							(end -0.2794 -0.1778)
						)
						(arc
							(start -0.2794 0.1778)
							(mid -0.249642 0.249642)
							(end -0.1778 0.2794)
						)
						(arc
							(start 0.1778 0.2794)
							(mid 0.249642 0.249642)
							(end 0.2794 0.1778)
						)
						(arc
							(start 0.2794 -0.1778)
							(mid 0.249642 -0.249642)
							(end 0.1778 -0.2794)
						)
					)
					(width 0)
					(fill yes)
				)
			)
		)
		(pad "2" smd custom
			(at 0 0.4445 270)
			(size 0.1397 0.1397)
			(layers "F.Cu" "F.Mask" "F.Paste")
			(net "SCC_LOC_HEARTBEAT")
			(options
				(clearance outline)
				(anchor circle)
			)
			(primitives
				(gr_poly
					(pts
						(arc
							(start -0.1778 -0.2794)
							(mid -0.249642 -0.249642)
							(end -0.2794 -0.1778)
						)
						(arc
							(start -0.2794 0.1778)
							(mid -0.249642 0.249642)
							(end -0.1778 0.2794)
						)
						(arc
							(start 0.1778 0.2794)
							(mid 0.249642 0.249642)
							(end 0.2794 0.1778)
						)
						(arc
							(start 0.2794 -0.1778)
							(mid 0.249642 -0.249642)
							(end 0.1778 -0.2794)
						)
					)
					(width 0)
					(fill yes)
				)
			)
		)
	)
	(footprint ""
		(layer "F.Cu")
		(at 87.930228 -67.507612 -90)
		(property "Reference" "R14"
			(at 0 0 270)
			(layer "F.SilkS")
			(hide yes)
			(effects
				(font
					(size 1.27 1.27)
				)
			)
		)
		(property "Value" "0R2J-2-GP"
			(at 0.064008 -3.993896 270)
			(unlocked yes)
			(layer "F.Fab")
			(hide yes)
			(effects
				(font
					(size 1.016 1.016)
					(thickness 0.1524)
				)
			)
		)
		(property "Device Type" "R402H16"
			(at 0.064008 -5.517896 270)
			(unlocked yes)
			(layer "F.Fab")
			(hide yes)
			(effects
				(font
					(size 1.016 1.016)
					(thickness 0.1524)
				)
			)
		)
		(duplicate_pad_numbers_are_jumpers no)
		(fp_line
			(start -0.508 -0.9398)
			(end -0.508 0.9398)
			(stroke
				(width 0.1524)
				(type default)
			)
			(layer "F.SilkS")
		)
		(fp_line
			(start 0.508 -0.9398)
			(end -0.508 -0.9398)
			(stroke
				(width 0.1524)
				(type default)
			)
			(layer "F.SilkS")
		)
		(fp_rect
			(start -0.508 0.9398)
			(end 0.508 -0.9398)
			(stroke
				(width 0)
				(type default)
			)
			(fill no)
			(layer "F.CrtYd")
		)
		(fp_rect
			(start -0.508 0.9398)
			(end 0.508 -0.9398)
			(stroke
				(width 0)
				(type default)
			)
			(fill no)
			(layer "F.Fab")
		)
		(pad "1" smd custom
			(at 0 -0.4445 270)
			(size 0.1397 0.1397)
			(layers "F.Cu" "F.Mask" "F.Paste")
			(net "NCSI_RXD0")
			(options
				(clearance outline)
				(anchor circle)
			)
			(primitives
				(gr_poly
					(pts
						(arc
							(start -0.1778 -0.2794)
							(mid -0.249642 -0.249642)
							(end -0.2794 -0.1778)
						)
						(arc
							(start -0.2794 0.1778)
							(mid -0.249642 0.249642)
							(end -0.1778 0.2794)
						)
						(arc
							(start 0.1778 0.2794)
							(mid 0.249642 0.249642)
							(end 0.2794 0.1778)
						)
						(arc
							(start 0.2794 -0.1778)
							(mid 0.249642 -0.249642)
							(end 0.1778 -0.2794)
						)
					)
					(width 0)
					(fill yes)
				)
			)
		)
		(pad "2" smd custom
			(at 0 0.4445 270)
			(size 0.1397 0.1397)
			(layers "F.Cu" "F.Mask" "F.Paste")
			(net "NCSI_RXD0_R")
			(options
				(clearance outline)
				(anchor circle)
			)
			(primitives
				(gr_poly
					(pts
						(arc
							(start -0.1778 -0.2794)
							(mid -0.249642 -0.249642)
							(end -0.2794 -0.1778)
						)
						(arc
							(start -0.2794 0.1778)
							(mid -0.249642 0.249642)
							(end -0.1778 0.2794)
						)
						(arc
							(start 0.1778 0.2794)
							(mid 0.249642 0.249642)
							(end 0.2794 0.1778)
						)
						(arc
							(start 0.2794 -0.1778)
							(mid 0.249642 -0.249642)
							(end 0.1778 -0.2794)
						)
					)
					(width 0)
					(fill yes)
				)
			)
		)
	)
	(footprint ""
		(layer "F.Cu")
		(at 89.45372 -162.360356 180)
		(property "Reference" "C19"
			(at 0 0 180)
			(layer "F.SilkS")
			(hide yes)
			(effects
				(font
					(size 1.27 1.27)
				)
			)
		)
		(property "Value" "SC1U16V3KX-5GP"
			(at 0 -2.8194 180)
			(unlocked yes)
			(layer "F.Fab")
			(hide yes)
			(effects
				(font
					(size 1.016 1.016)
					(thickness 0.1524)
				)
			)
		)
		(property "Device Type" "C603H36"
			(at 0 -4.3434 180)
			(unlocked yes)
			(layer "F.Fab")
			(hide yes)
			(effects
				(font
					(size 1.016 1.016)
					(thickness 0.1524)
				)
			)
		)
		(duplicate_pad_numbers_are_jumpers no)
		(fp_line
			(start 0.508 0)
			(end -0.508 0)
			(stroke
				(width 0.2032)
				(type default)
			)
			(layer "F.SilkS")
		)
		(fp_rect
			(start -0.5842 1.3335)
			(end 0.5842 -1.3335)
			(stroke
				(width 0)
				(type default)
			)
			(fill no)
			(layer "F.CrtYd")
		)
		(fp_rect
			(start -0.5842 1.3335)
			(end 0.5842 -1.3335)
			(stroke
				(width 0)
				(type default)
			)
			(fill no)
			(layer "F.Fab")
		)
		(pad "1" smd custom
			(at 0 -0.762 180)
			(size 0.2159 0.2159)
			(layers "F.Cu" "F.Mask" "F.Paste")
			(net "PLLFILT")
			(options
				(clearance outline)
				(anchor circle)
			)
			(primitives
				(gr_poly
					(pts
						(arc
							(start -0.3302 -0.4318)
							(mid -0.402042 -0.402042)
							(end -0.4318 -0.3302)
						)
						(arc
							(start -0.4318 0.3302)
							(mid -0.402042 0.402042)
							(end -0.3302 0.4318)
						)
						(arc
							(start 0.3302 0.4318)
							(mid 0.402042 0.402042)
							(end 0.4318 0.3302)
						)
						(arc
							(start 0.4318 -0.3302)
							(mid 0.402042 -0.402042)
							(end 0.3302 -0.4318)
						)
					)
					(width 0)
					(fill yes)
				)
			)
		)
		(pad "2" smd custom
			(at 0 0.762 180)
			(size 0.2159 0.2159)
			(layers "F.Cu" "F.Mask" "F.Paste")
			(net "GND")
			(options
				(clearance outline)
				(anchor circle)
			)
			(primitives
				(gr_poly
					(pts
						(arc
							(start -0.3302 -0.4318)
							(mid -0.402042 -0.402042)
							(end -0.4318 -0.3302)
						)
						(arc
							(start -0.4318 0.3302)
							(mid -0.402042 0.402042)
							(end -0.3302 0.4318)
						)
						(arc
							(start 0.3302 0.4318)
							(mid 0.402042 0.402042)
							(end 0.4318 0.3302)
						)
						(arc
							(start 0.4318 -0.3302)
							(mid 0.402042 -0.402042)
							(end 0.3302 -0.4318)
						)
					)
					(width 0)
					(fill yes)
				)
			)
		)
	)
	(footprint ""
		(layer "F.Cu")
		(at 61.289184 -142.341092 90)
		(property "Reference" "R157"
			(at 0 0 90)
			(layer "F.SilkS")
			(hide yes)
			(effects
				(font
					(size 1.27 1.27)
				)
			)
		)
		(property "Value" "0R2J-2-GP"
			(at 0.064008 -3.993896 90)
			(unlocked yes)
			(layer "F.Fab")
			(hide yes)
			(effects
				(font
					(size 1.016 1.016)
					(thickness 0.1524)
				)
			)
		)
		(property "Device Type" "R402H16"
			(at 0.064008 -5.517896 90)
			(unlocked yes)
			(layer "F.Fab")
			(hide yes)
			(effects
				(font
					(size 1.016 1.016)
					(thickness 0.1524)
				)
			)
		)
		(duplicate_pad_numbers_are_jumpers no)
		(fp_line
			(start 0.508 -0.9398)
			(end -0.508 -0.9398)
			(stroke
				(width 0.1524)
				(type default)
			)
			(layer "F.SilkS")
		)
		(fp_line
			(start -0.508 -0.9398)
			(end -0.508 0.9398)
			(stroke
				(width 0.1524)
				(type default)
			)
			(layer "F.SilkS")
		)
		(fp_rect
			(start -0.508 0.9398)
			(end 0.508 -0.9398)
			(stroke
				(width 0)
				(type default)
			)
			(fill no)
			(layer "F.CrtYd")
		)
		(fp_rect
			(start -0.508 0.9398)
			(end 0.508 -0.9398)
			(stroke
				(width 0)
				(type default)
			)
			(fill no)
			(layer "F.Fab")
		)
		(pad "1" smd custom
			(at 0 -0.4445 90)
			(size 0.1397 0.1397)
			(layers "F.Cu" "F.Mask" "F.Paste")
			(net "BMC_SMB11_DAT")
			(options
				(clearance outline)
				(anchor circle)
			)
			(primitives
				(gr_poly
					(pts
						(arc
							(start -0.1778 -0.2794)
							(mid -0.249642 -0.249642)
							(end -0.2794 -0.1778)
						)
						(arc
							(start -0.2794 0.1778)
							(mid -0.249642 0.249642)
							(end -0.1778 0.2794)
						)
						(arc
							(start 0.1778 0.2794)
							(mid 0.249642 0.249642)
							(end 0.2794 0.1778)
						)
						(arc
							(start 0.2794 -0.1778)
							(mid 0.249642 -0.249642)
							(end 0.1778 -0.2794)
						)
					)
					(width 0)
					(fill yes)
				)
			)
		)
		(pad "2" smd custom
			(at 0 0.4445 90)
			(size 0.1397 0.1397)
			(layers "F.Cu" "F.Mask" "F.Paste")
			(net "I2C_EXP_RMT_SDA_OUT")
			(options
				(clearance outline)
				(anchor circle)
			)
			(primitives
				(gr_poly
					(pts
						(arc
							(start -0.1778 -0.2794)
							(mid -0.249642 -0.249642)
							(end -0.2794 -0.1778)
						)
						(arc
							(start -0.2794 0.1778)
							(mid -0.249642 0.249642)
							(end -0.1778 0.2794)
						)
						(arc
							(start 0.1778 0.2794)
							(mid 0.249642 0.249642)
							(end 0.2794 0.1778)
						)
						(arc
							(start 0.2794 -0.1778)
							(mid 0.249642 -0.249642)
							(end 0.1778 -0.2794)
						)
					)
					(width 0)
					(fill yes)
				)
			)
		)
	)
	(footprint ""
		(layer "F.Cu")
		(at 42.988738 -185.10885 90)
		(property "Reference" "L9"
			(at 0 0 90)
			(layer "F.SilkS")
			(hide yes)
			(effects
				(font
					(size 1.27 1.27)
				)
			)
		)
		(property "Value" "COIL-3D3UH-26-GP"
			(at -4.699 -4.0132 90)
			(unlocked yes)
			(layer "F.Fab")
			(hide yes)
			(effects
				(font
					(size 1.016 1.016)
					(thickness 0.1524)
				)
			)
		)
		(property "Device Type" "L7066-1830-UH119"
			(at -4.699 -5.5372 90)
			(unlocked yes)
			(layer "F.Fab")
			(hide yes)
			(effects
				(font
					(size 1.016 1.016)
					(thickness 0.1524)
				)
			)
		)
		(duplicate_pad_numbers_are_jumpers no)
		(fp_line
			(start 3.556 -4.4958)
			(end 3.556 4.4958)
			(stroke
				(width 0.1524)
				(type default)
			)
			(layer "F.SilkS")
		)
		(fp_line
			(start -3.556 -4.4958)
			(end 3.556 -4.4958)
			(stroke
				(width 0.1524)
				(type default)
			)
			(layer "F.SilkS")
		)
		(fp_line
			(start 3.556 4.4958)
			(end -3.556 4.4958)
			(stroke
				(width 0.1524)
				(type default)
			)
			(layer "F.SilkS")
		)
		(fp_line
			(start -3.556 4.4958)
			(end -3.556 -4.4958)
			(stroke
				(width 0.1524)
				(type default)
			)
			(layer "F.SilkS")
		)
		(fp_rect
			(start -3.302 3.4798)
			(end 3.302 -3.4798)
			(stroke
				(width 0)
				(type default)
			)
			(fill no)
			(layer "F.CrtYd")
		)
		(fp_poly
			(pts
				(xy -3.81 4.572) (xy -3.81 -4.572) (xy 3.81 -4.572) (xy 3.81 -0.5588) (xy 3.302 -0.5588) (xy 3.302 -3.4798)
				(xy -3.302 -3.4798) (xy -3.302 3.4798) (xy 3.302 3.4798) (xy 3.302 -0.5461) (xy 3.81 -0.5461) (xy 3.81 4.572)
			)
			(stroke
				(width 0)
				(type default)
			)
			(fill no)
			(layer "F.CrtYd")
		)
		(fp_rect
			(start -3.81 4.572)
			(end 3.81 -4.572)
			(stroke
				(width 0)
				(type default)
			)
			(fill no)
			(layer "F.Fab")
		)
		(pad "1" smd rect
			(at 0 -2.779522 90)
			(size 3.5052 2.921)
			(layers "F.Cu" "F.Mask" "F.Paste")
			(net "P3V3_STBY_LL")
		)
		(pad "2" smd rect
			(at 0 2.779522 90)
			(size 3.5052 2.921)
			(layers "F.Cu" "F.Mask" "F.Paste")
			(net "P3V3_STBY_OUT")
		)
	)
	(footprint ""
		(layer "F.Cu")
		(at 98.942144 -156.96692 -90)
		(property "Reference" "R18"
			(at 0 0 270)
			(layer "F.SilkS")
			(hide yes)
			(effects
				(font
					(size 1.27 1.27)
				)
			)
		)
		(property "Value" "4K7R2F-GP"
			(at 0.064008 -3.993896 270)
			(unlocked yes)
			(layer "F.Fab")
			(hide yes)
			(effects
				(font
					(size 1.016 1.016)
					(thickness 0.1524)
				)
			)
		)
		(property "Device Type" "R402H16"
			(at 0.064008 -5.517896 270)
			(unlocked yes)
			(layer "F.Fab")
			(hide yes)
			(effects
				(font
					(size 1.016 1.016)
					(thickness 0.1524)
				)
			)
		)
		(duplicate_pad_numbers_are_jumpers no)
		(fp_line
			(start -0.508 -0.9398)
			(end -0.508 0.9398)
			(stroke
				(width 0.1524)
				(type default)
			)
			(layer "F.SilkS")
		)
		(fp_line
			(start 0.508 -0.9398)
			(end -0.508 -0.9398)
			(stroke
				(width 0.1524)
				(type default)
			)
			(layer "F.SilkS")
		)
		(fp_rect
			(start -0.508 0.9398)
			(end 0.508 -0.9398)
			(stroke
				(width 0)
				(type default)
			)
			(fill no)
			(layer "F.CrtYd")
		)
		(fp_rect
			(start -0.508 0.9398)
			(end 0.508 -0.9398)
			(stroke
				(width 0)
				(type default)
			)
			(fill no)
			(layer "F.Fab")
		)
		(pad "1" smd custom
			(at 0 -0.4445 270)
			(size 0.1397 0.1397)
			(layers "F.Cu" "F.Mask" "F.Paste")
			(net "P3V3_STBY")
			(options
				(clearance outline)
				(anchor circle)
			)
			(primitives
				(gr_poly
					(pts
						(arc
							(start -0.1778 -0.2794)
							(mid -0.249642 -0.249642)
							(end -0.2794 -0.1778)
						)
						(arc
							(start -0.2794 0.1778)
							(mid -0.249642 0.249642)
							(end -0.1778 0.2794)
						)
						(arc
							(start 0.1778 0.2794)
							(mid 0.249642 0.249642)
							(end 0.2794 0.1778)
						)
						(arc
							(start 0.2794 -0.1778)
							(mid 0.249642 -0.249642)
							(end 0.1778 -0.2794)
						)
					)
					(width 0)
					(fill yes)
				)
			)
		)
		(pad "2" smd custom
			(at 0 0.4445 270)
			(size 0.1397 0.1397)
			(layers "F.Cu" "F.Mask" "F.Paste")
			(net "CFG_SEL1")
			(options
				(clearance outline)
				(anchor circle)
			)
			(primitives
				(gr_poly
					(pts
						(arc
							(start -0.1778 -0.2794)
							(mid -0.249642 -0.249642)
							(end -0.2794 -0.1778)
						)
						(arc
							(start -0.2794 0.1778)
							(mid -0.249642 0.249642)
							(end -0.1778 0.2794)
						)
						(arc
							(start 0.1778 0.2794)
							(mid 0.249642 0.249642)
							(end 0.2794 0.1778)
						)
						(arc
							(start 0.2794 -0.1778)
							(mid 0.249642 -0.249642)
							(end 0.1778 -0.2794)
						)
					)
					(width 0)
					(fill yes)
				)
			)
		)
	)
	(footprint ""
		(layer "F.Cu")
		(at 91.613228 -47.034196 -90)
		(property "Reference" "C219"
			(at 0 0 270)
			(layer "F.SilkS")
			(hide yes)
			(effects
				(font
					(size 1.27 1.27)
				)
			)
		)
		(property "Value" "SCD47U25V3KX-3-GP"
			(at 0 -2.8194 270)
			(unlocked yes)
			(layer "F.Fab")
			(hide yes)
			(effects
				(font
					(size 1.016 1.016)
					(thickness 0.1524)
				)
			)
		)
		(property "Device Type" "C603H36"
			(at 0 -4.3434 270)
			(unlocked yes)
			(layer "F.Fab")
			(hide yes)
			(effects
				(font
					(size 1.016 1.016)
					(thickness 0.1524)
				)
			)
		)
		(duplicate_pad_numbers_are_jumpers no)
		(fp_line
			(start 0.508 0)
			(end -0.508 0)
			(stroke
				(width 0.2032)
				(type default)
			)
			(layer "F.SilkS")
		)
		(fp_rect
			(start -0.5842 1.3335)
			(end 0.5842 -1.3335)
			(stroke
				(width 0)
				(type default)
			)
			(fill no)
			(layer "F.CrtYd")
		)
		(fp_rect
			(start -0.5842 1.3335)
			(end 0.5842 -1.3335)
			(stroke
				(width 0)
				(type default)
			)
			(fill no)
			(layer "F.Fab")
		)
		(pad "1" smd custom
			(at 0 -0.762 270)
			(size 0.2159 0.2159)
			(layers "F.Cu" "F.Mask" "F.Paste")
			(net "PQ2_D")
			(options
				(clearance outline)
				(anchor circle)
			)
			(primitives
				(gr_poly
					(pts
						(arc
							(start -0.3302 -0.4318)
							(mid -0.402042 -0.402042)
							(end -0.4318 -0.3302)
						)
						(arc
							(start -0.4318 0.3302)
							(mid -0.402042 0.402042)
							(end -0.3302 0.4318)
						)
						(arc
							(start 0.3302 0.4318)
							(mid 0.402042 0.402042)
							(end 0.4318 0.3302)
						)
						(arc
							(start 0.4318 -0.3302)
							(mid 0.402042 -0.402042)
							(end 0.3302 -0.4318)
						)
					)
					(width 0)
					(fill yes)
				)
			)
		)
		(pad "2" smd custom
			(at 0 0.762 270)
			(size 0.2159 0.2159)
			(layers "F.Cu" "F.Mask" "F.Paste")
			(net "P3V3")
			(options
				(clearance outline)
				(anchor circle)
			)
			(primitives
				(gr_poly
					(pts
						(arc
							(start -0.3302 -0.4318)
							(mid -0.402042 -0.402042)
							(end -0.4318 -0.3302)
						)
						(arc
							(start -0.4318 0.3302)
							(mid -0.402042 0.402042)
							(end -0.3302 0.4318)
						)
						(arc
							(start 0.3302 0.4318)
							(mid 0.402042 0.402042)
							(end 0.4318 0.3302)
						)
						(arc
							(start 0.4318 -0.3302)
							(mid 0.402042 -0.402042)
							(end 0.3302 -0.4318)
						)
					)
					(width 0)
					(fill yes)
				)
			)
		)
	)
	(footprint ""
		(layer "F.Cu")
		(at 21.2725 -167.247316 180)
		(property "Reference" "C223"
			(at 0 0 180)
			(layer "F.SilkS")
			(hide yes)
			(effects
				(font
					(size 1.27 1.27)
				)
			)
		)
		(property "Value" "SC10U6D3V5KX-4GP"
			(at -0.0762 -6.1214 180)
			(unlocked yes)
			(layer "F.Fab")
			(hide yes)
			(effects
				(font
					(size 1.016 1.016)
					(thickness 0.1524)
				)
			)
		)
		(property "Device Type" "C805H58"
			(at -0.0762 -8.1534 180)
			(unlocked yes)
			(layer "F.Fab")
			(hide yes)
			(effects
				(font
					(size 1.016 1.016)
					(thickness 0.1524)
				)
			)
		)
		(duplicate_pad_numbers_are_jumpers no)
		(fp_line
			(start 0.635 0)
			(end -0.635 0)
			(stroke
				(width 0.508)
				(type default)
			)
			(layer "F.SilkS")
		)
		(fp_rect
			(start -0.9652 1.778)
			(end 0.9652 -1.778)
			(stroke
				(width 0)
				(type default)
			)
			(fill no)
			(layer "F.CrtYd")
		)
		(fp_poly
			(pts
				(xy -0.9652 -1.778) (xy 0.9652 -1.778) (xy 0.9652 1.778) (xy -0.9652 1.778)
			)
			(stroke
				(width 0)
				(type default)
			)
			(fill no)
			(layer "F.Fab")
		)
		(pad "1" smd rect
			(at 0 -0.9652 180)
			(size 1.397 1.143)
			(layers "F.Cu" "F.Mask" "F.Paste")
			(net "TPS74801_P1V2_STBY_OUT")
		)
		(pad "2" smd rect
			(at 0 0.9652 180)
			(size 1.397 1.143)
			(layers "F.Cu" "F.Mask" "F.Paste")
			(net "GND")
		)
	)
	(footprint ""
		(layer "F.Cu")
		(at 98.922332 -18.402046 90)
		(property "Reference" "L1"
			(at 0 0 90)
			(layer "F.SilkS")
			(hide yes)
			(effects
				(font
					(size 1.27 1.27)
				)
			)
		)
		(property "Value" "DLW21HN900SQ2LGP-U"
			(at -0.0889 -2.7813 90)
			(unlocked yes)
			(layer "F.Fab")
			(hide yes)
			(effects
				(font
					(size 1.016 1.016)
					(thickness 0.1524)
				)
			)
		)
		(property "Device Type" "L2012-4P-1MH40"
			(at -0.0889 -4.3053 90)
			(unlocked yes)
			(layer "F.Fab")
			(hide yes)
			(effects
				(font
					(size 1.016 1.016)
					(thickness 0.1524)
				)
			)
		)
		(duplicate_pad_numbers_are_jumpers no)
		(fp_line
			(start 1.5494 -1.0668)
			(end 1.5494 1.0668)
			(stroke
				(width 0.1524)
				(type default)
			)
			(layer "F.SilkS")
		)
		(fp_line
			(start -1.5494 -1.0668)
			(end 1.5494 -1.0668)
			(stroke
				(width 0.1524)
				(type default)
			)
			(layer "F.SilkS")
		)
		(fp_line
			(start 1.5494 1.0668)
			(end -1.5494 1.0668)
			(stroke
				(width 0.1524)
				(type default)
			)
			(layer "F.SilkS")
		)
		(fp_line
			(start -1.5494 1.0668)
			(end -1.5494 -1.0668)
			(stroke
				(width 0.1524)
				(type default)
			)
			(layer "F.SilkS")
		)
		(fp_line
			(start 1.0668 1.1811)
			(end 0.6858 1.1811)
			(stroke
				(width 0.3302)
				(type default)
			)
			(layer "F.SilkS")
		)
		(fp_poly
			(pts
				(xy 1.500124 1.768856) (xy 0.230124 1.768856) (xy 0.865124 1.133856)
			)
			(stroke
				(width 0)
				(type default)
			)
			(fill yes)
			(layer "F.SilkS")
		)
		(fp_rect
			(start -1.0033 0.5969)
			(end 1.0033 -0.5969)
			(stroke
				(width 0)
				(type default)
			)
			(fill no)
			(layer "F.CrtYd")
		)
		(fp_poly
			(pts
				(xy -1.8034 1.3208) (xy -1.8034 -1.3208) (xy 1.8034 -1.3208) (xy 1.8034 0.0508) (xy 1.0033 0.0508)
				(xy 1.0033 -0.5969) (xy -1.0033 -0.5969) (xy -1.0033 0.5969) (xy 1.0033 0.5969) (xy 1.0033 0.0762)
				(xy 1.8034 0.0762) (xy 1.8034 1.3208)
			)
			(stroke
				(width 0)
				(type default)
			)
			(fill no)
			(layer "F.CrtYd")
		)
		(fp_rect
			(start -1.8034 1.3208)
			(end 1.8034 -1.3208)
			(stroke
				(width 0)
				(type default)
			)
			(fill no)
			(layer "F.Fab")
		)
		(pad "1" smd rect
			(at 0.8382 0.4826 90)
			(size 0.9144 0.6604)
			(layers "F.Cu" "F.Mask" "F.Paste")
			(net "USB_P1_DP")
		)
		(pad "2" smd rect
			(at -0.8382 0.4826 90)
			(size 0.9144 0.6604)
			(layers "F.Cu" "F.Mask" "F.Paste")
			(net "USB_P1_F_DP1")
		)
		(pad "3" smd rect
			(at -0.8382 -0.4826 90)
			(size 0.9144 0.6604)
			(layers "F.Cu" "F.Mask" "F.Paste")
			(net "USB_P1_F_DN1")
		)
		(pad "4" smd rect
			(at 0.8382 -0.4826 90)
			(size 0.9144 0.6604)
			(layers "F.Cu" "F.Mask" "F.Paste")
			(net "USB_P1_DN")
		)
		(zone
			(layer "F.Cu")
			(hatch none 0.5)
			(connect_pads
				(clearance 0)
			)
			(min_thickness 0.25)
			(keepout
				(tracks allowed)
				(vias not_allowed)
				(pads allowed)
				(copperpour not_allowed)
				(footprints allowed)
			)
			(placement
				(enabled no)
				(sheetname "")
			)
			(fill
				(thermal_gap 0.5)
				(thermal_bridge_width 0.5)
				(island_removal_mode 0)
			)
			(polygon
				(pts
					(xy 99.735132 -18.021046) (xy 99.074732 -18.021046) (xy 99.074732 -17.106646) (xy 98.769932 -17.106646)
					(xy 98.769932 -18.021046) (xy 98.109532 -18.021046) (xy 98.109532 -18.783046) (xy 98.769932 -18.783046)
					(xy 98.769932 -19.697446) (xy 99.074732 -19.697446) (xy 99.074732 -18.783046) (xy 99.735132 -18.783046)
				)
			)
		)
		(zone
			(layer "F.Cu")
			(hatch none 0.5)
			(connect_pads
				(clearance 0)
			)
			(min_thickness 0.25)
			(keepout
				(tracks not_allowed)
				(vias allowed)
				(pads allowed)
				(copperpour not_allowed)
				(footprints allowed)
			)
			(placement
				(enabled no)
				(sheetname "")
			)
			(fill
				(thermal_gap 0.5)
				(thermal_bridge_width 0.5)
				(island_removal_mode 0)
			)
			(polygon
				(pts
					(xy 99.735132 -18.021046) (xy 99.074732 -18.021046) (xy 99.074732 -17.106646) (xy 98.769932 -17.106646)
					(xy 98.769932 -18.021046) (xy 98.109532 -18.021046) (xy 98.109532 -18.783046) (xy 98.769932 -18.783046)
					(xy 98.769932 -19.697446) (xy 99.074732 -19.697446) (xy 99.074732 -18.783046) (xy 99.735132 -18.783046)
				)
			)
		)
	)
	(footprint ""
		(layer "F.Cu")
		(at 84.438744 -160.351216 180)
		(property "Reference" "C237"
			(at 0 0 180)
			(layer "F.SilkS")
			(hide yes)
			(effects
				(font
					(size 1.27 1.27)
				)
			)
		)
		(property "Value" "SC10U6D3V5KX-4GP"
			(at -0.0762 -6.1214 180)
			(unlocked yes)
			(layer "F.Fab")
			(hide yes)
			(effects
				(font
					(size 1.016 1.016)
					(thickness 0.1524)
				)
			)
		)
		(property "Device Type" "C805H58"
			(at -0.0762 -8.1534 180)
			(unlocked yes)
			(layer "F.Fab")
			(hide yes)
			(effects
				(font
					(size 1.016 1.016)
					(thickness 0.1524)
				)
			)
		)
		(duplicate_pad_numbers_are_jumpers no)
		(fp_line
			(start 0.635 0)
			(end -0.635 0)
			(stroke
				(width 0.508)
				(type default)
			)
			(layer "F.SilkS")
		)
		(fp_rect
			(start -0.9652 1.778)
			(end 0.9652 -1.778)
			(stroke
				(width 0)
				(type default)
			)
			(fill no)
			(layer "F.CrtYd")
		)
		(fp_poly
			(pts
				(xy -0.9652 -1.778) (xy 0.9652 -1.778) (xy 0.9652 1.778) (xy -0.9652 1.778)
			)
			(stroke
				(width 0)
				(type default)
			)
			(fill no)
			(layer "F.Fab")
		)
		(pad "1" smd rect
			(at 0 -0.9652 180)
			(size 1.397 1.143)
			(layers "F.Cu" "F.Mask" "F.Paste")
			(net "TPS74801_P1V15_STBY_OUT")
		)
		(pad "2" smd rect
			(at 0 0.9652 180)
			(size 1.397 1.143)
			(layers "F.Cu" "F.Mask" "F.Paste")
			(net "GND")
		)
	)
	(footprint ""
		(layer "F.Cu")
		(at 68.6054 -118.2116 90)
		(property "Reference" "C74"
			(at 0 0 90)
			(layer "F.SilkS")
			(hide yes)
			(effects
				(font
					(size 1.27 1.27)
				)
			)
		)
		(property "Value" "SCD1U16V2KX-3GP"
			(at 1.1811 -2.7051 90)
			(unlocked yes)
			(layer "F.Fab")
			(hide yes)
			(effects
				(font
					(size 1.016 1.016)
					(thickness 0.1524)
				)
			)
		)
		(property "Device Type" "C402H22"
			(at 1.1811 -4.2291 90)
			(unlocked yes)
			(layer "F.Fab")
			(hide yes)
			(effects
				(font
					(size 1.016 1.016)
					(thickness 0.1524)
				)
			)
		)
		(duplicate_pad_numbers_are_jumpers no)
		(fp_rect
			(start -0.4318 0.9525)
			(end 0.4318 -0.9525)
			(stroke
				(width 0)
				(type default)
			)
			(fill no)
			(layer "F.CrtYd")
		)
		(fp_rect
			(start -0.4318 0.9525)
			(end 0.4318 -0.9525)
			(stroke
				(width 0)
				(type default)
			)
			(fill no)
			(layer "F.Fab")
		)
		(pad "1" smd custom
			(at 0 -0.4445 90)
			(size 0.1524 0.1524)
			(layers "F.Cu" "F.Mask" "F.Paste")
			(net "P3V3_STBY")
			(options
				(clearance outline)
				(anchor circle)
			)
			(primitives
				(gr_poly
					(pts
						(arc
							(start 0.3048 -0.2032)
							(mid 0.275042 -0.275042)
							(end 0.2032 -0.3048)
						)
						(arc
							(start -0.2032 -0.3048)
							(mid -0.275042 -0.275042)
							(end -0.3048 -0.2032)
						)
						(arc
							(start -0.3048 0.2032)
							(mid -0.275042 0.275042)
							(end -0.2032 0.3048)
						)
						(arc
							(start 0.2032 0.3048)
							(mid 0.275042 0.275042)
							(end 0.3048 0.2032)
						)
					)
					(width 0)
					(fill yes)
				)
			)
		)
		(pad "2" smd custom
			(at 0 0.4445 90)
			(size 0.1524 0.1524)
			(layers "F.Cu" "F.Mask" "F.Paste")
			(net "GND")
			(options
				(clearance outline)
				(anchor circle)
			)
			(primitives
				(gr_poly
					(pts
						(arc
							(start 0.3048 -0.2032)
							(mid 0.275042 -0.275042)
							(end 0.2032 -0.3048)
						)
						(arc
							(start -0.2032 -0.3048)
							(mid -0.275042 -0.275042)
							(end -0.3048 -0.2032)
						)
						(arc
							(start -0.3048 0.2032)
							(mid -0.275042 0.275042)
							(end -0.2032 0.3048)
						)
						(arc
							(start 0.2032 0.3048)
							(mid 0.275042 0.275042)
							(end 0.3048 0.2032)
						)
					)
					(width 0)
					(fill yes)
				)
			)
		)
	)
	(footprint ""
		(layer "F.Cu")
		(at 205.0034 -100.93452)
		(property "Reference" "TP216"
			(at 0 0 0)
			(layer "F.SilkS")
			(hide yes)
			(effects
				(font
					(size 1.27 1.27)
				)
			)
		)
		(property "Value" "TPAD32-GP"
			(at -0.0508 -1.6764 0)
			(unlocked yes)
			(layer "F.Fab")
			(hide yes)
			(effects
				(font
					(size 1.016 1.016)
					(thickness 0.1524)
				)
			)
		)
		(property "Device Type" "TPAD32"
			(at -0.0508 -3.2004 0)
			(unlocked yes)
			(layer "F.Fab")
			(hide yes)
			(effects
				(font
					(size 1.016 1.016)
					(thickness 0.1524)
				)
			)
		)
		(duplicate_pad_numbers_are_jumpers no)
		(fp_poly
			(pts
				(arc
					(start 0.4064 0)
					(mid -0.4064 0)
					(end 0.4064 0)
				)
			)
			(stroke
				(width 0)
				(type default)
			)
			(fill no)
			(layer "F.CrtYd")
		)
		(fp_poly
			(pts
				(arc
					(start 0.7112 0)
					(mid -0.7112 0)
					(end 0.7112 0)
				)
			)
			(stroke
				(width 0)
				(type default)
			)
			(fill no)
			(layer "F.Fab")
		)
		(pad "1" smd circle
			(at 0 0)
			(size 0.8128 0.8128)
			(layers "F.Cu" "F.Mask" "F.Paste")
			(net "TEMP_2_ALERT")
		)
	)
	(footprint ""
		(layer "F.Cu")
		(at 215.470994 -41.955212 90)
		(property "Reference" "R463"
			(at 0 0 90)
			(layer "F.SilkS")
			(hide yes)
			(effects
				(font
					(size 1.27 1.27)
				)
			)
		)
		(property "Value" "10KR2F-2-GP"
			(at 0.064008 -3.993896 90)
			(unlocked yes)
			(layer "F.Fab")
			(hide yes)
			(effects
				(font
					(size 1.016 1.016)
					(thickness 0.1524)
				)
			)
		)
		(property "Device Type" "R402H16"
			(at 0.064008 -5.517896 90)
			(unlocked yes)
			(layer "F.Fab")
			(hide yes)
			(effects
				(font
					(size 1.016 1.016)
					(thickness 0.1524)
				)
			)
		)
		(duplicate_pad_numbers_are_jumpers no)
		(fp_line
			(start 0.508 -0.9398)
			(end -0.508 -0.9398)
			(stroke
				(width 0.1524)
				(type default)
			)
			(layer "F.SilkS")
		)
		(fp_line
			(start -0.508 -0.9398)
			(end -0.508 0.9398)
			(stroke
				(width 0.1524)
				(type default)
			)
			(layer "F.SilkS")
		)
		(fp_rect
			(start -0.508 0.9398)
			(end 0.508 -0.9398)
			(stroke
				(width 0)
				(type default)
			)
			(fill no)
			(layer "F.CrtYd")
		)
		(fp_rect
			(start -0.508 0.9398)
			(end 0.508 -0.9398)
			(stroke
				(width 0)
				(type default)
			)
			(fill no)
			(layer "F.Fab")
		)
		(pad "1" smd custom
			(at 0 -0.4445 90)
			(size 0.1397 0.1397)
			(layers "F.Cu" "F.Mask" "F.Paste")
			(net "P12V_STBY")
			(options
				(clearance outline)
				(anchor circle)
			)
			(primitives
				(gr_poly
					(pts
						(arc
							(start -0.1778 -0.2794)
							(mid -0.249642 -0.249642)
							(end -0.2794 -0.1778)
						)
						(arc
							(start -0.2794 0.1778)
							(mid -0.249642 0.249642)
							(end -0.1778 0.2794)
						)
						(arc
							(start 0.1778 0.2794)
							(mid 0.249642 0.249642)
							(end 0.2794 0.1778)
						)
						(arc
							(start 0.2794 -0.1778)
							(mid 0.249642 -0.249642)
							(end 0.1778 -0.2794)
						)
					)
					(width 0)
					(fill yes)
				)
			)
		)
		(pad "2" smd custom
			(at 0 0.4445 90)
			(size 0.1397 0.1397)
			(layers "F.Cu" "F.Mask" "F.Paste")
			(net "P5V_EN_R")
			(options
				(clearance outline)
				(anchor circle)
			)
			(primitives
				(gr_poly
					(pts
						(arc
							(start -0.1778 -0.2794)
							(mid -0.249642 -0.249642)
							(end -0.2794 -0.1778)
						)
						(arc
							(start -0.2794 0.1778)
							(mid -0.249642 0.249642)
							(end -0.1778 0.2794)
						)
						(arc
							(start 0.1778 0.2794)
							(mid 0.249642 0.249642)
							(end 0.2794 0.1778)
						)
						(arc
							(start 0.2794 -0.1778)
							(mid 0.249642 -0.249642)
							(end 0.1778 -0.2794)
						)
					)
					(width 0)
					(fill yes)
				)
			)
		)
	)
	(footprint ""
		(layer "F.Cu")
		(at 74.680572 -168.346628 180)
		(property "Reference" "C241"
			(at 0 0 180)
			(layer "F.SilkS")
			(hide yes)
			(effects
				(font
					(size 1.27 1.27)
				)
			)
		)
		(property "Value" "SC1U16V3KX-5GP"
			(at 0 -2.8194 180)
			(unlocked yes)
			(layer "F.Fab")
			(hide yes)
			(effects
				(font
					(size 1.016 1.016)
					(thickness 0.1524)
				)
			)
		)
		(property "Device Type" "C603H36"
			(at 0 -4.3434 180)
			(unlocked yes)
			(layer "F.Fab")
			(hide yes)
			(effects
				(font
					(size 1.016 1.016)
					(thickness 0.1524)
				)
			)
		)
		(duplicate_pad_numbers_are_jumpers no)
		(fp_line
			(start 0.508 0)
			(end -0.508 0)
			(stroke
				(width 0.2032)
				(type default)
			)
			(layer "F.SilkS")
		)
		(fp_rect
			(start -0.5842 1.3335)
			(end 0.5842 -1.3335)
			(stroke
				(width 0)
				(type default)
			)
			(fill no)
			(layer "F.CrtYd")
		)
		(fp_rect
			(start -0.5842 1.3335)
			(end 0.5842 -1.3335)
			(stroke
				(width 0)
				(type default)
			)
			(fill no)
			(layer "F.Fab")
		)
		(pad "1" smd custom
			(at 0 -0.762 180)
			(size 0.2159 0.2159)
			(layers "F.Cu" "F.Mask" "F.Paste")
			(net "TPS74801_P1V15_STBY_BIAS")
			(options
				(clearance outline)
				(anchor circle)
			)
			(primitives
				(gr_poly
					(pts
						(arc
							(start -0.3302 -0.4318)
							(mid -0.402042 -0.402042)
							(end -0.4318 -0.3302)
						)
						(arc
							(start -0.4318 0.3302)
							(mid -0.402042 0.402042)
							(end -0.3302 0.4318)
						)
						(arc
							(start 0.3302 0.4318)
							(mid 0.402042 0.402042)
							(end 0.4318 0.3302)
						)
						(arc
							(start 0.4318 -0.3302)
							(mid 0.402042 -0.402042)
							(end 0.3302 -0.4318)
						)
					)
					(width 0)
					(fill yes)
				)
			)
		)
		(pad "2" smd custom
			(at 0 0.762 180)
			(size 0.2159 0.2159)
			(layers "F.Cu" "F.Mask" "F.Paste")
			(net "GND")
			(options
				(clearance outline)
				(anchor circle)
			)
			(primitives
				(gr_poly
					(pts
						(arc
							(start -0.3302 -0.4318)
							(mid -0.402042 -0.402042)
							(end -0.4318 -0.3302)
						)
						(arc
							(start -0.4318 0.3302)
							(mid -0.402042 0.402042)
							(end -0.3302 0.4318)
						)
						(arc
							(start 0.3302 0.4318)
							(mid 0.402042 0.402042)
							(end 0.4318 0.3302)
						)
						(arc
							(start 0.4318 -0.3302)
							(mid 0.402042 -0.402042)
							(end 0.3302 -0.4318)
						)
					)
					(width 0)
					(fill yes)
				)
			)
		)
	)
	(footprint ""
		(layer "F.Cu")
		(at 65.216532 -149.753066 90)
		(property "Reference" "C82"
			(at 0 0 90)
			(layer "F.SilkS")
			(hide yes)
			(effects
				(font
					(size 1.27 1.27)
				)
			)
		)
		(property "Value" "SC33P50V2JN-3GP"
			(at 1.1811 -2.7051 90)
			(unlocked yes)
			(layer "F.Fab")
			(hide yes)
			(effects
				(font
					(size 1.016 1.016)
					(thickness 0.1524)
				)
			)
		)
		(property "Device Type" "C402H22"
			(at 1.1811 -4.2291 90)
			(unlocked yes)
			(layer "F.Fab")
			(hide yes)
			(effects
				(font
					(size 1.016 1.016)
					(thickness 0.1524)
				)
			)
		)
		(duplicate_pad_numbers_are_jumpers no)
		(fp_rect
			(start -0.4318 0.9525)
			(end 0.4318 -0.9525)
			(stroke
				(width 0)
				(type default)
			)
			(fill no)
			(layer "F.CrtYd")
		)
		(fp_rect
			(start -0.4318 0.9525)
			(end 0.4318 -0.9525)
			(stroke
				(width 0)
				(type default)
			)
			(fill no)
			(layer "F.Fab")
		)
		(pad "1" smd custom
			(at 0 -0.4445 90)
			(size 0.1524 0.1524)
			(layers "F.Cu" "F.Mask" "F.Paste")
			(net "PD_USB2AVRES")
			(options
				(clearance outline)
				(anchor circle)
			)
			(primitives
				(gr_poly
					(pts
						(arc
							(start 0.3048 -0.2032)
							(mid 0.275042 -0.275042)
							(end 0.2032 -0.3048)
						)
						(arc
							(start -0.2032 -0.3048)
							(mid -0.275042 -0.275042)
							(end -0.3048 -0.2032)
						)
						(arc
							(start -0.3048 0.2032)
							(mid -0.275042 0.275042)
							(end -0.2032 0.3048)
						)
						(arc
							(start 0.2032 0.3048)
							(mid 0.275042 0.275042)
							(end 0.3048 0.2032)
						)
					)
					(width 0)
					(fill yes)
				)
			)
		)
		(pad "2" smd custom
			(at 0 0.4445 90)
			(size 0.1524 0.1524)
			(layers "F.Cu" "F.Mask" "F.Paste")
			(net "GND")
			(options
				(clearance outline)
				(anchor circle)
			)
			(primitives
				(gr_poly
					(pts
						(arc
							(start 0.3048 -0.2032)
							(mid 0.275042 -0.275042)
							(end 0.2032 -0.3048)
						)
						(arc
							(start -0.2032 -0.3048)
							(mid -0.275042 -0.275042)
							(end -0.3048 -0.2032)
						)
						(arc
							(start -0.3048 0.2032)
							(mid -0.275042 0.275042)
							(end -0.2032 0.3048)
						)
						(arc
							(start 0.2032 0.3048)
							(mid 0.275042 0.275042)
							(end 0.3048 0.2032)
						)
					)
					(width 0)
					(fill yes)
				)
			)
		)
	)
	(footprint ""
		(layer "F.Cu")
		(at 123.828556 -13.167614 90)
		(property "Reference" "R434"
			(at 0 0 90)
			(layer "F.SilkS")
			(hide yes)
			(effects
				(font
					(size 1.27 1.27)
				)
			)
		)
		(property "Value" "100R2D-GP"
			(at 0.064008 -3.993896 90)
			(unlocked yes)
			(layer "F.Fab")
			(hide yes)
			(effects
				(font
					(size 1.016 1.016)
					(thickness 0.1524)
				)
			)
		)
		(property "Device Type" "R402H14"
			(at 0.064008 -5.517896 90)
			(unlocked yes)
			(layer "F.Fab")
			(hide yes)
			(effects
				(font
					(size 1.016 1.016)
					(thickness 0.1524)
				)
			)
		)
		(duplicate_pad_numbers_are_jumpers no)
		(fp_line
			(start 0.508 -0.9398)
			(end -0.508 -0.9398)
			(stroke
				(width 0.1524)
				(type default)
			)
			(layer "F.SilkS")
		)
		(fp_line
			(start -0.508 -0.9398)
			(end -0.508 0.9398)
			(stroke
				(width 0.1524)
				(type default)
			)
			(layer "F.SilkS")
		)
		(fp_rect
			(start -0.508 0.9398)
			(end 0.508 -0.9398)
			(stroke
				(width 0)
				(type default)
			)
			(fill no)
			(layer "F.CrtYd")
		)
		(fp_rect
			(start -0.508 0.9398)
			(end 0.508 -0.9398)
			(stroke
				(width 0)
				(type default)
			)
			(fill no)
			(layer "F.Fab")
		)
		(pad "1" smd custom
			(at 0 -0.4445 90)
			(size 0.1397 0.1397)
			(layers "F.Cu" "F.Mask" "F.Paste")
			(net "GND")
			(options
				(clearance outline)
				(anchor circle)
			)
			(primitives
				(gr_poly
					(pts
						(arc
							(start -0.1778 -0.2794)
							(mid -0.249642 -0.249642)
							(end -0.2794 -0.1778)
						)
						(arc
							(start -0.2794 0.1778)
							(mid -0.249642 0.249642)
							(end -0.1778 0.2794)
						)
						(arc
							(start 0.1778 0.2794)
							(mid 0.249642 0.249642)
							(end 0.2794 0.1778)
						)
						(arc
							(start 0.2794 -0.1778)
							(mid 0.249642 -0.249642)
							(end 0.1778 -0.2794)
						)
					)
					(width 0)
					(fill yes)
				)
			)
		)
		(pad "2" smd custom
			(at 0 0.4445 90)
			(size 0.1397 0.1397)
			(layers "F.Cu" "F.Mask" "F.Paste")
			(net "MB0_TEMP_E")
			(options
				(clearance outline)
				(anchor circle)
			)
			(primitives
				(gr_poly
					(pts
						(arc
							(start -0.1778 -0.2794)
							(mid -0.249642 -0.249642)
							(end -0.2794 -0.1778)
						)
						(arc
							(start -0.2794 0.1778)
							(mid -0.249642 0.249642)
							(end -0.1778 0.2794)
						)
						(arc
							(start 0.1778 0.2794)
							(mid 0.249642 0.249642)
							(end 0.2794 0.1778)
						)
						(arc
							(start 0.2794 -0.1778)
							(mid 0.249642 -0.249642)
							(end 0.1778 -0.2794)
						)
					)
					(width 0)
					(fill yes)
				)
			)
		)
	)
	(footprint ""
		(layer "F.Cu")
		(at 20.591272 -129.074164 180)
		(property "Reference" "R225"
			(at 0 0 180)
			(layer "F.SilkS")
			(hide yes)
			(effects
				(font
					(size 1.27 1.27)
				)
			)
		)
		(property "Value" "120R2F-GP"
			(at 0.064008 -3.993896 180)
			(unlocked yes)
			(layer "F.Fab")
			(hide yes)
			(effects
				(font
					(size 1.016 1.016)
					(thickness 0.1524)
				)
			)
		)
		(property "Device Type" "R402H16"
			(at 0.064008 -5.517896 180)
			(unlocked yes)
			(layer "F.Fab")
			(hide yes)
			(effects
				(font
					(size 1.016 1.016)
					(thickness 0.1524)
				)
			)
		)
		(duplicate_pad_numbers_are_jumpers no)
		(fp_line
			(start 0.508 -0.9398)
			(end -0.508 -0.9398)
			(stroke
				(width 0.1524)
				(type default)
			)
			(layer "F.SilkS")
		)
		(fp_line
			(start -0.508 -0.9398)
			(end -0.508 0.9398)
			(stroke
				(width 0.1524)
				(type default)
			)
			(layer "F.SilkS")
		)
		(fp_rect
			(start -0.508 0.9398)
			(end 0.508 -0.9398)
			(stroke
				(width 0)
				(type default)
			)
			(fill no)
			(layer "F.CrtYd")
		)
		(fp_rect
			(start -0.508 0.9398)
			(end 0.508 -0.9398)
			(stroke
				(width 0)
				(type default)
			)
			(fill no)
			(layer "F.Fab")
		)
		(pad "1" smd custom
			(at 0 -0.4445 180)
			(size 0.1397 0.1397)
			(layers "F.Cu" "F.Mask" "F.Paste")
			(net "GND")
			(options
				(clearance outline)
				(anchor circle)
			)
			(primitives
				(gr_poly
					(pts
						(arc
							(start -0.1778 -0.2794)
							(mid -0.249642 -0.249642)
							(end -0.2794 -0.1778)
						)
						(arc
							(start -0.2794 0.1778)
							(mid -0.249642 0.249642)
							(end -0.1778 0.2794)
						)
						(arc
							(start 0.1778 0.2794)
							(mid 0.249642 0.249642)
							(end 0.2794 0.1778)
						)
						(arc
							(start 0.2794 -0.1778)
							(mid 0.249642 -0.249642)
							(end 0.1778 -0.2794)
						)
					)
					(width 0)
					(fill yes)
				)
			)
		)
		(pad "2" smd custom
			(at 0 0.4445 180)
			(size 0.1397 0.1397)
			(layers "F.Cu" "F.Mask" "F.Paste")
			(net "MEMCASN")
			(options
				(clearance outline)
				(anchor circle)
			)
			(primitives
				(gr_poly
					(pts
						(arc
							(start -0.1778 -0.2794)
							(mid -0.249642 -0.249642)
							(end -0.2794 -0.1778)
						)
						(arc
							(start -0.2794 0.1778)
							(mid -0.249642 0.249642)
							(end -0.1778 0.2794)
						)
						(arc
							(start 0.1778 0.2794)
							(mid 0.249642 0.249642)
							(end 0.2794 0.1778)
						)
						(arc
							(start 0.2794 -0.1778)
							(mid 0.249642 -0.249642)
							(end 0.1778 -0.2794)
						)
					)
					(width 0)
					(fill yes)
				)
			)
		)
	)
	(footprint ""
		(layer "F.Cu")
		(at 99.045776 -145.541746 -90)
		(property "Reference" "R426"
			(at 0 0 270)
			(layer "F.SilkS")
			(hide yes)
			(effects
				(font
					(size 1.27 1.27)
				)
			)
		)
		(property "Value" "0R2J-2-GP"
			(at 0.064008 -3.993896 270)
			(unlocked yes)
			(layer "F.Fab")
			(hide yes)
			(effects
				(font
					(size 1.016 1.016)
					(thickness 0.1524)
				)
			)
		)
		(property "Device Type" "R402H16"
			(at 0.064008 -5.517896 270)
			(unlocked yes)
			(layer "F.Fab")
			(hide yes)
			(effects
				(font
					(size 1.016 1.016)
					(thickness 0.1524)
				)
			)
		)
		(duplicate_pad_numbers_are_jumpers no)
		(fp_line
			(start -0.508 -0.9398)
			(end -0.508 0.9398)
			(stroke
				(width 0.1524)
				(type default)
			)
			(layer "F.SilkS")
		)
		(fp_line
			(start 0.508 -0.9398)
			(end -0.508 -0.9398)
			(stroke
				(width 0.1524)
				(type default)
			)
			(layer "F.SilkS")
		)
		(fp_rect
			(start -0.508 0.9398)
			(end 0.508 -0.9398)
			(stroke
				(width 0)
				(type default)
			)
			(fill no)
			(layer "F.CrtYd")
		)
		(fp_rect
			(start -0.508 0.9398)
			(end 0.508 -0.9398)
			(stroke
				(width 0)
				(type default)
			)
			(fill no)
			(layer "F.Fab")
		)
		(pad "1" smd custom
			(at 0 -0.4445 270)
			(size 0.1397 0.1397)
			(layers "F.Cu" "F.Mask" "F.Paste")
			(net "I2C_DEBUG_SDA_L")
			(options
				(clearance outline)
				(anchor circle)
			)
			(primitives
				(gr_poly
					(pts
						(arc
							(start -0.1778 -0.2794)
							(mid -0.249642 -0.249642)
							(end -0.2794 -0.1778)
						)
						(arc
							(start -0.2794 0.1778)
							(mid -0.249642 0.249642)
							(end -0.1778 0.2794)
						)
						(arc
							(start 0.1778 0.2794)
							(mid 0.249642 0.249642)
							(end 0.2794 0.1778)
						)
						(arc
							(start 0.2794 -0.1778)
							(mid 0.249642 -0.249642)
							(end 0.1778 -0.2794)
						)
					)
					(width 0)
					(fill yes)
				)
			)
		)
		(pad "2" smd custom
			(at 0 0.4445 270)
			(size 0.1397 0.1397)
			(layers "F.Cu" "F.Mask" "F.Paste")
			(net "I2C_DEBUG_SDA_R")
			(options
				(clearance outline)
				(anchor circle)
			)
			(primitives
				(gr_poly
					(pts
						(arc
							(start -0.1778 -0.2794)
							(mid -0.249642 -0.249642)
							(end -0.2794 -0.1778)
						)
						(arc
							(start -0.2794 0.1778)
							(mid -0.249642 0.249642)
							(end -0.1778 0.2794)
						)
						(arc
							(start 0.1778 0.2794)
							(mid 0.249642 0.249642)
							(end 0.2794 0.1778)
						)
						(arc
							(start 0.2794 -0.1778)
							(mid 0.249642 -0.249642)
							(end 0.1778 -0.2794)
						)
					)
					(width 0)
					(fill yes)
				)
			)
		)
	)
	(footprint ""
		(layer "F.Cu")
		(at 83.358228 -82.136996 90)
		(property "Reference" "VIA12"
			(at 0 0 90)
			(layer "F.SilkS")
			(hide yes)
			(effects
				(font
					(size 1.27 1.27)
				)
			)
		)
		(property "Value" "85OHM-8L-1D6MM-L16L18-GP"
			(at 4.064 0.6096 90)
			(unlocked yes)
			(layer "F.Fab")
			(hide yes)
			(effects
				(font
					(size 1.016 1.016)
					(thickness 0.1524)
				)
			)
		)
		(property "Device Type" "VIA-PCIE-4P-368076"
			(at 4.064 -0.9144 90)
			(unlocked yes)
			(layer "F.Fab")
			(hide yes)
			(effects
				(font
					(size 1.016 1.016)
					(thickness 0.1524)
				)
			)
		)
		(duplicate_pad_numbers_are_jumpers no)
		(fp_rect
			(start -1.8415 0.381)
			(end 1.8415 -0.381)
			(stroke
				(width 0)
				(type default)
			)
			(fill no)
			(layer "F.CrtYd")
		)
		(fp_rect
			(start -1.8415 0.381)
			(end 1.8415 -0.381)
			(stroke
				(width 0)
				(type default)
			)
			(fill no)
			(layer "F.Fab")
		)
		(pad "1" thru_hole circle
			(at -1.4605 0 90)
			(size 0.508 0.508)
			(drill 0.254)
			(layers "*.Cu" "*.Mask")
			(remove_unused_layers no)
			(net "GND")
			(clearance 0.127)
			(thermal_gap 0.127)
		)
		(pad "2" thru_hole circle
			(at -0.4445 0 90)
			(size 0.508 0.508)
			(drill 0.254)
			(layers "*.Cu" "*.Mask")
			(remove_unused_layers no)
			(net "PCIE_IOM_TO_COMP_19_DP")
			(clearance 0.127)
			(thermal_gap 0.127)
		)
		(pad "3" thru_hole circle
			(at 0.4445 0 90)
			(size 0.508 0.508)
			(drill 0.254)
			(layers "*.Cu" "*.Mask")
			(remove_unused_layers no)
			(net "PCIE_IOM_TO_COMP_19_DN")
			(clearance 0.127)
			(thermal_gap 0.127)
		)
		(pad "4" thru_hole circle
			(at 1.4605 0 90)
			(size 0.508 0.508)
			(drill 0.254)
			(layers "*.Cu" "*.Mask")
			(remove_unused_layers no)
			(net "GND")
			(clearance 0.127)
			(thermal_gap 0.127)
		)
	)
	(footprint ""
		(layer "F.Cu")
		(at 74.14133 -136.980676 90)
		(property "Reference" "C27"
			(at 0 0 90)
			(layer "F.SilkS")
			(hide yes)
			(effects
				(font
					(size 1.27 1.27)
				)
			)
		)
		(property "Value" "SCD1U16V2KX-3GP"
			(at 1.1811 -2.7051 90)
			(unlocked yes)
			(layer "F.Fab")
			(hide yes)
			(effects
				(font
					(size 1.016 1.016)
					(thickness 0.1524)
				)
			)
		)
		(property "Device Type" "C402H22"
			(at 1.1811 -4.2291 90)
			(unlocked yes)
			(layer "F.Fab")
			(hide yes)
			(effects
				(font
					(size 1.016 1.016)
					(thickness 0.1524)
				)
			)
		)
		(duplicate_pad_numbers_are_jumpers no)
		(fp_rect
			(start -0.4318 0.9525)
			(end 0.4318 -0.9525)
			(stroke
				(width 0)
				(type default)
			)
			(fill no)
			(layer "F.CrtYd")
		)
		(fp_rect
			(start -0.4318 0.9525)
			(end 0.4318 -0.9525)
			(stroke
				(width 0)
				(type default)
			)
			(fill no)
			(layer "F.Fab")
		)
		(pad "1" smd custom
			(at 0 -0.4445 90)
			(size 0.1524 0.1524)
			(layers "F.Cu" "F.Mask" "F.Paste")
			(net "P3V3_STBY")
			(options
				(clearance outline)
				(anchor circle)
			)
			(primitives
				(gr_poly
					(pts
						(arc
							(start 0.3048 -0.2032)
							(mid 0.275042 -0.275042)
							(end 0.2032 -0.3048)
						)
						(arc
							(start -0.2032 -0.3048)
							(mid -0.275042 -0.275042)
							(end -0.3048 -0.2032)
						)
						(arc
							(start -0.3048 0.2032)
							(mid -0.275042 0.275042)
							(end -0.2032 0.3048)
						)
						(arc
							(start 0.2032 0.3048)
							(mid 0.275042 0.275042)
							(end 0.3048 0.2032)
						)
					)
					(width 0)
					(fill yes)
				)
			)
		)
		(pad "2" smd custom
			(at 0 0.4445 90)
			(size 0.1524 0.1524)
			(layers "F.Cu" "F.Mask" "F.Paste")
			(net "GND")
			(options
				(clearance outline)
				(anchor circle)
			)
			(primitives
				(gr_poly
					(pts
						(arc
							(start 0.3048 -0.2032)
							(mid 0.275042 -0.275042)
							(end 0.2032 -0.3048)
						)
						(arc
							(start -0.2032 -0.3048)
							(mid -0.275042 -0.275042)
							(end -0.3048 -0.2032)
						)
						(arc
							(start -0.3048 0.2032)
							(mid -0.275042 0.275042)
							(end -0.2032 0.3048)
						)
						(arc
							(start 0.2032 0.3048)
							(mid 0.275042 0.275042)
							(end 0.3048 0.2032)
						)
					)
					(width 0)
					(fill yes)
				)
			)
		)
	)
	(footprint ""
		(layer "F.Cu")
		(at 14.478 -11.43 -90)
		(property "Reference" "R47"
			(at 0 0 270)
			(layer "F.SilkS")
			(hide yes)
			(effects
				(font
					(size 1.27 1.27)
				)
			)
		)
		(property "Value" "1MR2F-GP"
			(at 0.064008 -3.993896 270)
			(unlocked yes)
			(layer "F.Fab")
			(hide yes)
			(effects
				(font
					(size 1.016 1.016)
					(thickness 0.1524)
				)
			)
		)
		(property "Device Type" "R402H16"
			(at 0.064008 -5.517896 270)
			(unlocked yes)
			(layer "F.Fab")
			(hide yes)
			(effects
				(font
					(size 1.016 1.016)
					(thickness 0.1524)
				)
			)
		)
		(duplicate_pad_numbers_are_jumpers no)
		(fp_line
			(start -0.508 -0.9398)
			(end -0.508 0.9398)
			(stroke
				(width 0.1524)
				(type default)
			)
			(layer "F.SilkS")
		)
		(fp_line
			(start 0.508 -0.9398)
			(end -0.508 -0.9398)
			(stroke
				(width 0.1524)
				(type default)
			)
			(layer "F.SilkS")
		)
		(fp_rect
			(start -0.508 0.9398)
			(end 0.508 -0.9398)
			(stroke
				(width 0)
				(type default)
			)
			(fill no)
			(layer "F.CrtYd")
		)
		(fp_rect
			(start -0.508 0.9398)
			(end 0.508 -0.9398)
			(stroke
				(width 0)
				(type default)
			)
			(fill no)
			(layer "F.Fab")
		)
		(pad "1" smd custom
			(at 0 -0.4445 270)
			(size 0.1397 0.1397)
			(layers "F.Cu" "F.Mask" "F.Paste")
			(net "RST_BTN_GND")
			(options
				(clearance outline)
				(anchor circle)
			)
			(primitives
				(gr_poly
					(pts
						(arc
							(start -0.1778 -0.2794)
							(mid -0.249642 -0.249642)
							(end -0.2794 -0.1778)
						)
						(arc
							(start -0.2794 0.1778)
							(mid -0.249642 0.249642)
							(end -0.1778 0.2794)
						)
						(arc
							(start 0.1778 0.2794)
							(mid 0.249642 0.249642)
							(end 0.2794 0.1778)
						)
						(arc
							(start 0.2794 -0.1778)
							(mid 0.249642 -0.249642)
							(end 0.1778 -0.2794)
						)
					)
					(width 0)
					(fill yes)
				)
			)
		)
		(pad "2" smd custom
			(at 0 0.4445 270)
			(size 0.1397 0.1397)
			(layers "F.Cu" "F.Mask" "F.Paste")
			(net "GND")
			(options
				(clearance outline)
				(anchor circle)
			)
			(primitives
				(gr_poly
					(pts
						(arc
							(start -0.1778 -0.2794)
							(mid -0.249642 -0.249642)
							(end -0.2794 -0.1778)
						)
						(arc
							(start -0.2794 0.1778)
							(mid -0.249642 0.249642)
							(end -0.1778 0.2794)
						)
						(arc
							(start 0.1778 0.2794)
							(mid 0.249642 0.249642)
							(end 0.2794 0.1778)
						)
						(arc
							(start 0.2794 -0.1778)
							(mid 0.249642 -0.249642)
							(end 0.1778 -0.2794)
						)
					)
					(width 0)
					(fill yes)
				)
			)
		)
	)
	(footprint ""
		(layer "F.Cu")
		(at 91.537028 -48.7426 180)
		(property "Reference" "R503"
			(at 0 0 180)
			(layer "F.SilkS")
			(hide yes)
			(effects
				(font
					(size 1.27 1.27)
				)
			)
		)
		(property "Value" "1MR2F-GP"
			(at 0.064008 -3.993896 180)
			(unlocked yes)
			(layer "F.Fab")
			(hide yes)
			(effects
				(font
					(size 1.016 1.016)
					(thickness 0.1524)
				)
			)
		)
		(property "Device Type" "R402H16"
			(at 0.064008 -5.517896 180)
			(unlocked yes)
			(layer "F.Fab")
			(hide yes)
			(effects
				(font
					(size 1.016 1.016)
					(thickness 0.1524)
				)
			)
		)
		(duplicate_pad_numbers_are_jumpers no)
		(fp_line
			(start 0.508 -0.9398)
			(end -0.508 -0.9398)
			(stroke
				(width 0.1524)
				(type default)
			)
			(layer "F.SilkS")
		)
		(fp_line
			(start -0.508 -0.9398)
			(end -0.508 0.9398)
			(stroke
				(width 0.1524)
				(type default)
			)
			(layer "F.SilkS")
		)
		(fp_rect
			(start -0.508 0.9398)
			(end 0.508 -0.9398)
			(stroke
				(width 0)
				(type default)
			)
			(fill no)
			(layer "F.CrtYd")
		)
		(fp_rect
			(start -0.508 0.9398)
			(end 0.508 -0.9398)
			(stroke
				(width 0)
				(type default)
			)
			(fill no)
			(layer "F.Fab")
		)
		(pad "1" smd custom
			(at 0 -0.4445 180)
			(size 0.1397 0.1397)
			(layers "F.Cu" "F.Mask" "F.Paste")
			(net "PQ2_D")
			(options
				(clearance outline)
				(anchor circle)
			)
			(primitives
				(gr_poly
					(pts
						(arc
							(start -0.1778 -0.2794)
							(mid -0.249642 -0.249642)
							(end -0.2794 -0.1778)
						)
						(arc
							(start -0.2794 0.1778)
							(mid -0.249642 0.249642)
							(end -0.1778 0.2794)
						)
						(arc
							(start 0.1778 0.2794)
							(mid 0.249642 0.249642)
							(end 0.2794 0.1778)
						)
						(arc
							(start 0.2794 -0.1778)
							(mid 0.249642 -0.249642)
							(end 0.1778 -0.2794)
						)
					)
					(width 0)
					(fill yes)
				)
			)
		)
		(pad "2" smd custom
			(at 0 0.4445 180)
			(size 0.1397 0.1397)
			(layers "F.Cu" "F.Mask" "F.Paste")
			(net "P12V_STBY")
			(options
				(clearance outline)
				(anchor circle)
			)
			(primitives
				(gr_poly
					(pts
						(arc
							(start -0.1778 -0.2794)
							(mid -0.249642 -0.249642)
							(end -0.2794 -0.1778)
						)
						(arc
							(start -0.2794 0.1778)
							(mid -0.249642 0.249642)
							(end -0.1778 0.2794)
						)
						(arc
							(start 0.1778 0.2794)
							(mid 0.249642 0.249642)
							(end 0.2794 0.1778)
						)
						(arc
							(start 0.2794 -0.1778)
							(mid 0.249642 -0.249642)
							(end 0.1778 -0.2794)
						)
					)
					(width 0)
					(fill yes)
				)
			)
		)
	)
	(footprint ""
		(layer "F.Cu")
		(at 53.773324 -162.481768 180)
		(property "Reference" "R412"
			(at 0 0 180)
			(layer "F.SilkS")
			(hide yes)
			(effects
				(font
					(size 1.27 1.27)
				)
			)
		)
		(property "Value" "1KR2F-3-GP"
			(at 0.064008 -3.993896 180)
			(unlocked yes)
			(layer "F.Fab")
			(hide yes)
			(effects
				(font
					(size 1.016 1.016)
					(thickness 0.1524)
				)
			)
		)
		(property "Device Type" "R402H16"
			(at 0.064008 -5.517896 180)
			(unlocked yes)
			(layer "F.Fab")
			(hide yes)
			(effects
				(font
					(size 1.016 1.016)
					(thickness 0.1524)
				)
			)
		)
		(duplicate_pad_numbers_are_jumpers no)
		(fp_line
			(start 0.508 -0.9398)
			(end -0.508 -0.9398)
			(stroke
				(width 0.1524)
				(type default)
			)
			(layer "F.SilkS")
		)
		(fp_line
			(start -0.508 -0.9398)
			(end -0.508 0.9398)
			(stroke
				(width 0.1524)
				(type default)
			)
			(layer "F.SilkS")
		)
		(fp_rect
			(start -0.508 0.9398)
			(end 0.508 -0.9398)
			(stroke
				(width 0)
				(type default)
			)
			(fill no)
			(layer "F.CrtYd")
		)
		(fp_rect
			(start -0.508 0.9398)
			(end 0.508 -0.9398)
			(stroke
				(width 0)
				(type default)
			)
			(fill no)
			(layer "F.Fab")
		)
		(pad "1" smd custom
			(at 0 -0.4445 180)
			(size 0.1397 0.1397)
			(layers "F.Cu" "F.Mask" "F.Paste")
			(net "ADC_P3V3")
			(options
				(clearance outline)
				(anchor circle)
			)
			(primitives
				(gr_poly
					(pts
						(arc
							(start -0.1778 -0.2794)
							(mid -0.249642 -0.249642)
							(end -0.2794 -0.1778)
						)
						(arc
							(start -0.2794 0.1778)
							(mid -0.249642 0.249642)
							(end -0.1778 0.2794)
						)
						(arc
							(start 0.1778 0.2794)
							(mid 0.249642 0.249642)
							(end 0.2794 0.1778)
						)
						(arc
							(start 0.2794 -0.1778)
							(mid 0.249642 -0.249642)
							(end 0.1778 -0.2794)
						)
					)
					(width 0)
					(fill yes)
				)
			)
		)
		(pad "2" smd custom
			(at 0 0.4445 180)
			(size 0.1397 0.1397)
			(layers "F.Cu" "F.Mask" "F.Paste")
			(net "GND")
			(options
				(clearance outline)
				(anchor circle)
			)
			(primitives
				(gr_poly
					(pts
						(arc
							(start -0.1778 -0.2794)
							(mid -0.249642 -0.249642)
							(end -0.2794 -0.1778)
						)
						(arc
							(start -0.2794 0.1778)
							(mid -0.249642 0.249642)
							(end -0.1778 0.2794)
						)
						(arc
							(start 0.1778 0.2794)
							(mid 0.249642 0.249642)
							(end 0.2794 0.1778)
						)
						(arc
							(start 0.2794 -0.1778)
							(mid 0.249642 -0.249642)
							(end 0.1778 -0.2794)
						)
					)
					(width 0)
					(fill yes)
				)
			)
		)
	)
	(footprint ""
		(layer "F.Cu")
		(at 111.139732 -14.262862 -90)
		(property "Reference" "R458"
			(at 0 0 270)
			(layer "F.SilkS")
			(hide yes)
			(effects
				(font
					(size 1.27 1.27)
				)
			)
		)
		(property "Value" "86K6R2F-GP"
			(at 0.064008 -3.993896 270)
			(unlocked yes)
			(layer "F.Fab")
			(hide yes)
			(effects
				(font
					(size 1.016 1.016)
					(thickness 0.1524)
				)
			)
		)
		(property "Device Type" "R402H16"
			(at 0.064008 -5.517896 270)
			(unlocked yes)
			(layer "F.Fab")
			(hide yes)
			(effects
				(font
					(size 1.016 1.016)
					(thickness 0.1524)
				)
			)
		)
		(duplicate_pad_numbers_are_jumpers no)
		(fp_line
			(start -0.508 -0.9398)
			(end -0.508 0.9398)
			(stroke
				(width 0.1524)
				(type default)
			)
			(layer "F.SilkS")
		)
		(fp_line
			(start 0.508 -0.9398)
			(end -0.508 -0.9398)
			(stroke
				(width 0.1524)
				(type default)
			)
			(layer "F.SilkS")
		)
		(fp_rect
			(start -0.508 0.9398)
			(end 0.508 -0.9398)
			(stroke
				(width 0)
				(type default)
			)
			(fill no)
			(layer "F.CrtYd")
		)
		(fp_rect
			(start -0.508 0.9398)
			(end 0.508 -0.9398)
			(stroke
				(width 0)
				(type default)
			)
			(fill no)
			(layer "F.Fab")
		)
		(pad "1" smd custom
			(at 0 -0.4445 270)
			(size 0.1397 0.1397)
			(layers "F.Cu" "F.Mask" "F.Paste")
			(net "MB0_PSET_R")
			(options
				(clearance outline)
				(anchor circle)
			)
			(primitives
				(gr_poly
					(pts
						(arc
							(start -0.1778 -0.2794)
							(mid -0.249642 -0.249642)
							(end -0.2794 -0.1778)
						)
						(arc
							(start -0.2794 0.1778)
							(mid -0.249642 0.249642)
							(end -0.1778 0.2794)
						)
						(arc
							(start 0.1778 0.2794)
							(mid 0.249642 0.249642)
							(end 0.2794 0.1778)
						)
						(arc
							(start 0.2794 -0.1778)
							(mid 0.249642 -0.249642)
							(end 0.1778 -0.2794)
						)
					)
					(width 0)
					(fill yes)
				)
			)
		)
		(pad "2" smd custom
			(at 0 0.4445 270)
			(size 0.1397 0.1397)
			(layers "F.Cu" "F.Mask" "F.Paste")
			(net "AGND_CURRENT_MON")
			(options
				(clearance outline)
				(anchor circle)
			)
			(primitives
				(gr_poly
					(pts
						(arc
							(start -0.1778 -0.2794)
							(mid -0.249642 -0.249642)
							(end -0.2794 -0.1778)
						)
						(arc
							(start -0.2794 0.1778)
							(mid -0.249642 0.249642)
							(end -0.1778 0.2794)
						)
						(arc
							(start 0.1778 0.2794)
							(mid 0.249642 0.249642)
							(end 0.2794 0.1778)
						)
						(arc
							(start 0.2794 -0.1778)
							(mid 0.249642 -0.249642)
							(end 0.1778 -0.2794)
						)
					)
					(width 0)
					(fill yes)
				)
			)
		)
	)
	(footprint ""
		(layer "F.Cu")
		(at 170.039538 -9.120378)
		(property "Reference" "C214"
			(at 0 0 0)
			(layer "F.SilkS")
			(hide yes)
			(effects
				(font
					(size 1.27 1.27)
				)
			)
		)
		(property "Value" "SCD1U16V2KX-3GP"
			(at 1.1811 -2.7051 0)
			(unlocked yes)
			(layer "F.Fab")
			(hide yes)
			(effects
				(font
					(size 1.016 1.016)
					(thickness 0.1524)
				)
			)
		)
		(property "Device Type" "C402H22"
			(at 1.1811 -4.2291 0)
			(unlocked yes)
			(layer "F.Fab")
			(hide yes)
			(effects
				(font
					(size 1.016 1.016)
					(thickness 0.1524)
				)
			)
		)
		(duplicate_pad_numbers_are_jumpers no)
		(fp_rect
			(start -0.4318 0.9525)
			(end 0.4318 -0.9525)
			(stroke
				(width 0)
				(type default)
			)
			(fill no)
			(layer "F.CrtYd")
		)
		(fp_rect
			(start -0.4318 0.9525)
			(end 0.4318 -0.9525)
			(stroke
				(width 0)
				(type default)
			)
			(fill no)
			(layer "F.Fab")
		)
		(pad "1" smd custom
			(at 0 -0.4445)
			(size 0.1524 0.1524)
			(layers "F.Cu" "F.Mask" "F.Paste")
			(net "P1V8_STBY")
			(options
				(clearance outline)
				(anchor circle)
			)
			(primitives
				(gr_poly
					(pts
						(arc
							(start 0.3048 -0.2032)
							(mid 0.275042 -0.275042)
							(end 0.2032 -0.3048)
						)
						(arc
							(start -0.2032 -0.3048)
							(mid -0.275042 -0.275042)
							(end -0.3048 -0.2032)
						)
						(arc
							(start -0.3048 0.2032)
							(mid -0.275042 0.275042)
							(end -0.2032 0.3048)
						)
						(arc
							(start 0.2032 0.3048)
							(mid 0.275042 0.275042)
							(end 0.3048 0.2032)
						)
					)
					(width 0)
					(fill yes)
				)
			)
		)
		(pad "2" smd custom
			(at 0 0.4445)
			(size 0.1524 0.1524)
			(layers "F.Cu" "F.Mask" "F.Paste")
			(net "GND")
			(options
				(clearance outline)
				(anchor circle)
			)
			(primitives
				(gr_poly
					(pts
						(arc
							(start 0.3048 -0.2032)
							(mid 0.275042 -0.275042)
							(end 0.2032 -0.3048)
						)
						(arc
							(start -0.2032 -0.3048)
							(mid -0.275042 -0.275042)
							(end -0.3048 -0.2032)
						)
						(arc
							(start -0.3048 0.2032)
							(mid -0.275042 0.275042)
							(end -0.2032 0.3048)
						)
						(arc
							(start 0.2032 0.3048)
							(mid 0.275042 0.275042)
							(end 0.3048 0.2032)
						)
					)
					(width 0)
					(fill yes)
				)
			)
		)
	)
	(footprint ""
		(layer "F.Cu")
		(at 124.9426 -8.636 90)
		(property "Reference" "R435"
			(at 0 0 90)
			(layer "F.SilkS")
			(hide yes)
			(effects
				(font
					(size 1.27 1.27)
				)
			)
		)
		(property "Value" "26K1R2F-2-GP"
			(at 0.064008 -3.993896 90)
			(unlocked yes)
			(layer "F.Fab")
			(hide yes)
			(effects
				(font
					(size 1.016 1.016)
					(thickness 0.1524)
				)
			)
		)
		(property "Device Type" "R402H16"
			(at 0.064008 -5.517896 90)
			(unlocked yes)
			(layer "F.Fab")
			(hide yes)
			(effects
				(font
					(size 1.016 1.016)
					(thickness 0.1524)
				)
			)
		)
		(duplicate_pad_numbers_are_jumpers no)
		(fp_line
			(start 0.508 -0.9398)
			(end -0.508 -0.9398)
			(stroke
				(width 0.1524)
				(type default)
			)
			(layer "F.SilkS")
		)
		(fp_line
			(start -0.508 -0.9398)
			(end -0.508 0.9398)
			(stroke
				(width 0.1524)
				(type default)
			)
			(layer "F.SilkS")
		)
		(fp_rect
			(start -0.508 0.9398)
			(end 0.508 -0.9398)
			(stroke
				(width 0)
				(type default)
			)
			(fill no)
			(layer "F.CrtYd")
		)
		(fp_rect
			(start -0.508 0.9398)
			(end 0.508 -0.9398)
			(stroke
				(width 0)
				(type default)
			)
			(fill no)
			(layer "F.Fab")
		)
		(pad "1" smd custom
			(at 0 -0.4445 90)
			(size 0.1397 0.1397)
			(layers "F.Cu" "F.Mask" "F.Paste")
			(net "P12V_IOM_PGOOD")
			(options
				(clearance outline)
				(anchor circle)
			)
			(primitives
				(gr_poly
					(pts
						(arc
							(start -0.1778 -0.2794)
							(mid -0.249642 -0.249642)
							(end -0.2794 -0.1778)
						)
						(arc
							(start -0.2794 0.1778)
							(mid -0.249642 0.249642)
							(end -0.1778 0.2794)
						)
						(arc
							(start 0.1778 0.2794)
							(mid 0.249642 0.249642)
							(end 0.2794 0.1778)
						)
						(arc
							(start 0.2794 -0.1778)
							(mid 0.249642 -0.249642)
							(end 0.1778 -0.2794)
						)
					)
					(width 0)
					(fill yes)
				)
			)
		)
		(pad "2" smd custom
			(at 0 0.4445 90)
			(size 0.1397 0.1397)
			(layers "F.Cu" "F.Mask" "F.Paste")
			(net "GND")
			(options
				(clearance outline)
				(anchor circle)
			)
			(primitives
				(gr_poly
					(pts
						(arc
							(start -0.1778 -0.2794)
							(mid -0.249642 -0.249642)
							(end -0.2794 -0.1778)
						)
						(arc
							(start -0.2794 0.1778)
							(mid -0.249642 0.249642)
							(end -0.1778 0.2794)
						)
						(arc
							(start 0.1778 0.2794)
							(mid 0.249642 0.249642)
							(end 0.2794 0.1778)
						)
						(arc
							(start 0.2794 -0.1778)
							(mid 0.249642 -0.249642)
							(end 0.1778 -0.2794)
						)
					)
					(width 0)
					(fill yes)
				)
			)
		)
	)
	(footprint ""
		(layer "F.Cu")
		(at 57.3786 -158.8516)
		(property "Reference" "R390"
			(at 0 0 0)
			(layer "F.SilkS")
			(hide yes)
			(effects
				(font
					(size 1.27 1.27)
				)
			)
		)
		(property "Value" "4K7R2F-GP"
			(at 0.064008 -3.993896 0)
			(unlocked yes)
			(layer "F.Fab")
			(hide yes)
			(effects
				(font
					(size 1.016 1.016)
					(thickness 0.1524)
				)
			)
		)
		(property "Device Type" "R402H16"
			(at 0.064008 -5.517896 0)
			(unlocked yes)
			(layer "F.Fab")
			(hide yes)
			(effects
				(font
					(size 1.016 1.016)
					(thickness 0.1524)
				)
			)
		)
		(duplicate_pad_numbers_are_jumpers no)
		(fp_line
			(start -0.508 -0.9398)
			(end -0.508 0.9398)
			(stroke
				(width 0.1524)
				(type default)
			)
			(layer "F.SilkS")
		)
		(fp_line
			(start 0.508 -0.9398)
			(end -0.508 -0.9398)
			(stroke
				(width 0.1524)
				(type default)
			)
			(layer "F.SilkS")
		)
		(fp_rect
			(start -0.508 0.9398)
			(end 0.508 -0.9398)
			(stroke
				(width 0)
				(type default)
			)
			(fill no)
			(layer "F.CrtYd")
		)
		(fp_rect
			(start -0.508 0.9398)
			(end 0.508 -0.9398)
			(stroke
				(width 0)
				(type default)
			)
			(fill no)
			(layer "F.Fab")
		)
		(pad "1" smd custom
			(at 0 -0.4445)
			(size 0.1397 0.1397)
			(layers "F.Cu" "F.Mask" "F.Paste")
			(net "P3V3_STBY")
			(options
				(clearance outline)
				(anchor circle)
			)
			(primitives
				(gr_poly
					(pts
						(arc
							(start -0.1778 -0.2794)
							(mid -0.249642 -0.249642)
							(end -0.2794 -0.1778)
						)
						(arc
							(start -0.2794 0.1778)
							(mid -0.249642 0.249642)
							(end -0.1778 0.2794)
						)
						(arc
							(start 0.1778 0.2794)
							(mid 0.249642 0.249642)
							(end 0.2794 0.1778)
						)
						(arc
							(start 0.2794 -0.1778)
							(mid 0.249642 -0.249642)
							(end 0.1778 -0.2794)
						)
					)
					(width 0)
					(fill yes)
				)
			)
		)
		(pad "2" smd custom
			(at 0 0.4445)
			(size 0.1397 0.1397)
			(layers "F.Cu" "F.Mask" "F.Paste")
			(net "MAC2_TXCTL")
			(options
				(clearance outline)
				(anchor circle)
			)
			(primitives
				(gr_poly
					(pts
						(arc
							(start -0.1778 -0.2794)
							(mid -0.249642 -0.249642)
							(end -0.2794 -0.1778)
						)
						(arc
							(start -0.2794 0.1778)
							(mid -0.249642 0.249642)
							(end -0.1778 0.2794)
						)
						(arc
							(start 0.1778 0.2794)
							(mid 0.249642 0.249642)
							(end 0.2794 0.1778)
						)
						(arc
							(start 0.2794 -0.1778)
							(mid 0.249642 -0.249642)
							(end 0.1778 -0.2794)
						)
					)
					(width 0)
					(fill yes)
				)
			)
		)
	)
	(footprint ""
		(layer "F.Cu")
		(at 63.7032 -172.1104 180)
		(property "Reference" "R71"
			(at 0 0 180)
			(layer "F.SilkS")
			(hide yes)
			(effects
				(font
					(size 1.27 1.27)
				)
			)
		)
		(property "Value" "4K75R2F-1-GP"
			(at 0.064008 -3.993896 180)
			(unlocked yes)
			(layer "F.Fab")
			(hide yes)
			(effects
				(font
					(size 1.016 1.016)
					(thickness 0.1524)
				)
			)
		)
		(property "Device Type" "R402H16"
			(at 0.064008 -5.517896 180)
			(unlocked yes)
			(layer "F.Fab")
			(hide yes)
			(effects
				(font
					(size 1.016 1.016)
					(thickness 0.1524)
				)
			)
		)
		(duplicate_pad_numbers_are_jumpers no)
		(fp_line
			(start 0.508 -0.9398)
			(end -0.508 -0.9398)
			(stroke
				(width 0.1524)
				(type default)
			)
			(layer "F.SilkS")
		)
		(fp_line
			(start -0.508 -0.9398)
			(end -0.508 0.9398)
			(stroke
				(width 0.1524)
				(type default)
			)
			(layer "F.SilkS")
		)
		(fp_rect
			(start -0.508 0.9398)
			(end 0.508 -0.9398)
			(stroke
				(width 0)
				(type default)
			)
			(fill no)
			(layer "F.CrtYd")
		)
		(fp_rect
			(start -0.508 0.9398)
			(end 0.508 -0.9398)
			(stroke
				(width 0)
				(type default)
			)
			(fill no)
			(layer "F.Fab")
		)
		(pad "1" smd custom
			(at 0 -0.4445 180)
			(size 0.1397 0.1397)
			(layers "F.Cu" "F.Mask" "F.Paste")
			(net "P3V3_STBY")
			(options
				(clearance outline)
				(anchor circle)
			)
			(primitives
				(gr_poly
					(pts
						(arc
							(start -0.1778 -0.2794)
							(mid -0.249642 -0.249642)
							(end -0.2794 -0.1778)
						)
						(arc
							(start -0.2794 0.1778)
							(mid -0.249642 0.249642)
							(end -0.1778 0.2794)
						)
						(arc
							(start 0.1778 0.2794)
							(mid 0.249642 0.249642)
							(end 0.2794 0.1778)
						)
						(arc
							(start 0.2794 -0.1778)
							(mid 0.249642 -0.249642)
							(end 0.1778 -0.2794)
						)
					)
					(width 0)
					(fill yes)
				)
			)
		)
		(pad "2" smd custom
			(at 0 0.4445 180)
			(size 0.1397 0.1397)
			(layers "F.Cu" "F.Mask" "F.Paste")
			(net "FM_TPM_PRSNT_RST_N_C")
			(options
				(clearance outline)
				(anchor circle)
			)
			(primitives
				(gr_poly
					(pts
						(arc
							(start -0.1778 -0.2794)
							(mid -0.249642 -0.249642)
							(end -0.2794 -0.1778)
						)
						(arc
							(start -0.2794 0.1778)
							(mid -0.249642 0.249642)
							(end -0.1778 0.2794)
						)
						(arc
							(start 0.1778 0.2794)
							(mid 0.249642 0.249642)
							(end 0.2794 0.1778)
						)
						(arc
							(start 0.2794 -0.1778)
							(mid 0.249642 -0.249642)
							(end 0.1778 -0.2794)
						)
					)
					(width 0)
					(fill yes)
				)
			)
		)
	)
	(footprint ""
		(layer "F.Cu")
		(at 183.1594 -111.0234 180)
		(property "Reference" "R552"
			(at 0 0 180)
			(layer "F.SilkS")
			(hide yes)
			(effects
				(font
					(size 1.27 1.27)
				)
			)
		)
		(property "Value" "4K7R2F-GP"
			(at 0.064008 -3.993896 180)
			(unlocked yes)
			(layer "F.Fab")
			(hide yes)
			(effects
				(font
					(size 1.016 1.016)
					(thickness 0.1524)
				)
			)
		)
		(property "Device Type" "R402H16"
			(at 0.064008 -5.517896 180)
			(unlocked yes)
			(layer "F.Fab")
			(hide yes)
			(effects
				(font
					(size 1.016 1.016)
					(thickness 0.1524)
				)
			)
		)
		(duplicate_pad_numbers_are_jumpers no)
		(fp_line
			(start 0.508 -0.9398)
			(end -0.508 -0.9398)
			(stroke
				(width 0.1524)
				(type default)
			)
			(layer "F.SilkS")
		)
		(fp_line
			(start -0.508 -0.9398)
			(end -0.508 0.9398)
			(stroke
				(width 0.1524)
				(type default)
			)
			(layer "F.SilkS")
		)
		(fp_rect
			(start -0.508 0.9398)
			(end 0.508 -0.9398)
			(stroke
				(width 0)
				(type default)
			)
			(fill no)
			(layer "F.CrtYd")
		)
		(fp_rect
			(start -0.508 0.9398)
			(end 0.508 -0.9398)
			(stroke
				(width 0)
				(type default)
			)
			(fill no)
			(layer "F.Fab")
		)
		(pad "1" smd custom
			(at 0 -0.4445 180)
			(size 0.1397 0.1397)
			(layers "F.Cu" "F.Mask" "F.Paste")
			(net "TEMP_1_A1")
			(options
				(clearance outline)
				(anchor circle)
			)
			(primitives
				(gr_poly
					(pts
						(arc
							(start -0.1778 -0.2794)
							(mid -0.249642 -0.249642)
							(end -0.2794 -0.1778)
						)
						(arc
							(start -0.2794 0.1778)
							(mid -0.249642 0.249642)
							(end -0.1778 0.2794)
						)
						(arc
							(start 0.1778 0.2794)
							(mid 0.249642 0.249642)
							(end 0.2794 0.1778)
						)
						(arc
							(start 0.2794 -0.1778)
							(mid 0.249642 -0.249642)
							(end 0.1778 -0.2794)
						)
					)
					(width 0)
					(fill yes)
				)
			)
		)
		(pad "2" smd custom
			(at 0 0.4445 180)
			(size 0.1397 0.1397)
			(layers "F.Cu" "F.Mask" "F.Paste")
			(net "GND")
			(options
				(clearance outline)
				(anchor circle)
			)
			(primitives
				(gr_poly
					(pts
						(arc
							(start -0.1778 -0.2794)
							(mid -0.249642 -0.249642)
							(end -0.2794 -0.1778)
						)
						(arc
							(start -0.2794 0.1778)
							(mid -0.249642 0.249642)
							(end -0.1778 0.2794)
						)
						(arc
							(start 0.1778 0.2794)
							(mid 0.249642 0.249642)
							(end 0.2794 0.1778)
						)
						(arc
							(start 0.2794 -0.1778)
							(mid 0.249642 -0.249642)
							(end 0.1778 -0.2794)
						)
					)
					(width 0)
					(fill yes)
				)
			)
		)
	)
	(footprint ""
		(layer "F.Cu")
		(at 203.503276 -105.12425)
		(property "Reference" "U85"
			(at 0 0 0)
			(layer "F.SilkS")
			(hide yes)
			(effects
				(font
					(size 1.27 1.27)
				)
			)
		)
		(property "Value" "TMP75AIDGKR-GP"
			(at -0.1143 -9.1948 0)
			(unlocked yes)
			(layer "F.Fab")
			(hide yes)
			(effects
				(font
					(size 1.016 1.016)
					(thickness 0.1524)
				)
			)
		)
		(property "Device Type" "MSOP8-1H44"
			(at -0.1143 -10.795 0)
			(unlocked yes)
			(layer "F.Fab")
			(hide yes)
			(effects
				(font
					(size 1.016 1.016)
					(thickness 0.1524)
				)
			)
		)
		(duplicate_pad_numbers_are_jumpers no)
		(fp_line
			(start -1.9558 -1.016)
			(end -1.9558 1.016)
			(stroke
				(width 0.1524)
				(type default)
			)
			(layer "F.SilkS")
		)
		(fp_line
			(start -1.9558 -0.5461)
			(end -1.4478 -0.0381)
			(stroke
				(width 0.1524)
				(type default)
			)
			(layer "F.SilkS")
		)
		(fp_line
			(start -1.9558 1.016)
			(end 1.0795 1.016)
			(stroke
				(width 0.1524)
				(type default)
			)
			(layer "F.SilkS")
		)
		(fp_line
			(start -1.778 1.0922)
			(end -1.778 3.048)
			(stroke
				(width 0.508)
				(type default)
			)
			(layer "F.SilkS")
		)
		(fp_line
			(start -1.4478 -0.0381)
			(end -1.9558 0.4699)
			(stroke
				(width 0.1524)
				(type default)
			)
			(layer "F.SilkS")
		)
		(fp_line
			(start 1.0795 -1.016)
			(end -1.9558 -1.016)
			(stroke
				(width 0.1524)
				(type default)
			)
			(layer "F.SilkS")
		)
		(fp_line
			(start 1.0795 1.016)
			(end 1.0795 -1.016)
			(stroke
				(width 0.1524)
				(type default)
			)
			(layer "F.SilkS")
		)
		(fp_poly
			(pts
				(xy -1.1557 -1.016) (xy -1.1557 1.016) (xy 1.1557 1.016) (xy 1.1557 -1.016)
			)
			(stroke
				(width 0)
				(type default)
			)
			(fill yes)
			(layer "F.SilkS")
		)
		(fp_rect
			(start -1.4986 2.4511)
			(end 1.4986 -2.4511)
			(stroke
				(width 0)
				(type default)
			)
			(fill no)
			(layer "F.CrtYd")
		)
		(fp_poly
			(pts
				(xy -2.032 3.302) (xy -2.032 -3.302) (xy 2.032 -3.302) (xy 2.032 -2.1209) (xy 1.4986 -2.1209) (xy 1.4986 -2.4511)
				(xy -1.4986 -2.4511) (xy -1.4986 2.4511) (xy 1.4986 2.4511) (xy 1.4986 -2.1082) (xy 2.032 -2.1082)
				(xy 2.032 3.302)
			)
			(stroke
				(width 0)
				(type default)
			)
			(fill no)
			(layer "F.CrtYd")
		)
		(fp_rect
			(start -2.032 3.302)
			(end 2.032 -3.302)
			(stroke
				(width 0)
				(type default)
			)
			(fill no)
			(layer "F.Fab")
		)
		(pad "1" smd rect
			(at -0.97536 2.05486)
			(size 0.3556 1.524)
			(layers "F.Cu" "F.Mask" "F.Paste")
			(net "TEMP_2_SDA")
		)
		(pad "2" smd rect
			(at -0.32512 2.05486)
			(size 0.3556 1.524)
			(layers "F.Cu" "F.Mask" "F.Paste")
			(net "TEMP_2_SCL")
		)
		(pad "3" smd rect
			(at 0.32512 2.05486)
			(size 0.3556 1.524)
			(layers "F.Cu" "F.Mask" "F.Paste")
			(net "TEMP_2_ALERT")
		)
		(pad "4" smd rect
			(at 0.97536 2.05486)
			(size 0.3556 1.524)
			(layers "F.Cu" "F.Mask" "F.Paste")
			(net "GND")
		)
		(pad "5" smd rect
			(at 0.97536 -2.05486)
			(size 0.3556 1.524)
			(layers "F.Cu" "F.Mask" "F.Paste")
			(net "TEMP_2_A2")
		)
		(pad "6" smd rect
			(at 0.32512 -2.05486)
			(size 0.3556 1.524)
			(layers "F.Cu" "F.Mask" "F.Paste")
			(net "TEMP_2_A1")
		)
		(pad "7" smd rect
			(at -0.32512 -2.05486)
			(size 0.3556 1.524)
			(layers "F.Cu" "F.Mask" "F.Paste")
			(net "TEMP_2_A0")
		)
		(pad "8" smd rect
			(at -0.97536 -2.05486)
			(size 0.3556 1.524)
			(layers "F.Cu" "F.Mask" "F.Paste")
			(net "P3V3_STBY")
		)
	)
	(footprint ""
		(layer "F.Cu")
		(at 155.499816 -153.999946)
		(property "Reference" ""
			(at 0 0 0)
			(layer "F.SilkS")
			(hide yes)
			(effects
				(font
					(size 1.27 1.27)
				)
			)
		)
		(property "Value" "*"
			(at -6.38175 0.19685 0)
			(unlocked yes)
			(layer "F.Fab")
			(hide yes)
			(effects
				(font
					(size 1.016 1.016)
					(thickness 0.1524)
				)
			)
		)
		(duplicate_pad_numbers_are_jumpers no)
		(fp_poly
			(pts
				(arc
					(start 5.0673 0)
					(mid -5.0673 0)
					(end 5.0673 0)
				)
			)
			(stroke
				(width 0)
				(type default)
			)
			(fill no)
			(layer "B.CrtYd")
		)
		(fp_poly
			(pts
				(arc
					(start 5.0673 0)
					(mid -5.0673 0)
					(end 5.0673 0)
				)
			)
			(stroke
				(width 0)
				(type default)
			)
			(fill no)
			(layer "F.CrtYd")
		)
		(fp_poly
			(pts
				(arc
					(start 5.0673 0)
					(mid -5.0673 0)
					(end 5.0673 0)
				)
			)
			(stroke
				(width 0)
				(type default)
			)
			(fill no)
			(layer "B.Fab")
		)
		(fp_poly
			(pts
				(arc
					(start 5.0673 0)
					(mid -5.0673 0)
					(end 5.0673 0)
				)
			)
			(stroke
				(width 0)
				(type default)
			)
			(fill no)
			(layer "F.Fab")
		)
		(pad "1" thru_hole circle
			(at 0 0)
			(size 9.525 9.525)
			(drill 3.5052)
			(layers "*.Cu" "*.Mask")
			(remove_unused_layers no)
			(net "Net_39")
			(clearance -2.5019)
			(thermal_gap 0.3048)
			(padstack
				(mode front_inner_back)
				(layer "Inner"
					(shape circle)
					(size 3.9116 3.9116)
					(clearance 0.3048)
				)
				(layer "B.Cu"
					(shape circle)
					(size 9.525 9.525)
					(clearance -2.5019)
				)
			)
		)
	)
	(footprint ""
		(layer "F.Cu")
		(at 98.676206 -140.77569 180)
		(property "Reference" "R423"
			(at 0 0 180)
			(layer "F.SilkS")
			(hide yes)
			(effects
				(font
					(size 1.27 1.27)
				)
			)
		)
		(property "Value" "4K7R2F-GP"
			(at 0.064008 -3.993896 180)
			(unlocked yes)
			(layer "F.Fab")
			(hide yes)
			(effects
				(font
					(size 1.016 1.016)
					(thickness 0.1524)
				)
			)
		)
		(property "Device Type" "R402H16"
			(at 0.064008 -5.517896 180)
			(unlocked yes)
			(layer "F.Fab")
			(hide yes)
			(effects
				(font
					(size 1.016 1.016)
					(thickness 0.1524)
				)
			)
		)
		(duplicate_pad_numbers_are_jumpers no)
		(fp_line
			(start 0.508 -0.9398)
			(end -0.508 -0.9398)
			(stroke
				(width 0.1524)
				(type default)
			)
			(layer "F.SilkS")
		)
		(fp_line
			(start -0.508 -0.9398)
			(end -0.508 0.9398)
			(stroke
				(width 0.1524)
				(type default)
			)
			(layer "F.SilkS")
		)
		(fp_rect
			(start -0.508 0.9398)
			(end 0.508 -0.9398)
			(stroke
				(width 0)
				(type default)
			)
			(fill no)
			(layer "F.CrtYd")
		)
		(fp_rect
			(start -0.508 0.9398)
			(end 0.508 -0.9398)
			(stroke
				(width 0)
				(type default)
			)
			(fill no)
			(layer "F.Fab")
		)
		(pad "1" smd custom
			(at 0 -0.4445 180)
			(size 0.1397 0.1397)
			(layers "F.Cu" "F.Mask" "F.Paste")
			(net "P3V3_STBY")
			(options
				(clearance outline)
				(anchor circle)
			)
			(primitives
				(gr_poly
					(pts
						(arc
							(start -0.1778 -0.2794)
							(mid -0.249642 -0.249642)
							(end -0.2794 -0.1778)
						)
						(arc
							(start -0.2794 0.1778)
							(mid -0.249642 0.249642)
							(end -0.1778 0.2794)
						)
						(arc
							(start 0.1778 0.2794)
							(mid 0.249642 0.249642)
							(end 0.2794 0.1778)
						)
						(arc
							(start 0.2794 -0.1778)
							(mid 0.249642 -0.249642)
							(end 0.1778 -0.2794)
						)
					)
					(width 0)
					(fill yes)
				)
			)
		)
		(pad "2" smd custom
			(at 0 0.4445 180)
			(size 0.1397 0.1397)
			(layers "F.Cu" "F.Mask" "F.Paste")
			(net "TCA9555_A0")
			(options
				(clearance outline)
				(anchor circle)
			)
			(primitives
				(gr_poly
					(pts
						(arc
							(start -0.1778 -0.2794)
							(mid -0.249642 -0.249642)
							(end -0.2794 -0.1778)
						)
						(arc
							(start -0.2794 0.1778)
							(mid -0.249642 0.249642)
							(end -0.1778 0.2794)
						)
						(arc
							(start 0.1778 0.2794)
							(mid 0.249642 0.249642)
							(end 0.2794 0.1778)
						)
						(arc
							(start 0.2794 -0.1778)
							(mid 0.249642 -0.249642)
							(end 0.1778 -0.2794)
						)
					)
					(width 0)
					(fill yes)
				)
			)
		)
	)
	(footprint ""
		(layer "F.Cu")
		(at 162.902138 -15.292578 180)
		(property "Reference" "C211"
			(at 0 0 180)
			(layer "F.SilkS")
			(hide yes)
			(effects
				(font
					(size 1.27 1.27)
				)
			)
		)
		(property "Value" "SCD1U50V3KX-GP"
			(at 0 -2.8194 180)
			(unlocked yes)
			(layer "F.Fab")
			(hide yes)
			(effects
				(font
					(size 1.016 1.016)
					(thickness 0.1524)
				)
			)
		)
		(property "Device Type" "C603H36"
			(at 0 -4.3434 180)
			(unlocked yes)
			(layer "F.Fab")
			(hide yes)
			(effects
				(font
					(size 1.016 1.016)
					(thickness 0.1524)
				)
			)
		)
		(duplicate_pad_numbers_are_jumpers no)
		(fp_line
			(start 0.508 0)
			(end -0.508 0)
			(stroke
				(width 0.2032)
				(type default)
			)
			(layer "F.SilkS")
		)
		(fp_rect
			(start -0.5842 1.3335)
			(end 0.5842 -1.3335)
			(stroke
				(width 0)
				(type default)
			)
			(fill no)
			(layer "F.CrtYd")
		)
		(fp_rect
			(start -0.5842 1.3335)
			(end 0.5842 -1.3335)
			(stroke
				(width 0)
				(type default)
			)
			(fill no)
			(layer "F.Fab")
		)
		(pad "1" smd custom
			(at 0 -0.762 180)
			(size 0.2159 0.2159)
			(layers "F.Cu" "F.Mask" "F.Paste")
			(net "P1V8_STBY")
			(options
				(clearance outline)
				(anchor circle)
			)
			(primitives
				(gr_poly
					(pts
						(arc
							(start -0.3302 -0.4318)
							(mid -0.402042 -0.402042)
							(end -0.4318 -0.3302)
						)
						(arc
							(start -0.4318 0.3302)
							(mid -0.402042 0.402042)
							(end -0.3302 0.4318)
						)
						(arc
							(start 0.3302 0.4318)
							(mid 0.402042 0.402042)
							(end 0.4318 0.3302)
						)
						(arc
							(start 0.4318 -0.3302)
							(mid 0.402042 -0.402042)
							(end 0.3302 -0.4318)
						)
					)
					(width 0)
					(fill yes)
				)
			)
		)
		(pad "2" smd custom
			(at 0 0.762 180)
			(size 0.2159 0.2159)
			(layers "F.Cu" "F.Mask" "F.Paste")
			(net "P1V8_STBY_VFB_R")
			(options
				(clearance outline)
				(anchor circle)
			)
			(primitives
				(gr_poly
					(pts
						(arc
							(start -0.3302 -0.4318)
							(mid -0.402042 -0.402042)
							(end -0.4318 -0.3302)
						)
						(arc
							(start -0.4318 0.3302)
							(mid -0.402042 0.402042)
							(end -0.3302 0.4318)
						)
						(arc
							(start 0.3302 0.4318)
							(mid 0.402042 0.402042)
							(end 0.4318 0.3302)
						)
						(arc
							(start 0.4318 -0.3302)
							(mid 0.402042 -0.402042)
							(end 0.3302 -0.4318)
						)
					)
					(width 0)
					(fill yes)
				)
			)
		)
	)
	(footprint ""
		(layer "F.Cu")
		(at 78.796896 -143.754602 -90)
		(property "Reference" "U105"
			(at 0 0 270)
			(layer "F.SilkS")
			(hide yes)
			(effects
				(font
					(size 1.27 1.27)
				)
			)
		)
		(property "Value" "SN74CBTLV3245APWR-GP"
			(at -0.889 -6.2738 270)
			(unlocked yes)
			(layer "F.Fab")
			(hide yes)
			(effects
				(font
					(size 1.016 1.016)
					(thickness 0.1524)
				)
			)
		)
		(property "Device Type" "TSOIC20H48"
			(at -0.9144 -7.8994 270)
			(unlocked yes)
			(layer "F.Fab")
			(hide yes)
			(effects
				(font
					(size 1.016 1.016)
					(thickness 0.1524)
				)
			)
		)
		(duplicate_pad_numbers_are_jumpers no)
		(fp_line
			(start -3.556 4.064)
			(end -3.556 1.778)
			(stroke
				(width 0.508)
				(type default)
			)
			(layer "F.SilkS")
		)
		(fp_line
			(start -3.556 1.397)
			(end -3.556 1.778)
			(stroke
				(width 0.2032)
				(type default)
			)
			(layer "F.SilkS")
		)
		(fp_line
			(start 3.175 1.397)
			(end -3.556 1.397)
			(stroke
				(width 0.2032)
				(type default)
			)
			(layer "F.SilkS")
		)
		(fp_line
			(start -2.667 0)
			(end -3.556 0.889)
			(stroke
				(width 0.2032)
				(type default)
			)
			(layer "F.SilkS")
		)
		(fp_line
			(start -2.667 0)
			(end -3.556 -0.889)
			(stroke
				(width 0.2032)
				(type default)
			)
			(layer "F.SilkS")
		)
		(fp_line
			(start -3.556 -1.397)
			(end -3.556 4.064)
			(stroke
				(width 0.2032)
				(type default)
			)
			(layer "F.SilkS")
		)
		(fp_line
			(start -3.556 -1.397)
			(end 3.175 -1.397)
			(stroke
				(width 0.2032)
				(type default)
			)
			(layer "F.SilkS")
		)
		(fp_line
			(start 3.175 -1.397)
			(end 3.175 1.397)
			(stroke
				(width 0.2032)
				(type default)
			)
			(layer "F.SilkS")
		)
		(fp_poly
			(pts
				(xy -3.25628 -1.8542) (xy 3.25628 -1.8542) (xy 3.25628 1.8542) (xy -3.25628 1.8542)
			)
			(stroke
				(width 0)
				(type default)
			)
			(fill yes)
			(layer "F.SilkS")
		)
		(fp_rect
			(start -3.556 3.81)
			(end 3.556 -3.81)
			(stroke
				(width 0)
				(type default)
			)
			(fill no)
			(layer "F.CrtYd")
		)
		(fp_poly
			(pts
				(xy -3.556 -3.81) (xy 3.556 -3.81) (xy 3.556 3.81) (xy -3.556 3.81)
			)
			(stroke
				(width 0)
				(type default)
			)
			(fill no)
			(layer "F.Fab")
		)
		(pad "1" smd rect
			(at -2.92608 2.8194 270)
			(size 0.3556 1.524)
			(layers "F.Cu" "F.Mask" "F.Paste")
			(net "Net_133")
		)
		(pad "2" smd rect
			(at -2.27584 2.8194 270)
			(size 0.3556 1.524)
			(layers "F.Cu" "F.Mask" "F.Paste")
			(net "I2C_EXP_LOC_SCL_OUT")
		)
		(pad "3" smd rect
			(at -1.6256 2.8194 270)
			(size 0.3556 1.524)
			(layers "F.Cu" "F.Mask" "F.Paste")
			(net "I2C_EXP_LOC_SDA_OUT")
		)
		(pad "4" smd rect
			(at -0.97536 2.8194 270)
			(size 0.3556 1.524)
			(layers "F.Cu" "F.Mask" "F.Paste")
			(net "I2C_EXP_RMT_SCL_OUT")
		)
		(pad "5" smd rect
			(at -0.32512 2.8194 270)
			(size 0.3556 1.524)
			(layers "F.Cu" "F.Mask" "F.Paste")
			(net "I2C_EXP_RMT_SDA_OUT")
		)
		(pad "6" smd rect
			(at 0.32512 2.8194 270)
			(size 0.3556 1.524)
			(layers "F.Cu" "F.Mask" "F.Paste")
			(net "I2C_SCC_SCL_OUT")
		)
		(pad "7" smd rect
			(at 0.97536 2.8194 270)
			(size 0.3556 1.524)
			(layers "F.Cu" "F.Mask" "F.Paste")
			(net "I2C_SCC_SDA_OUT")
		)
		(pad "8" smd rect
			(at 1.6256 2.8194 270)
			(size 0.3556 1.524)
			(layers "F.Cu" "F.Mask" "F.Paste")
			(net "I2C_DPB_SCL_OUT")
		)
		(pad "9" smd rect
			(at 2.27584 2.8194 270)
			(size 0.3556 1.524)
			(layers "F.Cu" "F.Mask" "F.Paste")
			(net "I2C_DPB_SDA_OUT")
		)
		(pad "10" smd rect
			(at 2.92608 2.8194 270)
			(size 0.3556 1.524)
			(layers "F.Cu" "F.Mask" "F.Paste")
			(net "GND")
		)
		(pad "11" smd rect
			(at 2.92608 -2.8194 270)
			(size 0.3556 1.524)
			(layers "F.Cu" "F.Mask" "F.Paste")
			(net "I2C_DPB_SDA_R")
		)
		(pad "12" smd rect
			(at 2.27584 -2.8194 270)
			(size 0.3556 1.524)
			(layers "F.Cu" "F.Mask" "F.Paste")
			(net "I2C_DPB_SCL_R")
		)
		(pad "13" smd rect
			(at 1.6256 -2.8194 270)
			(size 0.3556 1.524)
			(layers "F.Cu" "F.Mask" "F.Paste")
			(net "I2C_SCC_SDA_R")
		)
		(pad "14" smd rect
			(at 0.97536 -2.8194 270)
			(size 0.3556 1.524)
			(layers "F.Cu" "F.Mask" "F.Paste")
			(net "I2C_SCC_SCL_R")
		)
		(pad "15" smd rect
			(at 0.32512 -2.8194 270)
			(size 0.3556 1.524)
			(layers "F.Cu" "F.Mask" "F.Paste")
			(net "I2C_EXP_RMT_SDA_R")
		)
		(pad "16" smd rect
			(at -0.32512 -2.8194 270)
			(size 0.3556 1.524)
			(layers "F.Cu" "F.Mask" "F.Paste")
			(net "I2C_EXP_RMT_SCL_R")
		)
		(pad "17" smd rect
			(at -0.97536 -2.8194 270)
			(size 0.3556 1.524)
			(layers "F.Cu" "F.Mask" "F.Paste")
			(net "I2C_EXP_LOC_SDA_R")
		)
		(pad "18" smd rect
			(at -1.6256 -2.8194 270)
			(size 0.3556 1.524)
			(layers "F.Cu" "F.Mask" "F.Paste")
			(net "I2C_EXP_LOC_SCL_R")
		)
		(pad "19" smd rect
			(at -2.27584 -2.8194 270)
			(size 0.3556 1.524)
			(layers "F.Cu" "F.Mask" "F.Paste")
			(net "PWRGD_P3V3_STBY_N_R1")
		)
		(pad "20" smd rect
			(at -2.92608 -2.8194 270)
			(size 0.3556 1.524)
			(layers "F.Cu" "F.Mask" "F.Paste")
			(net "P3V3_STBY")
		)
	)
	(footprint ""
		(layer "F.Cu")
		(at 65.778126 -137.978134 180)
		(property "Reference" "R731"
			(at 0 0 180)
			(layer "F.SilkS")
			(hide yes)
			(effects
				(font
					(size 1.27 1.27)
				)
			)
		)
		(property "Value" "0R2J-2-GP"
			(at 0.064008 -3.993896 180)
			(unlocked yes)
			(layer "F.Fab")
			(hide yes)
			(effects
				(font
					(size 1.016 1.016)
					(thickness 0.1524)
				)
			)
		)
		(property "Device Type" "R402H16"
			(at 0.064008 -5.517896 180)
			(unlocked yes)
			(layer "F.Fab")
			(hide yes)
			(effects
				(font
					(size 1.016 1.016)
					(thickness 0.1524)
				)
			)
		)
		(duplicate_pad_numbers_are_jumpers no)
		(fp_line
			(start 0.508 -0.9398)
			(end -0.508 -0.9398)
			(stroke
				(width 0.1524)
				(type default)
			)
			(layer "F.SilkS")
		)
		(fp_line
			(start -0.508 -0.9398)
			(end -0.508 0.9398)
			(stroke
				(width 0.1524)
				(type default)
			)
			(layer "F.SilkS")
		)
		(fp_rect
			(start -0.508 0.9398)
			(end 0.508 -0.9398)
			(stroke
				(width 0)
				(type default)
			)
			(fill no)
			(layer "F.CrtYd")
		)
		(fp_rect
			(start -0.508 0.9398)
			(end 0.508 -0.9398)
			(stroke
				(width 0)
				(type default)
			)
			(fill no)
			(layer "F.Fab")
		)
		(pad "1" smd custom
			(at 0 -0.4445 180)
			(size 0.1397 0.1397)
			(layers "F.Cu" "F.Mask" "F.Paste")
			(net "COMP_SPARE_1")
			(options
				(clearance outline)
				(anchor circle)
			)
			(primitives
				(gr_poly
					(pts
						(arc
							(start -0.1778 -0.2794)
							(mid -0.249642 -0.249642)
							(end -0.2794 -0.1778)
						)
						(arc
							(start -0.2794 0.1778)
							(mid -0.249642 0.249642)
							(end -0.1778 0.2794)
						)
						(arc
							(start 0.1778 0.2794)
							(mid 0.249642 0.249642)
							(end 0.2794 0.1778)
						)
						(arc
							(start 0.2794 -0.1778)
							(mid 0.249642 -0.249642)
							(end 0.1778 -0.2794)
						)
					)
					(width 0)
					(fill yes)
				)
			)
		)
		(pad "2" smd custom
			(at 0 0.4445 180)
			(size 0.1397 0.1397)
			(layers "F.Cu" "F.Mask" "F.Paste")
			(net "COMP_SPARE_1_R")
			(options
				(clearance outline)
				(anchor circle)
			)
			(primitives
				(gr_poly
					(pts
						(arc
							(start -0.1778 -0.2794)
							(mid -0.249642 -0.249642)
							(end -0.2794 -0.1778)
						)
						(arc
							(start -0.2794 0.1778)
							(mid -0.249642 0.249642)
							(end -0.1778 0.2794)
						)
						(arc
							(start 0.1778 0.2794)
							(mid 0.249642 0.249642)
							(end 0.2794 0.1778)
						)
						(arc
							(start 0.2794 -0.1778)
							(mid 0.249642 -0.249642)
							(end 0.1778 -0.2794)
						)
					)
					(width 0)
					(fill yes)
				)
			)
		)
	)
	(footprint ""
		(layer "F.Cu")
		(at 112.646206 -11.201654)
		(property "Reference" "R453"
			(at 0 0 0)
			(layer "F.SilkS")
			(hide yes)
			(effects
				(font
					(size 1.27 1.27)
				)
			)
		)
		(property "Value" "100KR2J-4-GP"
			(at 0.064008 -3.993896 0)
			(unlocked yes)
			(layer "F.Fab")
			(hide yes)
			(effects
				(font
					(size 1.016 1.016)
					(thickness 0.1524)
				)
			)
		)
		(property "Device Type" "R402H15"
			(at 0.064008 -5.517896 0)
			(unlocked yes)
			(layer "F.Fab")
			(hide yes)
			(effects
				(font
					(size 1.016 1.016)
					(thickness 0.1524)
				)
			)
		)
		(duplicate_pad_numbers_are_jumpers no)
		(fp_line
			(start -0.508 -0.9398)
			(end -0.508 0.9398)
			(stroke
				(width 0.1524)
				(type default)
			)
			(layer "F.SilkS")
		)
		(fp_line
			(start 0.508 -0.9398)
			(end -0.508 -0.9398)
			(stroke
				(width 0.1524)
				(type default)
			)
			(layer "F.SilkS")
		)
		(fp_rect
			(start -0.508 0.9398)
			(end 0.508 -0.9398)
			(stroke
				(width 0)
				(type default)
			)
			(fill no)
			(layer "F.CrtYd")
		)
		(fp_rect
			(start -0.508 0.9398)
			(end 0.508 -0.9398)
			(stroke
				(width 0)
				(type default)
			)
			(fill no)
			(layer "F.Fab")
		)
		(pad "1" smd custom
			(at 0 -0.4445)
			(size 0.1397 0.1397)
			(layers "F.Cu" "F.Mask" "F.Paste")
			(net "MB0_VCAP_R")
			(options
				(clearance outline)
				(anchor circle)
			)
			(primitives
				(gr_poly
					(pts
						(arc
							(start -0.1778 -0.2794)
							(mid -0.249642 -0.249642)
							(end -0.2794 -0.1778)
						)
						(arc
							(start -0.2794 0.1778)
							(mid -0.249642 0.249642)
							(end -0.1778 0.2794)
						)
						(arc
							(start 0.1778 0.2794)
							(mid 0.249642 0.249642)
							(end 0.2794 0.1778)
						)
						(arc
							(start 0.2794 -0.1778)
							(mid 0.249642 -0.249642)
							(end 0.1778 -0.2794)
						)
					)
					(width 0)
					(fill yes)
				)
			)
		)
		(pad "2" smd custom
			(at 0 0.4445)
			(size 0.1397 0.1397)
			(layers "F.Cu" "F.Mask" "F.Paste")
			(net "MB0_ISET_R")
			(options
				(clearance outline)
				(anchor circle)
			)
			(primitives
				(gr_poly
					(pts
						(arc
							(start -0.1778 -0.2794)
							(mid -0.249642 -0.249642)
							(end -0.2794 -0.1778)
						)
						(arc
							(start -0.2794 0.1778)
							(mid -0.249642 0.249642)
							(end -0.1778 0.2794)
						)
						(arc
							(start 0.1778 0.2794)
							(mid 0.249642 0.249642)
							(end 0.2794 0.1778)
						)
						(arc
							(start 0.2794 -0.1778)
							(mid 0.249642 -0.249642)
							(end 0.1778 -0.2794)
						)
					)
					(width 0)
					(fill yes)
				)
			)
		)
	)
	(footprint ""
		(layer "F.Cu")
		(at 61.681868 -145.43659 -90)
		(property "Reference" "R162"
			(at 0 0 270)
			(layer "F.SilkS")
			(hide yes)
			(effects
				(font
					(size 1.27 1.27)
				)
			)
		)
		(property "Value" "0R2J-2-GP"
			(at 0.064008 -3.993896 270)
			(unlocked yes)
			(layer "F.Fab")
			(hide yes)
			(effects
				(font
					(size 1.016 1.016)
					(thickness 0.1524)
				)
			)
		)
		(property "Device Type" "R402H16"
			(at 0.064008 -5.517896 270)
			(unlocked yes)
			(layer "F.Fab")
			(hide yes)
			(effects
				(font
					(size 1.016 1.016)
					(thickness 0.1524)
				)
			)
		)
		(duplicate_pad_numbers_are_jumpers no)
		(fp_line
			(start -0.508 -0.9398)
			(end -0.508 0.9398)
			(stroke
				(width 0.1524)
				(type default)
			)
			(layer "F.SilkS")
		)
		(fp_line
			(start 0.508 -0.9398)
			(end -0.508 -0.9398)
			(stroke
				(width 0.1524)
				(type default)
			)
			(layer "F.SilkS")
		)
		(fp_rect
			(start -0.508 0.9398)
			(end 0.508 -0.9398)
			(stroke
				(width 0)
				(type default)
			)
			(fill no)
			(layer "F.CrtYd")
		)
		(fp_rect
			(start -0.508 0.9398)
			(end 0.508 -0.9398)
			(stroke
				(width 0)
				(type default)
			)
			(fill no)
			(layer "F.Fab")
		)
		(pad "1" smd custom
			(at 0 -0.4445 270)
			(size 0.1397 0.1397)
			(layers "F.Cu" "F.Mask" "F.Paste")
			(net "I2C_SCC_SDA_OUT")
			(options
				(clearance outline)
				(anchor circle)
			)
			(primitives
				(gr_poly
					(pts
						(arc
							(start -0.1778 -0.2794)
							(mid -0.249642 -0.249642)
							(end -0.2794 -0.1778)
						)
						(arc
							(start -0.2794 0.1778)
							(mid -0.249642 0.249642)
							(end -0.1778 0.2794)
						)
						(arc
							(start 0.1778 0.2794)
							(mid 0.249642 0.249642)
							(end 0.2794 0.1778)
						)
						(arc
							(start 0.2794 -0.1778)
							(mid 0.249642 -0.249642)
							(end 0.1778 -0.2794)
						)
					)
					(width 0)
					(fill yes)
				)
			)
		)
		(pad "2" smd custom
			(at 0 0.4445 270)
			(size 0.1397 0.1397)
			(layers "F.Cu" "F.Mask" "F.Paste")
			(net "BMC_SMB3_DAT")
			(options
				(clearance outline)
				(anchor circle)
			)
			(primitives
				(gr_poly
					(pts
						(arc
							(start -0.1778 -0.2794)
							(mid -0.249642 -0.249642)
							(end -0.2794 -0.1778)
						)
						(arc
							(start -0.2794 0.1778)
							(mid -0.249642 0.249642)
							(end -0.1778 0.2794)
						)
						(arc
							(start 0.1778 0.2794)
							(mid 0.249642 0.249642)
							(end 0.2794 0.1778)
						)
						(arc
							(start 0.2794 -0.1778)
							(mid 0.249642 -0.249642)
							(end 0.1778 -0.2794)
						)
					)
					(width 0)
					(fill yes)
				)
			)
		)
	)
	(footprint ""
		(layer "F.Cu")
		(at 23.777956 -128.105408 180)
		(property "Reference" "LED6"
			(at 0 0 180)
			(layer "F.SilkS")
			(hide yes)
			(effects
				(font
					(size 1.27 1.27)
				)
			)
		)
		(property "Value" "LED-YG-51-GP"
			(at -2.6924 -1.4224 180)
			(unlocked yes)
			(layer "F.Fab")
			(hide yes)
			(effects
				(font
					(size 1.016 1.016)
					(thickness 0.1524)
				)
			)
		)
		(property "Device Type" "LED1608AKH40"
			(at -2.6924 -2.9464 180)
			(unlocked yes)
			(layer "F.Fab")
			(hide yes)
			(effects
				(font
					(size 1.016 1.016)
					(thickness 0.1524)
				)
			)
		)
		(duplicate_pad_numbers_are_jumpers no)
		(fp_line
			(start 0.7493 1.651)
			(end 0.7493 1.1811)
			(stroke
				(width 0.3302)
				(type default)
			)
			(layer "F.SilkS")
		)
		(fp_line
			(start 0.6604 1.3716)
			(end -0.6604 1.3716)
			(stroke
				(width 0.1524)
				(type default)
			)
			(layer "F.SilkS")
		)
		(fp_line
			(start 0.6604 -1.3716)
			(end 0.6604 1.3716)
			(stroke
				(width 0.1524)
				(type default)
			)
			(layer "F.SilkS")
		)
		(fp_line
			(start -0.5969 1.5494)
			(end 0.5842 1.5494)
			(stroke
				(width 0.508)
				(type default)
			)
			(layer "F.SilkS")
		)
		(fp_line
			(start -0.6604 1.3716)
			(end -0.6604 -1.3716)
			(stroke
				(width 0.1524)
				(type default)
			)
			(layer "F.SilkS")
		)
		(fp_line
			(start -0.6604 -1.3716)
			(end 0.6604 -1.3716)
			(stroke
				(width 0.1524)
				(type default)
			)
			(layer "F.SilkS")
		)
		(fp_line
			(start -0.7493 1.651)
			(end -0.7493 1.1811)
			(stroke
				(width 0.3302)
				(type default)
			)
			(layer "F.SilkS")
		)
		(fp_rect
			(start -0.6223 1.3335)
			(end 0.6223 -1.3335)
			(stroke
				(width 0)
				(type default)
			)
			(fill no)
			(layer "F.CrtYd")
		)
		(fp_rect
			(start -0.6223 1.3335)
			(end 0.6223 -1.3335)
			(stroke
				(width 0)
				(type default)
			)
			(fill no)
			(layer "F.Fab")
		)
		(pad "A" smd custom
			(at 0 -0.762 180)
			(size 0.2159 0.2159)
			(layers "F.Cu" "F.Mask" "F.Paste")
			(net "BMC_HBLED_R")
			(options
				(clearance outline)
				(anchor circle)
			)
			(primitives
				(gr_poly
					(pts
						(arc
							(start -0.3302 -0.4318)
							(mid -0.402042 -0.402042)
							(end -0.4318 -0.3302)
						)
						(arc
							(start -0.4318 0.3302)
							(mid -0.402042 0.402042)
							(end -0.3302 0.4318)
						)
						(arc
							(start 0.3302 0.4318)
							(mid 0.402042 0.402042)
							(end 0.4318 0.3302)
						)
						(arc
							(start 0.4318 -0.3302)
							(mid 0.402042 -0.402042)
							(end 0.3302 -0.4318)
						)
					)
					(width 0)
					(fill yes)
				)
			)
		)
		(pad "K" smd custom
			(at 0 0.762 180)
			(size 0.2159 0.2159)
			(layers "F.Cu" "F.Mask" "F.Paste")
			(net "BMC_HBLED")
			(options
				(clearance outline)
				(anchor circle)
			)
			(primitives
				(gr_poly
					(pts
						(arc
							(start -0.3302 -0.4318)
							(mid -0.402042 -0.402042)
							(end -0.4318 -0.3302)
						)
						(arc
							(start -0.4318 0.3302)
							(mid -0.402042 0.402042)
							(end -0.3302 0.4318)
						)
						(arc
							(start 0.3302 0.4318)
							(mid 0.402042 0.402042)
							(end 0.4318 0.3302)
						)
						(arc
							(start 0.4318 -0.3302)
							(mid 0.402042 -0.402042)
							(end 0.3302 -0.4318)
						)
					)
					(width 0)
					(fill yes)
				)
			)
		)
	)
	(footprint ""
		(layer "F.Cu")
		(at 57.399936 -167.828722)
		(property "Reference" "R197"
			(at 0 0 0)
			(layer "F.SilkS")
			(hide yes)
			(effects
				(font
					(size 1.27 1.27)
				)
			)
		)
		(property "Value" "2K2R2F-GP"
			(at 0.064008 -3.993896 0)
			(unlocked yes)
			(layer "F.Fab")
			(hide yes)
			(effects
				(font
					(size 1.016 1.016)
					(thickness 0.1524)
				)
			)
		)
		(property "Device Type" "R402H16"
			(at 0.064008 -5.517896 0)
			(unlocked yes)
			(layer "F.Fab")
			(hide yes)
			(effects
				(font
					(size 1.016 1.016)
					(thickness 0.1524)
				)
			)
		)
		(duplicate_pad_numbers_are_jumpers no)
		(fp_line
			(start -0.508 -0.9398)
			(end -0.508 0.9398)
			(stroke
				(width 0.1524)
				(type default)
			)
			(layer "F.SilkS")
		)
		(fp_line
			(start 0.508 -0.9398)
			(end -0.508 -0.9398)
			(stroke
				(width 0.1524)
				(type default)
			)
			(layer "F.SilkS")
		)
		(fp_rect
			(start -0.508 0.9398)
			(end 0.508 -0.9398)
			(stroke
				(width 0)
				(type default)
			)
			(fill no)
			(layer "F.CrtYd")
		)
		(fp_rect
			(start -0.508 0.9398)
			(end 0.508 -0.9398)
			(stroke
				(width 0)
				(type default)
			)
			(fill no)
			(layer "F.Fab")
		)
		(pad "1" smd custom
			(at 0 -0.4445)
			(size 0.1397 0.1397)
			(layers "F.Cu" "F.Mask" "F.Paste")
			(net "I2C_TPM_SDA")
			(options
				(clearance outline)
				(anchor circle)
			)
			(primitives
				(gr_poly
					(pts
						(arc
							(start -0.1778 -0.2794)
							(mid -0.249642 -0.249642)
							(end -0.2794 -0.1778)
						)
						(arc
							(start -0.2794 0.1778)
							(mid -0.249642 0.249642)
							(end -0.1778 0.2794)
						)
						(arc
							(start 0.1778 0.2794)
							(mid 0.249642 0.249642)
							(end 0.2794 0.1778)
						)
						(arc
							(start 0.2794 -0.1778)
							(mid 0.249642 -0.249642)
							(end 0.1778 -0.2794)
						)
					)
					(width 0)
					(fill yes)
				)
			)
		)
		(pad "2" smd custom
			(at 0 0.4445)
			(size 0.1397 0.1397)
			(layers "F.Cu" "F.Mask" "F.Paste")
			(net "P3V3_STBY")
			(options
				(clearance outline)
				(anchor circle)
			)
			(primitives
				(gr_poly
					(pts
						(arc
							(start -0.1778 -0.2794)
							(mid -0.249642 -0.249642)
							(end -0.2794 -0.1778)
						)
						(arc
							(start -0.2794 0.1778)
							(mid -0.249642 0.249642)
							(end -0.1778 0.2794)
						)
						(arc
							(start 0.1778 0.2794)
							(mid 0.249642 0.249642)
							(end 0.2794 0.1778)
						)
						(arc
							(start 0.2794 -0.1778)
							(mid 0.249642 -0.249642)
							(end 0.1778 -0.2794)
						)
					)
					(width 0)
					(fill yes)
				)
			)
		)
	)
	(footprint ""
		(layer "F.Cu")
		(at 66.276474 -175.088296)
		(property "Reference" "U10"
			(at 0 0 0)
			(layer "F.SilkS")
			(hide yes)
			(effects
				(font
					(size 1.27 1.27)
				)
			)
		)
		(property "Value" "LMV331IDCKRG4-GP"
			(at -2.3368 -8.6868 0)
			(unlocked yes)
			(layer "F.Fab")
			(hide yes)
			(effects
				(font
					(size 1.016 1.016)
					(thickness 0.1524)
				)
			)
		)
		(property "Device Type" "SC70-5H44"
			(at -2.3114 -10.414 0)
			(unlocked yes)
			(layer "F.Fab")
			(hide yes)
			(effects
				(font
					(size 1.016 1.016)
					(thickness 0.1524)
				)
			)
		)
		(duplicate_pad_numbers_are_jumpers no)
		(fp_line
			(start -1.27 -1.7018)
			(end 1.27 -1.7018)
			(stroke
				(width 0.1524)
				(type default)
			)
			(layer "F.SilkS")
		)
		(fp_line
			(start -1.27 1.7018)
			(end -1.27 -1.7018)
			(stroke
				(width 0.1524)
				(type default)
			)
			(layer "F.SilkS")
		)
		(fp_line
			(start 0.6604 -1.8034)
			(end 1.3843 -1.8034)
			(stroke
				(width 0.3302)
				(type default)
			)
			(layer "F.SilkS")
		)
		(fp_line
			(start 1.27 -1.7018)
			(end 1.27 1.7018)
			(stroke
				(width 0.1524)
				(type default)
			)
			(layer "F.SilkS")
		)
		(fp_line
			(start 1.27 1.7018)
			(end -1.27 1.7018)
			(stroke
				(width 0.1524)
				(type default)
			)
			(layer "F.SilkS")
		)
		(fp_line
			(start 1.3843 -1.8034)
			(end 1.3843 -1.1176)
			(stroke
				(width 0.3302)
				(type default)
			)
			(layer "F.SilkS")
		)
		(fp_rect
			(start -1.524 1.9558)
			(end 1.524 -1.9558)
			(stroke
				(width 0)
				(type default)
			)
			(fill no)
			(layer "F.CrtYd")
		)
		(fp_poly
			(pts
				(xy -1.524 -1.9558) (xy 1.524 -1.9558) (xy 1.524 1.9558) (xy -1.524 1.9558)
			)
			(stroke
				(width 0)
				(type default)
			)
			(fill no)
			(layer "F.Fab")
		)
		(pad "1" smd rect
			(at 0.65024 -0.8255)
			(size 0.4064 1.2192)
			(layers "F.Cu" "F.Mask" "F.Paste")
			(net "FM_TPM_PRSNT_RST_N")
		)
		(pad "2" smd rect
			(at 0 -0.8255)
			(size 0.4064 1.2192)
			(layers "F.Cu" "F.Mask" "F.Paste")
			(net "GND")
		)
		(pad "3" smd rect
			(at -0.65024 -0.8255)
			(size 0.4064 1.2192)
			(layers "F.Cu" "F.Mask" "F.Paste")
			(net "VREF_2V2")
		)
		(pad "4" smd rect
			(at -0.65024 0.8255)
			(size 0.4064 1.2192)
			(layers "F.Cu" "F.Mask" "F.Paste")
			(net "FM_TPM_PRSNT_N")
		)
		(pad "5" smd rect
			(at 0.65024 0.8255)
			(size 0.4064 1.2192)
			(layers "F.Cu" "F.Mask" "F.Paste")
			(net "P5V_STBY")
		)
	)
	(footprint ""
		(layer "F.Cu")
		(at 23.368 -130.9878 180)
		(property "Reference" "R214"
			(at 0 0 180)
			(layer "F.SilkS")
			(hide yes)
			(effects
				(font
					(size 1.27 1.27)
				)
			)
		)
		(property "Value" "2K7R2F-GP"
			(at 0.064008 -3.993896 180)
			(unlocked yes)
			(layer "F.Fab")
			(hide yes)
			(effects
				(font
					(size 1.016 1.016)
					(thickness 0.1524)
				)
			)
		)
		(property "Device Type" "R402H16"
			(at 0.064008 -5.517896 180)
			(unlocked yes)
			(layer "F.Fab")
			(hide yes)
			(effects
				(font
					(size 1.016 1.016)
					(thickness 0.1524)
				)
			)
		)
		(duplicate_pad_numbers_are_jumpers no)
		(fp_line
			(start 0.508 -0.9398)
			(end -0.508 -0.9398)
			(stroke
				(width 0.1524)
				(type default)
			)
			(layer "F.SilkS")
		)
		(fp_line
			(start -0.508 -0.9398)
			(end -0.508 0.9398)
			(stroke
				(width 0.1524)
				(type default)
			)
			(layer "F.SilkS")
		)
		(fp_rect
			(start -0.508 0.9398)
			(end 0.508 -0.9398)
			(stroke
				(width 0)
				(type default)
			)
			(fill no)
			(layer "F.CrtYd")
		)
		(fp_rect
			(start -0.508 0.9398)
			(end 0.508 -0.9398)
			(stroke
				(width 0)
				(type default)
			)
			(fill no)
			(layer "F.Fab")
		)
		(pad "1" smd custom
			(at 0 -0.4445 180)
			(size 0.1397 0.1397)
			(layers "F.Cu" "F.Mask" "F.Paste")
			(net "DDR4_ALERT")
			(options
				(clearance outline)
				(anchor circle)
			)
			(primitives
				(gr_poly
					(pts
						(arc
							(start -0.1778 -0.2794)
							(mid -0.249642 -0.249642)
							(end -0.2794 -0.1778)
						)
						(arc
							(start -0.2794 0.1778)
							(mid -0.249642 0.249642)
							(end -0.1778 0.2794)
						)
						(arc
							(start 0.1778 0.2794)
							(mid 0.249642 0.249642)
							(end 0.2794 0.1778)
						)
						(arc
							(start 0.2794 -0.1778)
							(mid 0.249642 -0.249642)
							(end 0.1778 -0.2794)
						)
					)
					(width 0)
					(fill yes)
				)
			)
		)
		(pad "2" smd custom
			(at 0 0.4445 180)
			(size 0.1397 0.1397)
			(layers "F.Cu" "F.Mask" "F.Paste")
			(net "P1V2_STBY")
			(options
				(clearance outline)
				(anchor circle)
			)
			(primitives
				(gr_poly
					(pts
						(arc
							(start -0.1778 -0.2794)
							(mid -0.249642 -0.249642)
							(end -0.2794 -0.1778)
						)
						(arc
							(start -0.2794 0.1778)
							(mid -0.249642 0.249642)
							(end -0.1778 0.2794)
						)
						(arc
							(start 0.1778 0.2794)
							(mid 0.249642 0.249642)
							(end 0.2794 0.1778)
						)
						(arc
							(start 0.2794 -0.1778)
							(mid 0.249642 -0.249642)
							(end 0.1778 -0.2794)
						)
					)
					(width 0)
					(fill yes)
				)
			)
		)
	)
	(footprint ""
		(layer "F.Cu")
		(at 201.9046 -110.7694)
		(property "Reference" "R548"
			(at 0 0 0)
			(layer "F.SilkS")
			(hide yes)
			(effects
				(font
					(size 1.27 1.27)
				)
			)
		)
		(property "Value" "4K7R2F-GP"
			(at 0.064008 -3.993896 0)
			(unlocked yes)
			(layer "F.Fab")
			(hide yes)
			(effects
				(font
					(size 1.016 1.016)
					(thickness 0.1524)
				)
			)
		)
		(property "Device Type" "R402H16"
			(at 0.064008 -5.517896 0)
			(unlocked yes)
			(layer "F.Fab")
			(hide yes)
			(effects
				(font
					(size 1.016 1.016)
					(thickness 0.1524)
				)
			)
		)
		(duplicate_pad_numbers_are_jumpers no)
		(fp_line
			(start -0.508 -0.9398)
			(end -0.508 0.9398)
			(stroke
				(width 0.1524)
				(type default)
			)
			(layer "F.SilkS")
		)
		(fp_line
			(start 0.508 -0.9398)
			(end -0.508 -0.9398)
			(stroke
				(width 0.1524)
				(type default)
			)
			(layer "F.SilkS")
		)
		(fp_rect
			(start -0.508 0.9398)
			(end 0.508 -0.9398)
			(stroke
				(width 0)
				(type default)
			)
			(fill no)
			(layer "F.CrtYd")
		)
		(fp_rect
			(start -0.508 0.9398)
			(end 0.508 -0.9398)
			(stroke
				(width 0)
				(type default)
			)
			(fill no)
			(layer "F.Fab")
		)
		(pad "1" smd custom
			(at 0 -0.4445)
			(size 0.1397 0.1397)
			(layers "F.Cu" "F.Mask" "F.Paste")
			(net "P3V3_STBY")
			(options
				(clearance outline)
				(anchor circle)
			)
			(primitives
				(gr_poly
					(pts
						(arc
							(start -0.1778 -0.2794)
							(mid -0.249642 -0.249642)
							(end -0.2794 -0.1778)
						)
						(arc
							(start -0.2794 0.1778)
							(mid -0.249642 0.249642)
							(end -0.1778 0.2794)
						)
						(arc
							(start 0.1778 0.2794)
							(mid 0.249642 0.249642)
							(end 0.2794 0.1778)
						)
						(arc
							(start 0.2794 -0.1778)
							(mid 0.249642 -0.249642)
							(end 0.1778 -0.2794)
						)
					)
					(width 0)
					(fill yes)
				)
			)
		)
		(pad "2" smd custom
			(at 0 0.4445)
			(size 0.1397 0.1397)
			(layers "F.Cu" "F.Mask" "F.Paste")
			(net "TEMP_2_A0")
			(options
				(clearance outline)
				(anchor circle)
			)
			(primitives
				(gr_poly
					(pts
						(arc
							(start -0.1778 -0.2794)
							(mid -0.249642 -0.249642)
							(end -0.2794 -0.1778)
						)
						(arc
							(start -0.2794 0.1778)
							(mid -0.249642 0.249642)
							(end -0.1778 0.2794)
						)
						(arc
							(start 0.1778 0.2794)
							(mid 0.249642 0.249642)
							(end 0.2794 0.1778)
						)
						(arc
							(start 0.2794 -0.1778)
							(mid 0.249642 -0.249642)
							(end 0.1778 -0.2794)
						)
					)
					(width 0)
					(fill yes)
				)
			)
		)
	)
	(footprint ""
		(layer "F.Cu")
		(at 45.913802 -116.78412 -90)
		(property "Reference" "R86"
			(at 0 0 270)
			(layer "F.SilkS")
			(hide yes)
			(effects
				(font
					(size 1.27 1.27)
				)
			)
		)
		(property "Value" "2K2R2J-2-GP"
			(at 0.064008 -3.993896 270)
			(unlocked yes)
			(layer "F.Fab")
			(hide yes)
			(effects
				(font
					(size 1.016 1.016)
					(thickness 0.1524)
				)
			)
		)
		(property "Device Type" "R402H16"
			(at 0.064008 -5.517896 270)
			(unlocked yes)
			(layer "F.Fab")
			(hide yes)
			(effects
				(font
					(size 1.016 1.016)
					(thickness 0.1524)
				)
			)
		)
		(duplicate_pad_numbers_are_jumpers no)
		(fp_line
			(start -0.508 -0.9398)
			(end -0.508 0.9398)
			(stroke
				(width 0.1524)
				(type default)
			)
			(layer "F.SilkS")
		)
		(fp_line
			(start 0.508 -0.9398)
			(end -0.508 -0.9398)
			(stroke
				(width 0.1524)
				(type default)
			)
			(layer "F.SilkS")
		)
		(fp_rect
			(start -0.508 0.9398)
			(end 0.508 -0.9398)
			(stroke
				(width 0)
				(type default)
			)
			(fill no)
			(layer "F.CrtYd")
		)
		(fp_rect
			(start -0.508 0.9398)
			(end 0.508 -0.9398)
			(stroke
				(width 0)
				(type default)
			)
			(fill no)
			(layer "F.Fab")
		)
		(pad "1" smd custom
			(at 0 -0.4445 270)
			(size 0.1397 0.1397)
			(layers "F.Cu" "F.Mask" "F.Paste")
			(net "P3V3_STBY")
			(options
				(clearance outline)
				(anchor circle)
			)
			(primitives
				(gr_poly
					(pts
						(arc
							(start -0.1778 -0.2794)
							(mid -0.249642 -0.249642)
							(end -0.2794 -0.1778)
						)
						(arc
							(start -0.2794 0.1778)
							(mid -0.249642 0.249642)
							(end -0.1778 0.2794)
						)
						(arc
							(start 0.1778 0.2794)
							(mid 0.249642 0.249642)
							(end 0.2794 0.1778)
						)
						(arc
							(start 0.2794 -0.1778)
							(mid 0.249642 -0.249642)
							(end 0.1778 -0.2794)
						)
					)
					(width 0)
					(fill yes)
				)
			)
		)
		(pad "2" smd custom
			(at 0 0.4445 270)
			(size 0.1397 0.1397)
			(layers "F.Cu" "F.Mask" "F.Paste")
			(net "FLA0_SPI_HOLD_N")
			(options
				(clearance outline)
				(anchor circle)
			)
			(primitives
				(gr_poly
					(pts
						(arc
							(start -0.1778 -0.2794)
							(mid -0.249642 -0.249642)
							(end -0.2794 -0.1778)
						)
						(arc
							(start -0.2794 0.1778)
							(mid -0.249642 0.249642)
							(end -0.1778 0.2794)
						)
						(arc
							(start 0.1778 0.2794)
							(mid 0.249642 0.249642)
							(end 0.2794 0.1778)
						)
						(arc
							(start 0.2794 -0.1778)
							(mid 0.249642 -0.249642)
							(end 0.1778 -0.2794)
						)
					)
					(width 0)
					(fill yes)
				)
			)
		)
	)
	(footprint ""
		(layer "F.Cu")
		(at 19.144742 -129.077466 180)
		(property "Reference" "R215"
			(at 0 0 180)
			(layer "F.SilkS")
			(hide yes)
			(effects
				(font
					(size 1.27 1.27)
				)
			)
		)
		(property "Value" "120R2F-GP"
			(at 0.064008 -3.993896 180)
			(unlocked yes)
			(layer "F.Fab")
			(hide yes)
			(effects
				(font
					(size 1.016 1.016)
					(thickness 0.1524)
				)
			)
		)
		(property "Device Type" "R402H16"
			(at 0.064008 -5.517896 180)
			(unlocked yes)
			(layer "F.Fab")
			(hide yes)
			(effects
				(font
					(size 1.016 1.016)
					(thickness 0.1524)
				)
			)
		)
		(duplicate_pad_numbers_are_jumpers no)
		(fp_line
			(start 0.508 -0.9398)
			(end -0.508 -0.9398)
			(stroke
				(width 0.1524)
				(type default)
			)
			(layer "F.SilkS")
		)
		(fp_line
			(start -0.508 -0.9398)
			(end -0.508 0.9398)
			(stroke
				(width 0.1524)
				(type default)
			)
			(layer "F.SilkS")
		)
		(fp_rect
			(start -0.508 0.9398)
			(end 0.508 -0.9398)
			(stroke
				(width 0)
				(type default)
			)
			(fill no)
			(layer "F.CrtYd")
		)
		(fp_rect
			(start -0.508 0.9398)
			(end 0.508 -0.9398)
			(stroke
				(width 0)
				(type default)
			)
			(fill no)
			(layer "F.Fab")
		)
		(pad "1" smd custom
			(at 0 -0.4445 180)
			(size 0.1397 0.1397)
			(layers "F.Cu" "F.Mask" "F.Paste")
			(net "GND")
			(options
				(clearance outline)
				(anchor circle)
			)
			(primitives
				(gr_poly
					(pts
						(arc
							(start -0.1778 -0.2794)
							(mid -0.249642 -0.249642)
							(end -0.2794 -0.1778)
						)
						(arc
							(start -0.2794 0.1778)
							(mid -0.249642 0.249642)
							(end -0.1778 0.2794)
						)
						(arc
							(start 0.1778 0.2794)
							(mid 0.249642 0.249642)
							(end 0.2794 0.1778)
						)
						(arc
							(start 0.2794 -0.1778)
							(mid 0.249642 -0.249642)
							(end 0.1778 -0.2794)
						)
					)
					(width 0)
					(fill yes)
				)
			)
		)
		(pad "2" smd custom
			(at 0 0.4445 180)
			(size 0.1397 0.1397)
			(layers "F.Cu" "F.Mask" "F.Paste")
			(net "MEMCSN")
			(options
				(clearance outline)
				(anchor circle)
			)
			(primitives
				(gr_poly
					(pts
						(arc
							(start -0.1778 -0.2794)
							(mid -0.249642 -0.249642)
							(end -0.2794 -0.1778)
						)
						(arc
							(start -0.2794 0.1778)
							(mid -0.249642 0.249642)
							(end -0.1778 0.2794)
						)
						(arc
							(start 0.1778 0.2794)
							(mid 0.249642 0.249642)
							(end 0.2794 0.1778)
						)
						(arc
							(start 0.2794 -0.1778)
							(mid 0.249642 -0.249642)
							(end 0.1778 -0.2794)
						)
					)
					(width 0)
					(fill yes)
				)
			)
		)
	)
	(footprint ""
		(layer "F.Cu")
		(at 67.4878 -140.4874 90)
		(property "Reference" "R56"
			(at 0 0 90)
			(layer "F.SilkS")
			(hide yes)
			(effects
				(font
					(size 1.27 1.27)
				)
			)
		)
		(property "Value" "10KR2F-2-GP"
			(at 0.064008 -3.993896 90)
			(unlocked yes)
			(layer "F.Fab")
			(hide yes)
			(effects
				(font
					(size 1.016 1.016)
					(thickness 0.1524)
				)
			)
		)
		(property "Device Type" "R402H16"
			(at 0.064008 -5.517896 90)
			(unlocked yes)
			(layer "F.Fab")
			(hide yes)
			(effects
				(font
					(size 1.016 1.016)
					(thickness 0.1524)
				)
			)
		)
		(duplicate_pad_numbers_are_jumpers no)
		(fp_line
			(start 0.508 -0.9398)
			(end -0.508 -0.9398)
			(stroke
				(width 0.1524)
				(type default)
			)
			(layer "F.SilkS")
		)
		(fp_line
			(start -0.508 -0.9398)
			(end -0.508 0.9398)
			(stroke
				(width 0.1524)
				(type default)
			)
			(layer "F.SilkS")
		)
		(fp_rect
			(start -0.508 0.9398)
			(end 0.508 -0.9398)
			(stroke
				(width 0)
				(type default)
			)
			(fill no)
			(layer "F.CrtYd")
		)
		(fp_rect
			(start -0.508 0.9398)
			(end 0.508 -0.9398)
			(stroke
				(width 0)
				(type default)
			)
			(fill no)
			(layer "F.Fab")
		)
		(pad "1" smd custom
			(at 0 -0.4445 90)
			(size 0.1397 0.1397)
			(layers "F.Cu" "F.Mask" "F.Paste")
			(net "P3V3_STBY")
			(options
				(clearance outline)
				(anchor circle)
			)
			(primitives
				(gr_poly
					(pts
						(arc
							(start -0.1778 -0.2794)
							(mid -0.249642 -0.249642)
							(end -0.2794 -0.1778)
						)
						(arc
							(start -0.2794 0.1778)
							(mid -0.249642 0.249642)
							(end -0.1778 0.2794)
						)
						(arc
							(start 0.1778 0.2794)
							(mid 0.249642 0.249642)
							(end 0.2794 0.1778)
						)
						(arc
							(start 0.2794 -0.1778)
							(mid 0.249642 -0.249642)
							(end 0.1778 -0.2794)
						)
					)
					(width 0)
					(fill yes)
				)
			)
		)
		(pad "2" smd custom
			(at 0 0.4445 90)
			(size 0.1397 0.1397)
			(layers "F.Cu" "F.Mask" "F.Paste")
			(net "FP_RETBTN")
			(options
				(clearance outline)
				(anchor circle)
			)
			(primitives
				(gr_poly
					(pts
						(arc
							(start -0.1778 -0.2794)
							(mid -0.249642 -0.249642)
							(end -0.2794 -0.1778)
						)
						(arc
							(start -0.2794 0.1778)
							(mid -0.249642 0.249642)
							(end -0.1778 0.2794)
						)
						(arc
							(start 0.1778 0.2794)
							(mid 0.249642 0.249642)
							(end 0.2794 0.1778)
						)
						(arc
							(start 0.2794 -0.1778)
							(mid 0.249642 -0.249642)
							(end 0.1778 -0.2794)
						)
					)
					(width 0)
					(fill yes)
				)
			)
		)
	)
	(footprint ""
		(layer "F.Cu")
		(at 222.499936 -7.999984)
		(property "Reference" ""
			(at 0 0 0)
			(layer "F.SilkS")
			(hide yes)
			(effects
				(font
					(size 1.27 1.27)
				)
			)
		)
		(property "Value" "*"
			(at 6.2484 0.3429 0)
			(unlocked yes)
			(layer "F.Fab")
			(hide yes)
			(effects
				(font
					(size 1.016 1.016)
					(thickness 0.1524)
				)
			)
		)
		(duplicate_pad_numbers_are_jumpers no)
		(fp_poly
			(pts
				(arc
					(start 5.0673 0)
					(mid -5.0673 0)
					(end 5.0673 0)
				)
			)
			(stroke
				(width 0)
				(type default)
			)
			(fill no)
			(layer "B.CrtYd")
		)
		(fp_poly
			(pts
				(arc
					(start 5.0673 0)
					(mid -5.0673 0)
					(end 5.0673 0)
				)
			)
			(stroke
				(width 0)
				(type default)
			)
			(fill no)
			(layer "F.CrtYd")
		)
		(fp_poly
			(pts
				(arc
					(start 5.0673 0)
					(mid -5.0673 0)
					(end 5.0673 0)
				)
			)
			(stroke
				(width 0)
				(type default)
			)
			(fill no)
			(layer "B.Fab")
		)
		(fp_poly
			(pts
				(arc
					(start 5.0673 0)
					(mid -5.0673 0)
					(end 5.0673 0)
				)
			)
			(stroke
				(width 0)
				(type default)
			)
			(fill no)
			(layer "F.Fab")
		)
		(pad "1" thru_hole circle
			(at 0 0)
			(size 9.525 9.525)
			(drill 4.0132)
			(layers "*.Cu" "*.Mask")
			(remove_unused_layers no)
			(net "Net_84")
			(clearance -2.2479)
			(thermal_gap 0.3048)
			(padstack
				(mode front_inner_back)
				(layer "Inner"
					(shape circle)
					(size 4.4196 4.4196)
					(clearance 0.3048)
				)
				(layer "B.Cu"
					(shape circle)
					(size 9.525 9.525)
					(clearance -2.2479)
				)
			)
		)
	)
	(footprint ""
		(layer "F.Cu")
		(at 20.773136 -170.1038)
		(property "Reference" "C230"
			(at 0 0 0)
			(layer "F.SilkS")
			(hide yes)
			(effects
				(font
					(size 1.27 1.27)
				)
			)
		)
		(property "Value" "SCD1U16V2KX-3GP"
			(at 1.1811 -2.7051 0)
			(unlocked yes)
			(layer "F.Fab")
			(hide yes)
			(effects
				(font
					(size 1.016 1.016)
					(thickness 0.1524)
				)
			)
		)
		(property "Device Type" "C402H22"
			(at 1.1811 -4.2291 0)
			(unlocked yes)
			(layer "F.Fab")
			(hide yes)
			(effects
				(font
					(size 1.016 1.016)
					(thickness 0.1524)
				)
			)
		)
		(duplicate_pad_numbers_are_jumpers no)
		(fp_rect
			(start -0.4318 0.9525)
			(end 0.4318 -0.9525)
			(stroke
				(width 0)
				(type default)
			)
			(fill no)
			(layer "F.CrtYd")
		)
		(fp_rect
			(start -0.4318 0.9525)
			(end 0.4318 -0.9525)
			(stroke
				(width 0)
				(type default)
			)
			(fill no)
			(layer "F.Fab")
		)
		(pad "1" smd custom
			(at 0 -0.4445)
			(size 0.1524 0.1524)
			(layers "F.Cu" "F.Mask" "F.Paste")
			(net "P1V8_STBY")
			(options
				(clearance outline)
				(anchor circle)
			)
			(primitives
				(gr_poly
					(pts
						(arc
							(start 0.3048 -0.2032)
							(mid 0.275042 -0.275042)
							(end 0.2032 -0.3048)
						)
						(arc
							(start -0.2032 -0.3048)
							(mid -0.275042 -0.275042)
							(end -0.3048 -0.2032)
						)
						(arc
							(start -0.3048 0.2032)
							(mid -0.275042 0.275042)
							(end -0.2032 0.3048)
						)
						(arc
							(start 0.2032 0.3048)
							(mid 0.275042 0.275042)
							(end 0.3048 0.2032)
						)
					)
					(width 0)
					(fill yes)
				)
			)
		)
		(pad "2" smd custom
			(at 0 0.4445)
			(size 0.1524 0.1524)
			(layers "F.Cu" "F.Mask" "F.Paste")
			(net "GND")
			(options
				(clearance outline)
				(anchor circle)
			)
			(primitives
				(gr_poly
					(pts
						(arc
							(start 0.3048 -0.2032)
							(mid 0.275042 -0.275042)
							(end 0.2032 -0.3048)
						)
						(arc
							(start -0.2032 -0.3048)
							(mid -0.275042 -0.275042)
							(end -0.3048 -0.2032)
						)
						(arc
							(start -0.3048 0.2032)
							(mid -0.275042 0.275042)
							(end -0.2032 0.3048)
						)
						(arc
							(start 0.2032 0.3048)
							(mid 0.275042 0.275042)
							(end 0.3048 0.2032)
						)
					)
					(width 0)
					(fill yes)
				)
			)
		)
	)
	(footprint ""
		(layer "F.Cu")
		(at 60.9092 -121.3612 90)
		(property "Reference" "U29"
			(at 0 0 90)
			(layer "F.SilkS")
			(hide yes)
			(effects
				(font
					(size 1.27 1.27)
				)
			)
		)
		(property "Value" "MX25L25635FMI-10G-GP"
			(at 0 -14.6812 90)
			(unlocked yes)
			(layer "F.Fab")
			(hide yes)
			(effects
				(font
					(size 1.016 1.016)
					(thickness 0.1524)
				)
			)
		)
		(property "Device Type" "SOIC16-6H105"
			(at 0 -16.2052 90)
			(unlocked yes)
			(layer "F.Fab")
			(hide yes)
			(effects
				(font
					(size 1.016 1.016)
					(thickness 0.1524)
				)
			)
		)
		(duplicate_pad_numbers_are_jumpers no)
		(fp_line
			(start 4.7498 -3.2258)
			(end 4.7498 3.2258)
			(stroke
				(width 0.1524)
				(type default)
			)
			(layer "F.SilkS")
		)
		(fp_line
			(start -5.588 -3.2258)
			(end 4.7498 -3.2258)
			(stroke
				(width 0.1524)
				(type default)
			)
			(layer "F.SilkS")
		)
		(fp_line
			(start -5.588 -0.50038)
			(end -5.08762 0)
			(stroke
				(width 0.1524)
				(type default)
			)
			(layer "F.SilkS")
		)
		(fp_line
			(start -5.08762 0)
			(end -5.588 0.50038)
			(stroke
				(width 0.1524)
				(type default)
			)
			(layer "F.SilkS")
		)
		(fp_line
			(start 4.7498 3.2258)
			(end -5.588 3.2258)
			(stroke
				(width 0.1524)
				(type default)
			)
			(layer "F.SilkS")
		)
		(fp_line
			(start -5.4102 3.2258)
			(end -5.4102 5.7912)
			(stroke
				(width 0.508)
				(type default)
			)
			(layer "F.SilkS")
		)
		(fp_line
			(start -5.588 3.2258)
			(end -5.588 -3.2258)
			(stroke
				(width 0.1524)
				(type default)
			)
			(layer "F.SilkS")
		)
		(fp_poly
			(pts
				(xy -4.764786 -3.2258) (xy 4.7625 -3.2258) (xy 4.7625 3.2258) (xy -4.764786 3.2258)
			)
			(stroke
				(width 0)
				(type default)
			)
			(fill yes)
			(layer "F.SilkS")
		)
		(fp_poly
			(pts
				(xy -5.6642 6.0452) (xy 5.6642 6.0452) (xy 5.6642 -6.0452) (xy -5.6642 -6.0452)
			)
			(stroke
				(width 0)
				(type default)
			)
			(fill no)
			(layer "F.CrtYd")
		)
		(fp_poly
			(pts
				(xy -5.6642 -6.0452) (xy 5.6642 -6.0452) (xy 5.6642 6.0452) (xy -5.6642 6.0452)
			)
			(stroke
				(width 0)
				(type default)
			)
			(fill no)
			(layer "F.Fab")
		)
		(pad "1" smd rect
			(at -4.445 4.71805 90)
			(size 0.635 1.651)
			(layers "F.Cu" "F.Mask" "F.Paste")
			(net "PU_IBMC_BT_HOLD_N")
		)
		(pad "2" smd rect
			(at -3.175 4.71805 90)
			(size 0.635 1.651)
			(layers "F.Cu" "F.Mask" "F.Paste")
			(net "P3V3_STBY")
		)
		(pad "3" smd rect
			(at -1.905 4.71805 90)
			(size 0.635 1.651)
			(layers "F.Cu" "F.Mask" "F.Paste")
			(net "FLA1_SPI_RST")
		)
		(pad "4" smd rect
			(at -0.635 4.71805 90)
			(size 0.635 1.651)
			(layers "F.Cu" "F.Mask" "F.Paste")
			(net "Net_541")
		)
		(pad "5" smd rect
			(at 0.635 4.71805 90)
			(size 0.635 1.651)
			(layers "F.Cu" "F.Mask" "F.Paste")
			(net "Net_540")
		)
		(pad "6" smd rect
			(at 1.905 4.71805 90)
			(size 0.635 1.651)
			(layers "F.Cu" "F.Mask" "F.Paste")
			(net "Net_539")
		)
		(pad "7" smd rect
			(at 3.175 4.71805 90)
			(size 0.635 1.651)
			(layers "F.Cu" "F.Mask" "F.Paste")
			(net "FLA_CS_1_R")
		)
		(pad "8" smd rect
			(at 4.445 4.71805 90)
			(size 0.635 1.651)
			(layers "F.Cu" "F.Mask" "F.Paste")
			(net "BMC_SPI_MISO_R")
		)
		(pad "9" smd rect
			(at 4.445 -4.71805 90)
			(size 0.635 1.651)
			(layers "F.Cu" "F.Mask" "F.Paste")
			(net "FLA1_WP_N")
		)
		(pad "10" smd rect
			(at 3.175 -4.71805 90)
			(size 0.635 1.651)
			(layers "F.Cu" "F.Mask" "F.Paste")
			(net "GND")
		)
		(pad "11" smd rect
			(at 1.905 -4.71805 90)
			(size 0.635 1.651)
			(layers "F.Cu" "F.Mask" "F.Paste")
			(net "Net_538")
		)
		(pad "12" smd rect
			(at 0.635 -4.71805 90)
			(size 0.635 1.651)
			(layers "F.Cu" "F.Mask" "F.Paste")
			(net "Net_537")
		)
		(pad "13" smd rect
			(at -0.635 -4.71805 90)
			(size 0.635 1.651)
			(layers "F.Cu" "F.Mask" "F.Paste")
			(net "Net_536")
		)
		(pad "14" smd rect
			(at -1.905 -4.71805 90)
			(size 0.635 1.651)
			(layers "F.Cu" "F.Mask" "F.Paste")
			(net "Net_535")
		)
		(pad "15" smd rect
			(at -3.175 -4.71805 90)
			(size 0.635 1.651)
			(layers "F.Cu" "F.Mask" "F.Paste")
			(net "BMC_SPI_MOSI_R")
		)
		(pad "16" smd rect
			(at -4.445 -4.71805 90)
			(size 0.635 1.651)
			(layers "F.Cu" "F.Mask" "F.Paste")
			(net "BMC_SPI_CLK_R")
		)
	)
	(footprint ""
		(layer "F.Cu")
		(at 65.641474 -179.457096)
		(property "Reference" "R81"
			(at 0 0 0)
			(layer "F.SilkS")
			(hide yes)
			(effects
				(font
					(size 1.27 1.27)
				)
			)
		)
		(property "Value" "4K75R2F-1-GP"
			(at 0.064008 -3.993896 0)
			(unlocked yes)
			(layer "F.Fab")
			(hide yes)
			(effects
				(font
					(size 1.016 1.016)
					(thickness 0.1524)
				)
			)
		)
		(property "Device Type" "R402H16"
			(at 0.064008 -5.517896 0)
			(unlocked yes)
			(layer "F.Fab")
			(hide yes)
			(effects
				(font
					(size 1.016 1.016)
					(thickness 0.1524)
				)
			)
		)
		(duplicate_pad_numbers_are_jumpers no)
		(fp_line
			(start -0.508 -0.9398)
			(end -0.508 0.9398)
			(stroke
				(width 0.1524)
				(type default)
			)
			(layer "F.SilkS")
		)
		(fp_line
			(start 0.508 -0.9398)
			(end -0.508 -0.9398)
			(stroke
				(width 0.1524)
				(type default)
			)
			(layer "F.SilkS")
		)
		(fp_rect
			(start -0.508 0.9398)
			(end 0.508 -0.9398)
			(stroke
				(width 0)
				(type default)
			)
			(fill no)
			(layer "F.CrtYd")
		)
		(fp_rect
			(start -0.508 0.9398)
			(end 0.508 -0.9398)
			(stroke
				(width 0)
				(type default)
			)
			(fill no)
			(layer "F.Fab")
		)
		(pad "1" smd custom
			(at 0 -0.4445)
			(size 0.1397 0.1397)
			(layers "F.Cu" "F.Mask" "F.Paste")
			(net "P3V3_STBY")
			(options
				(clearance outline)
				(anchor circle)
			)
			(primitives
				(gr_poly
					(pts
						(arc
							(start -0.1778 -0.2794)
							(mid -0.249642 -0.249642)
							(end -0.2794 -0.1778)
						)
						(arc
							(start -0.2794 0.1778)
							(mid -0.249642 0.249642)
							(end -0.1778 0.2794)
						)
						(arc
							(start 0.1778 0.2794)
							(mid 0.249642 0.249642)
							(end 0.2794 0.1778)
						)
						(arc
							(start 0.2794 -0.1778)
							(mid 0.249642 -0.249642)
							(end 0.1778 -0.2794)
						)
					)
					(width 0)
					(fill yes)
				)
			)
		)
		(pad "2" smd custom
			(at 0 0.4445)
			(size 0.1397 0.1397)
			(layers "F.Cu" "F.Mask" "F.Paste")
			(net "VREF_2V2")
			(options
				(clearance outline)
				(anchor circle)
			)
			(primitives
				(gr_poly
					(pts
						(arc
							(start -0.1778 -0.2794)
							(mid -0.249642 -0.249642)
							(end -0.2794 -0.1778)
						)
						(arc
							(start -0.2794 0.1778)
							(mid -0.249642 0.249642)
							(end -0.1778 0.2794)
						)
						(arc
							(start 0.1778 0.2794)
							(mid 0.249642 0.249642)
							(end 0.2794 0.1778)
						)
						(arc
							(start 0.2794 -0.1778)
							(mid 0.249642 -0.249642)
							(end 0.1778 -0.2794)
						)
					)
					(width 0)
					(fill yes)
				)
			)
		)
	)
	(footprint ""
		(layer "F.Cu")
		(at 75.69581 -150.579074 90)
		(property "Reference" "R307"
			(at 0 0 90)
			(layer "F.SilkS")
			(hide yes)
			(effects
				(font
					(size 1.27 1.27)
				)
			)
		)
		(property "Value" "10KR2F-2-GP"
			(at 0.064008 -3.993896 90)
			(unlocked yes)
			(layer "F.Fab")
			(hide yes)
			(effects
				(font
					(size 1.016 1.016)
					(thickness 0.1524)
				)
			)
		)
		(property "Device Type" "R402H16"
			(at 0.064008 -5.517896 90)
			(unlocked yes)
			(layer "F.Fab")
			(hide yes)
			(effects
				(font
					(size 1.016 1.016)
					(thickness 0.1524)
				)
			)
		)
		(duplicate_pad_numbers_are_jumpers no)
		(fp_line
			(start 0.508 -0.9398)
			(end -0.508 -0.9398)
			(stroke
				(width 0.1524)
				(type default)
			)
			(layer "F.SilkS")
		)
		(fp_line
			(start -0.508 -0.9398)
			(end -0.508 0.9398)
			(stroke
				(width 0.1524)
				(type default)
			)
			(layer "F.SilkS")
		)
		(fp_rect
			(start -0.508 0.9398)
			(end 0.508 -0.9398)
			(stroke
				(width 0)
				(type default)
			)
			(fill no)
			(layer "F.CrtYd")
		)
		(fp_rect
			(start -0.508 0.9398)
			(end 0.508 -0.9398)
			(stroke
				(width 0)
				(type default)
			)
			(fill no)
			(layer "F.Fab")
		)
		(pad "1" smd custom
			(at 0 -0.4445 90)
			(size 0.1397 0.1397)
			(layers "F.Cu" "F.Mask" "F.Paste")
			(net "P3V3_STBY")
			(options
				(clearance outline)
				(anchor circle)
			)
			(primitives
				(gr_poly
					(pts
						(arc
							(start -0.1778 -0.2794)
							(mid -0.249642 -0.249642)
							(end -0.2794 -0.1778)
						)
						(arc
							(start -0.2794 0.1778)
							(mid -0.249642 0.249642)
							(end -0.1778 0.2794)
						)
						(arc
							(start 0.1778 0.2794)
							(mid 0.249642 0.249642)
							(end 0.2794 0.1778)
						)
						(arc
							(start 0.2794 -0.1778)
							(mid 0.249642 -0.249642)
							(end 0.1778 -0.2794)
						)
					)
					(width 0)
					(fill yes)
				)
			)
		)
		(pad "2" smd custom
			(at 0 0.4445 90)
			(size 0.1397 0.1397)
			(layers "F.Cu" "F.Mask" "F.Paste")
			(net "50M_CLK_OE")
			(options
				(clearance outline)
				(anchor circle)
			)
			(primitives
				(gr_poly
					(pts
						(arc
							(start -0.1778 -0.2794)
							(mid -0.249642 -0.249642)
							(end -0.2794 -0.1778)
						)
						(arc
							(start -0.2794 0.1778)
							(mid -0.249642 0.249642)
							(end -0.1778 0.2794)
						)
						(arc
							(start 0.1778 0.2794)
							(mid 0.249642 0.249642)
							(end 0.2794 0.1778)
						)
						(arc
							(start 0.2794 -0.1778)
							(mid 0.249642 -0.249642)
							(end 0.1778 -0.2794)
						)
					)
					(width 0)
					(fill yes)
				)
			)
		)
	)
	(footprint ""
		(layer "F.Cu")
		(at 229.682548 -18.16481 -90)
		(property "Reference" "G1"
			(at 0 0 270)
			(layer "F.SilkS")
			(hide yes)
			(effects
				(font
					(size 1.27 1.27)
				)
			)
		)
		(property "Value" "GAP-CLOSE-PWR-4-GP"
			(at -2.4638 -0.5461 270)
			(unlocked yes)
			(layer "F.Fab")
			(hide yes)
			(effects
				(font
					(size 1.016 1.016)
					(thickness 0.1524)
				)
			)
		)
		(property "Device Type" "GAP-CLOSE-PWR-4"
			(at -2.4638 -2.0701 270)
			(unlocked yes)
			(layer "F.Fab")
			(hide yes)
			(effects
				(font
					(size 1.016 1.016)
					(thickness 0.1524)
				)
			)
		)
		(duplicate_pad_numbers_are_jumpers no)
		(fp_rect
			(start -0.2794 0.254)
			(end 0.2794 -0.254)
			(stroke
				(width 0)
				(type default)
			)
			(fill no)
			(layer "F.CrtYd")
		)
		(fp_rect
			(start -0.2794 0.254)
			(end 0.2794 -0.254)
			(stroke
				(width 0)
				(type default)
			)
			(fill no)
			(layer "F.Fab")
		)
		(pad "1" smd rect
			(at -0.0635 0 270)
			(size 0.1778 0.254)
			(layers "F.Cu" "F.Mask" "F.Paste")
			(net "P5V_STBY")
		)
		(pad "2" smd rect
			(at 0.0635 0 270)
			(size 0.1778 0.254)
			(layers "F.Cu" "F.Mask" "F.Paste")
			(net "P5V_CC")
		)
	)
	(footprint ""
		(layer "F.Cu")
		(at 181.1528 -99.695)
		(property "Reference" "R556"
			(at 0 0 0)
			(layer "F.SilkS")
			(hide yes)
			(effects
				(font
					(size 1.27 1.27)
				)
			)
		)
		(property "Value" "0R2J-2-GP"
			(at 0.064008 -3.993896 0)
			(unlocked yes)
			(layer "F.Fab")
			(hide yes)
			(effects
				(font
					(size 1.016 1.016)
					(thickness 0.1524)
				)
			)
		)
		(property "Device Type" "R402H16"
			(at 0.064008 -5.517896 0)
			(unlocked yes)
			(layer "F.Fab")
			(hide yes)
			(effects
				(font
					(size 1.016 1.016)
					(thickness 0.1524)
				)
			)
		)
		(duplicate_pad_numbers_are_jumpers no)
		(fp_line
			(start -0.508 -0.9398)
			(end -0.508 0.9398)
			(stroke
				(width 0.1524)
				(type default)
			)
			(layer "F.SilkS")
		)
		(fp_line
			(start 0.508 -0.9398)
			(end -0.508 -0.9398)
			(stroke
				(width 0.1524)
				(type default)
			)
			(layer "F.SilkS")
		)
		(fp_rect
			(start -0.508 0.9398)
			(end 0.508 -0.9398)
			(stroke
				(width 0)
				(type default)
			)
			(fill no)
			(layer "F.CrtYd")
		)
		(fp_rect
			(start -0.508 0.9398)
			(end 0.508 -0.9398)
			(stroke
				(width 0)
				(type default)
			)
			(fill no)
			(layer "F.Fab")
		)
		(pad "1" smd custom
			(at 0 -0.4445)
			(size 0.1397 0.1397)
			(layers "F.Cu" "F.Mask" "F.Paste")
			(net "TEMP_1_SDA")
			(options
				(clearance outline)
				(anchor circle)
			)
			(primitives
				(gr_poly
					(pts
						(arc
							(start -0.1778 -0.2794)
							(mid -0.249642 -0.249642)
							(end -0.2794 -0.1778)
						)
						(arc
							(start -0.2794 0.1778)
							(mid -0.249642 0.249642)
							(end -0.1778 0.2794)
						)
						(arc
							(start 0.1778 0.2794)
							(mid 0.249642 0.249642)
							(end 0.2794 0.1778)
						)
						(arc
							(start 0.2794 -0.1778)
							(mid 0.249642 -0.249642)
							(end 0.1778 -0.2794)
						)
					)
					(width 0)
					(fill yes)
				)
			)
		)
		(pad "2" smd custom
			(at 0 0.4445)
			(size 0.1397 0.1397)
			(layers "F.Cu" "F.Mask" "F.Paste")
			(net "I2C_IOM_SDA")
			(options
				(clearance outline)
				(anchor circle)
			)
			(primitives
				(gr_poly
					(pts
						(arc
							(start -0.1778 -0.2794)
							(mid -0.249642 -0.249642)
							(end -0.2794 -0.1778)
						)
						(arc
							(start -0.2794 0.1778)
							(mid -0.249642 0.249642)
							(end -0.1778 0.2794)
						)
						(arc
							(start 0.1778 0.2794)
							(mid 0.249642 0.249642)
							(end 0.2794 0.1778)
						)
						(arc
							(start 0.2794 -0.1778)
							(mid 0.249642 -0.249642)
							(end 0.1778 -0.2794)
						)
					)
					(width 0)
					(fill yes)
				)
			)
		)
	)
	(footprint ""
		(layer "F.Cu")
		(at 36.213288 -161.399728)
		(property "Reference" "R300"
			(at 0 0 0)
			(layer "F.SilkS")
			(hide yes)
			(effects
				(font
					(size 1.27 1.27)
				)
			)
		)
		(property "Value" "4K7R2F-GP"
			(at 0.064008 -3.993896 0)
			(unlocked yes)
			(layer "F.Fab")
			(hide yes)
			(effects
				(font
					(size 1.016 1.016)
					(thickness 0.1524)
				)
			)
		)
		(property "Device Type" "R402H16"
			(at 0.064008 -5.517896 0)
			(unlocked yes)
			(layer "F.Fab")
			(hide yes)
			(effects
				(font
					(size 1.016 1.016)
					(thickness 0.1524)
				)
			)
		)
		(duplicate_pad_numbers_are_jumpers no)
		(fp_line
			(start -0.508 -0.9398)
			(end -0.508 0.9398)
			(stroke
				(width 0.1524)
				(type default)
			)
			(layer "F.SilkS")
		)
		(fp_line
			(start 0.508 -0.9398)
			(end -0.508 -0.9398)
			(stroke
				(width 0.1524)
				(type default)
			)
			(layer "F.SilkS")
		)
		(fp_rect
			(start -0.508 0.9398)
			(end 0.508 -0.9398)
			(stroke
				(width 0)
				(type default)
			)
			(fill no)
			(layer "F.CrtYd")
		)
		(fp_rect
			(start -0.508 0.9398)
			(end 0.508 -0.9398)
			(stroke
				(width 0)
				(type default)
			)
			(fill no)
			(layer "F.Fab")
		)
		(pad "1" smd custom
			(at 0 -0.4445)
			(size 0.1397 0.1397)
			(layers "F.Cu" "F.Mask" "F.Paste")
			(net "P3V3_STBY")
			(options
				(clearance outline)
				(anchor circle)
			)
			(primitives
				(gr_poly
					(pts
						(arc
							(start -0.1778 -0.2794)
							(mid -0.249642 -0.249642)
							(end -0.2794 -0.1778)
						)
						(arc
							(start -0.2794 0.1778)
							(mid -0.249642 0.249642)
							(end -0.1778 0.2794)
						)
						(arc
							(start 0.1778 0.2794)
							(mid 0.249642 0.249642)
							(end 0.2794 0.1778)
						)
						(arc
							(start 0.2794 -0.1778)
							(mid 0.249642 -0.249642)
							(end 0.1778 -0.2794)
						)
					)
					(width 0)
					(fill yes)
				)
			)
		)
		(pad "2" smd custom
			(at 0 0.4445)
			(size 0.1397 0.1397)
			(layers "F.Cu" "F.Mask" "F.Paste")
			(net "UART_COMP_OUT_TX")
			(options
				(clearance outline)
				(anchor circle)
			)
			(primitives
				(gr_poly
					(pts
						(arc
							(start -0.1778 -0.2794)
							(mid -0.249642 -0.249642)
							(end -0.2794 -0.1778)
						)
						(arc
							(start -0.2794 0.1778)
							(mid -0.249642 0.249642)
							(end -0.1778 0.2794)
						)
						(arc
							(start 0.1778 0.2794)
							(mid 0.249642 0.249642)
							(end 0.2794 0.1778)
						)
						(arc
							(start 0.2794 -0.1778)
							(mid 0.249642 -0.249642)
							(end 0.1778 -0.2794)
						)
					)
					(width 0)
					(fill yes)
				)
			)
		)
	)
	(footprint ""
		(layer "F.Cu")
		(at 183.8452 -6.0198 180)
		(property "Reference" "R695"
			(at 0 0 180)
			(layer "F.SilkS")
			(hide yes)
			(effects
				(font
					(size 1.27 1.27)
				)
			)
		)
		(property "Value" "1KR2F-3-GP"
			(at 0.064008 -3.993896 180)
			(unlocked yes)
			(layer "F.Fab")
			(hide yes)
			(effects
				(font
					(size 1.016 1.016)
					(thickness 0.1524)
				)
			)
		)
		(property "Device Type" "R402H16"
			(at 0.064008 -5.517896 180)
			(unlocked yes)
			(layer "F.Fab")
			(hide yes)
			(effects
				(font
					(size 1.016 1.016)
					(thickness 0.1524)
				)
			)
		)
		(duplicate_pad_numbers_are_jumpers no)
		(fp_line
			(start 0.508 -0.9398)
			(end -0.508 -0.9398)
			(stroke
				(width 0.1524)
				(type default)
			)
			(layer "F.SilkS")
		)
		(fp_line
			(start -0.508 -0.9398)
			(end -0.508 0.9398)
			(stroke
				(width 0.1524)
				(type default)
			)
			(layer "F.SilkS")
		)
		(fp_rect
			(start -0.508 0.9398)
			(end 0.508 -0.9398)
			(stroke
				(width 0)
				(type default)
			)
			(fill no)
			(layer "F.CrtYd")
		)
		(fp_rect
			(start -0.508 0.9398)
			(end 0.508 -0.9398)
			(stroke
				(width 0)
				(type default)
			)
			(fill no)
			(layer "F.Fab")
		)
		(pad "1" smd custom
			(at 0 -0.4445 180)
			(size 0.1397 0.1397)
			(layers "F.Cu" "F.Mask" "F.Paste")
			(net "P5V_STBY")
			(options
				(clearance outline)
				(anchor circle)
			)
			(primitives
				(gr_poly
					(pts
						(arc
							(start -0.1778 -0.2794)
							(mid -0.249642 -0.249642)
							(end -0.2794 -0.1778)
						)
						(arc
							(start -0.2794 0.1778)
							(mid -0.249642 0.249642)
							(end -0.1778 0.2794)
						)
						(arc
							(start 0.1778 0.2794)
							(mid 0.249642 0.249642)
							(end 0.2794 0.1778)
						)
						(arc
							(start 0.2794 -0.1778)
							(mid 0.249642 -0.249642)
							(end 0.1778 -0.2794)
						)
					)
					(width 0)
					(fill yes)
				)
			)
		)
		(pad "2" smd custom
			(at 0 0.4445 180)
			(size 0.1397 0.1397)
			(layers "F.Cu" "F.Mask" "F.Paste")
			(net "BMC_ML_PWR_BLUE_LED_L")
			(options
				(clearance outline)
				(anchor circle)
			)
			(primitives
				(gr_poly
					(pts
						(arc
							(start -0.1778 -0.2794)
							(mid -0.249642 -0.249642)
							(end -0.2794 -0.1778)
						)
						(arc
							(start -0.2794 0.1778)
							(mid -0.249642 0.249642)
							(end -0.1778 0.2794)
						)
						(arc
							(start 0.1778 0.2794)
							(mid 0.249642 0.249642)
							(end 0.2794 0.1778)
						)
						(arc
							(start 0.2794 -0.1778)
							(mid 0.249642 -0.249642)
							(end 0.1778 -0.2794)
						)
					)
					(width 0)
					(fill yes)
				)
			)
		)
	)
	(footprint ""
		(layer "F.Cu")
		(at 45.932598 -117.795294 90)
		(property "Reference" "C36"
			(at 0 0 90)
			(layer "F.SilkS")
			(hide yes)
			(effects
				(font
					(size 1.27 1.27)
				)
			)
		)
		(property "Value" "SCD1U16V2KX-3GP"
			(at 1.1811 -2.7051 90)
			(unlocked yes)
			(layer "F.Fab")
			(hide yes)
			(effects
				(font
					(size 1.016 1.016)
					(thickness 0.1524)
				)
			)
		)
		(property "Device Type" "C402H22"
			(at 1.1811 -4.2291 90)
			(unlocked yes)
			(layer "F.Fab")
			(hide yes)
			(effects
				(font
					(size 1.016 1.016)
					(thickness 0.1524)
				)
			)
		)
		(duplicate_pad_numbers_are_jumpers no)
		(fp_rect
			(start -0.4318 0.9525)
			(end 0.4318 -0.9525)
			(stroke
				(width 0)
				(type default)
			)
			(fill no)
			(layer "F.CrtYd")
		)
		(fp_rect
			(start -0.4318 0.9525)
			(end 0.4318 -0.9525)
			(stroke
				(width 0)
				(type default)
			)
			(fill no)
			(layer "F.Fab")
		)
		(pad "1" smd custom
			(at 0 -0.4445 90)
			(size 0.1524 0.1524)
			(layers "F.Cu" "F.Mask" "F.Paste")
			(net "P3V3_STBY")
			(options
				(clearance outline)
				(anchor circle)
			)
			(primitives
				(gr_poly
					(pts
						(arc
							(start 0.3048 -0.2032)
							(mid 0.275042 -0.275042)
							(end 0.2032 -0.3048)
						)
						(arc
							(start -0.2032 -0.3048)
							(mid -0.275042 -0.275042)
							(end -0.3048 -0.2032)
						)
						(arc
							(start -0.3048 0.2032)
							(mid -0.275042 0.275042)
							(end -0.2032 0.3048)
						)
						(arc
							(start 0.2032 0.3048)
							(mid 0.275042 0.275042)
							(end 0.3048 0.2032)
						)
					)
					(width 0)
					(fill yes)
				)
			)
		)
		(pad "2" smd custom
			(at 0 0.4445 90)
			(size 0.1524 0.1524)
			(layers "F.Cu" "F.Mask" "F.Paste")
			(net "GND")
			(options
				(clearance outline)
				(anchor circle)
			)
			(primitives
				(gr_poly
					(pts
						(arc
							(start 0.3048 -0.2032)
							(mid 0.275042 -0.275042)
							(end 0.2032 -0.3048)
						)
						(arc
							(start -0.2032 -0.3048)
							(mid -0.275042 -0.275042)
							(end -0.3048 -0.2032)
						)
						(arc
							(start -0.3048 0.2032)
							(mid -0.275042 0.275042)
							(end -0.2032 0.3048)
						)
						(arc
							(start 0.2032 0.3048)
							(mid 0.275042 0.275042)
							(end 0.3048 0.2032)
						)
					)
					(width 0)
					(fill yes)
				)
			)
		)
	)
	(footprint ""
		(layer "F.Cu")
		(at 45.97019 -158.5976)
		(property "Reference" "R172"
			(at 0 0 0)
			(layer "F.SilkS")
			(hide yes)
			(effects
				(font
					(size 1.27 1.27)
				)
			)
		)
		(property "Value" "0R2J-2-GP"
			(at 0.064008 -3.993896 0)
			(unlocked yes)
			(layer "F.Fab")
			(hide yes)
			(effects
				(font
					(size 1.016 1.016)
					(thickness 0.1524)
				)
			)
		)
		(property "Device Type" "R402H16"
			(at 0.064008 -5.517896 0)
			(unlocked yes)
			(layer "F.Fab")
			(hide yes)
			(effects
				(font
					(size 1.016 1.016)
					(thickness 0.1524)
				)
			)
		)
		(duplicate_pad_numbers_are_jumpers no)
		(fp_line
			(start -0.508 -0.9398)
			(end -0.508 0.9398)
			(stroke
				(width 0.1524)
				(type default)
			)
			(layer "F.SilkS")
		)
		(fp_line
			(start 0.508 -0.9398)
			(end -0.508 -0.9398)
			(stroke
				(width 0.1524)
				(type default)
			)
			(layer "F.SilkS")
		)
		(fp_rect
			(start -0.508 0.9398)
			(end 0.508 -0.9398)
			(stroke
				(width 0)
				(type default)
			)
			(fill no)
			(layer "F.CrtYd")
		)
		(fp_rect
			(start -0.508 0.9398)
			(end 0.508 -0.9398)
			(stroke
				(width 0)
				(type default)
			)
			(fill no)
			(layer "F.Fab")
		)
		(pad "1" smd custom
			(at 0 -0.4445)
			(size 0.1397 0.1397)
			(layers "F.Cu" "F.Mask" "F.Paste")
			(net "I2C_DPB_SDA_OUT")
			(options
				(clearance outline)
				(anchor circle)
			)
			(primitives
				(gr_poly
					(pts
						(arc
							(start -0.1778 -0.2794)
							(mid -0.249642 -0.249642)
							(end -0.2794 -0.1778)
						)
						(arc
							(start -0.2794 0.1778)
							(mid -0.249642 0.249642)
							(end -0.1778 0.2794)
						)
						(arc
							(start 0.1778 0.2794)
							(mid 0.249642 0.249642)
							(end 0.2794 0.1778)
						)
						(arc
							(start 0.2794 -0.1778)
							(mid 0.249642 -0.249642)
							(end 0.1778 -0.2794)
						)
					)
					(width 0)
					(fill yes)
				)
			)
		)
		(pad "2" smd custom
			(at 0 0.4445)
			(size 0.1397 0.1397)
			(layers "F.Cu" "F.Mask" "F.Paste")
			(net "BMC_SMB7_DAT")
			(options
				(clearance outline)
				(anchor circle)
			)
			(primitives
				(gr_poly
					(pts
						(arc
							(start -0.1778 -0.2794)
							(mid -0.249642 -0.249642)
							(end -0.2794 -0.1778)
						)
						(arc
							(start -0.2794 0.1778)
							(mid -0.249642 0.249642)
							(end -0.1778 0.2794)
						)
						(arc
							(start 0.1778 0.2794)
							(mid 0.249642 0.249642)
							(end 0.2794 0.1778)
						)
						(arc
							(start 0.2794 -0.1778)
							(mid 0.249642 -0.249642)
							(end 0.1778 -0.2794)
						)
					)
					(width 0)
					(fill yes)
				)
			)
		)
	)
	(footprint ""
		(layer "F.Cu")
		(at 99.3648 -149.6314 -90)
		(property "Reference" "R30"
			(at 0 0 270)
			(layer "F.SilkS")
			(hide yes)
			(effects
				(font
					(size 1.27 1.27)
				)
			)
		)
		(property "Value" "4K7R2F-GP"
			(at 0.064008 -3.993896 270)
			(unlocked yes)
			(layer "F.Fab")
			(hide yes)
			(effects
				(font
					(size 1.016 1.016)
					(thickness 0.1524)
				)
			)
		)
		(property "Device Type" "R402H16"
			(at 0.064008 -5.517896 270)
			(unlocked yes)
			(layer "F.Fab")
			(hide yes)
			(effects
				(font
					(size 1.016 1.016)
					(thickness 0.1524)
				)
			)
		)
		(duplicate_pad_numbers_are_jumpers no)
		(fp_line
			(start -0.508 -0.9398)
			(end -0.508 0.9398)
			(stroke
				(width 0.1524)
				(type default)
			)
			(layer "F.SilkS")
		)
		(fp_line
			(start 0.508 -0.9398)
			(end -0.508 -0.9398)
			(stroke
				(width 0.1524)
				(type default)
			)
			(layer "F.SilkS")
		)
		(fp_rect
			(start -0.508 0.9398)
			(end 0.508 -0.9398)
			(stroke
				(width 0)
				(type default)
			)
			(fill no)
			(layer "F.CrtYd")
		)
		(fp_rect
			(start -0.508 0.9398)
			(end 0.508 -0.9398)
			(stroke
				(width 0)
				(type default)
			)
			(fill no)
			(layer "F.Fab")
		)
		(pad "1" smd custom
			(at 0 -0.4445 270)
			(size 0.1397 0.1397)
			(layers "F.Cu" "F.Mask" "F.Paste")
			(net "P3V3_STBY")
			(options
				(clearance outline)
				(anchor circle)
			)
			(primitives
				(gr_poly
					(pts
						(arc
							(start -0.1778 -0.2794)
							(mid -0.249642 -0.249642)
							(end -0.2794 -0.1778)
						)
						(arc
							(start -0.2794 0.1778)
							(mid -0.249642 0.249642)
							(end -0.1778 0.2794)
						)
						(arc
							(start 0.1778 0.2794)
							(mid 0.249642 0.249642)
							(end 0.2794 0.1778)
						)
						(arc
							(start 0.2794 -0.1778)
							(mid 0.249642 -0.249642)
							(end 0.1778 -0.2794)
						)
					)
					(width 0)
					(fill yes)
				)
			)
		)
		(pad "2" smd custom
			(at 0 0.4445 270)
			(size 0.1397 0.1397)
			(layers "F.Cu" "F.Mask" "F.Paste")
			(net "USB_OCS_N3")
			(options
				(clearance outline)
				(anchor circle)
			)
			(primitives
				(gr_poly
					(pts
						(arc
							(start -0.1778 -0.2794)
							(mid -0.249642 -0.249642)
							(end -0.2794 -0.1778)
						)
						(arc
							(start -0.2794 0.1778)
							(mid -0.249642 0.249642)
							(end -0.1778 0.2794)
						)
						(arc
							(start 0.1778 0.2794)
							(mid 0.249642 0.249642)
							(end 0.2794 0.1778)
						)
						(arc
							(start 0.2794 -0.1778)
							(mid 0.249642 -0.249642)
							(end 0.1778 -0.2794)
						)
					)
					(width 0)
					(fill yes)
				)
			)
		)
	)
	(footprint ""
		(layer "F.Cu")
		(at 165.629082 -133.555994 -90)
		(property "Reference" "R810"
			(at 0 0 270)
			(layer "F.SilkS")
			(hide yes)
			(effects
				(font
					(size 1.27 1.27)
				)
			)
		)
		(property "Value" "0R2J-2-GP"
			(at 0.064008 -3.993896 270)
			(unlocked yes)
			(layer "F.Fab")
			(hide yes)
			(effects
				(font
					(size 1.016 1.016)
					(thickness 0.1524)
				)
			)
		)
		(property "Device Type" "R402H16"
			(at 0.064008 -5.517896 270)
			(unlocked yes)
			(layer "F.Fab")
			(hide yes)
			(effects
				(font
					(size 1.016 1.016)
					(thickness 0.1524)
				)
			)
		)
		(duplicate_pad_numbers_are_jumpers no)
		(fp_line
			(start -0.508 -0.9398)
			(end -0.508 0.9398)
			(stroke
				(width 0.1524)
				(type default)
			)
			(layer "F.SilkS")
		)
		(fp_line
			(start 0.508 -0.9398)
			(end -0.508 -0.9398)
			(stroke
				(width 0.1524)
				(type default)
			)
			(layer "F.SilkS")
		)
		(fp_rect
			(start -0.508 0.9398)
			(end 0.508 -0.9398)
			(stroke
				(width 0)
				(type default)
			)
			(fill no)
			(layer "F.CrtYd")
		)
		(fp_rect
			(start -0.508 0.9398)
			(end 0.508 -0.9398)
			(stroke
				(width 0)
				(type default)
			)
			(fill no)
			(layer "F.Fab")
		)
		(pad "1" smd custom
			(at 0 -0.4445 270)
			(size 0.1397 0.1397)
			(layers "F.Cu" "F.Mask" "F.Paste")
			(net "M2_2_PRESENT_N")
			(options
				(clearance outline)
				(anchor circle)
			)
			(primitives
				(gr_poly
					(pts
						(arc
							(start -0.1778 -0.2794)
							(mid -0.249642 -0.249642)
							(end -0.2794 -0.1778)
						)
						(arc
							(start -0.2794 0.1778)
							(mid -0.249642 0.249642)
							(end -0.1778 0.2794)
						)
						(arc
							(start 0.1778 0.2794)
							(mid 0.249642 0.249642)
							(end 0.2794 0.1778)
						)
						(arc
							(start 0.2794 -0.1778)
							(mid 0.249642 -0.249642)
							(end 0.1778 -0.2794)
						)
					)
					(width 0)
					(fill yes)
				)
			)
		)
		(pad "2" smd custom
			(at 0 0.4445 270)
			(size 0.1397 0.1397)
			(layers "F.Cu" "F.Mask" "F.Paste")
			(net "M2_2_PRESENT_N_R")
			(options
				(clearance outline)
				(anchor circle)
			)
			(primitives
				(gr_poly
					(pts
						(arc
							(start -0.1778 -0.2794)
							(mid -0.249642 -0.249642)
							(end -0.2794 -0.1778)
						)
						(arc
							(start -0.2794 0.1778)
							(mid -0.249642 0.249642)
							(end -0.1778 0.2794)
						)
						(arc
							(start 0.1778 0.2794)
							(mid 0.249642 0.249642)
							(end 0.2794 0.1778)
						)
						(arc
							(start 0.2794 -0.1778)
							(mid 0.249642 -0.249642)
							(end 0.1778 -0.2794)
						)
					)
					(width 0)
					(fill yes)
				)
			)
		)
	)
	(footprint ""
		(layer "F.Cu")
		(at 50.4698 -131.7244)
		(property "Reference" "R149"
			(at 0 0 0)
			(layer "F.SilkS")
			(hide yes)
			(effects
				(font
					(size 1.27 1.27)
				)
			)
		)
		(property "Value" "100KR2F-L1-GP"
			(at 0.064008 -3.993896 0)
			(unlocked yes)
			(layer "F.Fab")
			(hide yes)
			(effects
				(font
					(size 1.016 1.016)
					(thickness 0.1524)
				)
			)
		)
		(property "Device Type" "R402H16"
			(at 0.064008 -5.517896 0)
			(unlocked yes)
			(layer "F.Fab")
			(hide yes)
			(effects
				(font
					(size 1.016 1.016)
					(thickness 0.1524)
				)
			)
		)
		(duplicate_pad_numbers_are_jumpers no)
		(fp_line
			(start -0.508 -0.9398)
			(end -0.508 0.9398)
			(stroke
				(width 0.1524)
				(type default)
			)
			(layer "F.SilkS")
		)
		(fp_line
			(start 0.508 -0.9398)
			(end -0.508 -0.9398)
			(stroke
				(width 0.1524)
				(type default)
			)
			(layer "F.SilkS")
		)
		(fp_rect
			(start -0.508 0.9398)
			(end 0.508 -0.9398)
			(stroke
				(width 0)
				(type default)
			)
			(fill no)
			(layer "F.CrtYd")
		)
		(fp_rect
			(start -0.508 0.9398)
			(end 0.508 -0.9398)
			(stroke
				(width 0)
				(type default)
			)
			(fill no)
			(layer "F.Fab")
		)
		(pad "1" smd custom
			(at 0 -0.4445)
			(size 0.1397 0.1397)
			(layers "F.Cu" "F.Mask" "F.Paste")
			(net "LPCRST0_N")
			(options
				(clearance outline)
				(anchor circle)
			)
			(primitives
				(gr_poly
					(pts
						(arc
							(start -0.1778 -0.2794)
							(mid -0.249642 -0.249642)
							(end -0.2794 -0.1778)
						)
						(arc
							(start -0.2794 0.1778)
							(mid -0.249642 0.249642)
							(end -0.1778 0.2794)
						)
						(arc
							(start 0.1778 0.2794)
							(mid 0.249642 0.249642)
							(end 0.2794 0.1778)
						)
						(arc
							(start 0.2794 -0.1778)
							(mid 0.249642 -0.249642)
							(end 0.1778 -0.2794)
						)
					)
					(width 0)
					(fill yes)
				)
			)
		)
		(pad "2" smd custom
			(at 0 0.4445)
			(size 0.1397 0.1397)
			(layers "F.Cu" "F.Mask" "F.Paste")
			(net "GND")
			(options
				(clearance outline)
				(anchor circle)
			)
			(primitives
				(gr_poly
					(pts
						(arc
							(start -0.1778 -0.2794)
							(mid -0.249642 -0.249642)
							(end -0.2794 -0.1778)
						)
						(arc
							(start -0.2794 0.1778)
							(mid -0.249642 0.249642)
							(end -0.1778 0.2794)
						)
						(arc
							(start 0.1778 0.2794)
							(mid 0.249642 0.249642)
							(end 0.2794 0.1778)
						)
						(arc
							(start 0.2794 -0.1778)
							(mid 0.249642 -0.249642)
							(end 0.1778 -0.2794)
						)
					)
					(width 0)
					(fill yes)
				)
			)
		)
	)
	(footprint ""
		(layer "F.Cu")
		(at 215.330024 -87.56396 90)
		(property "Reference" "R836"
			(at 0 0 90)
			(layer "F.SilkS")
			(hide yes)
			(effects
				(font
					(size 1.27 1.27)
				)
			)
		)
		(property "Value" "2KR2F-3-GP"
			(at 0.064008 -3.993896 90)
			(unlocked yes)
			(layer "F.Fab")
			(hide yes)
			(effects
				(font
					(size 1.016 1.016)
					(thickness 0.1524)
				)
			)
		)
		(property "Device Type" "R402H16"
			(at 0.064008 -5.517896 90)
			(unlocked yes)
			(layer "F.Fab")
			(hide yes)
			(effects
				(font
					(size 1.016 1.016)
					(thickness 0.1524)
				)
			)
		)
		(duplicate_pad_numbers_are_jumpers no)
		(fp_line
			(start 0.508 -0.9398)
			(end -0.508 -0.9398)
			(stroke
				(width 0.1524)
				(type default)
			)
			(layer "F.SilkS")
		)
		(fp_line
			(start -0.508 -0.9398)
			(end -0.508 0.9398)
			(stroke
				(width 0.1524)
				(type default)
			)
			(layer "F.SilkS")
		)
		(fp_rect
			(start -0.508 0.9398)
			(end 0.508 -0.9398)
			(stroke
				(width 0)
				(type default)
			)
			(fill no)
			(layer "F.CrtYd")
		)
		(fp_rect
			(start -0.508 0.9398)
			(end 0.508 -0.9398)
			(stroke
				(width 0)
				(type default)
			)
			(fill no)
			(layer "F.Fab")
		)
		(pad "1" smd custom
			(at 0 -0.4445 90)
			(size 0.1397 0.1397)
			(layers "F.Cu" "F.Mask" "F.Paste")
			(net "P3V3_M2_LL_R")
			(options
				(clearance outline)
				(anchor circle)
			)
			(primitives
				(gr_poly
					(pts
						(arc
							(start -0.1778 -0.2794)
							(mid -0.249642 -0.249642)
							(end -0.2794 -0.1778)
						)
						(arc
							(start -0.2794 0.1778)
							(mid -0.249642 0.249642)
							(end -0.1778 0.2794)
						)
						(arc
							(start 0.1778 0.2794)
							(mid 0.249642 0.249642)
							(end 0.2794 0.1778)
						)
						(arc
							(start 0.2794 -0.1778)
							(mid 0.249642 -0.249642)
							(end 0.1778 -0.2794)
						)
					)
					(width 0)
					(fill yes)
				)
			)
		)
		(pad "2" smd custom
			(at 0 0.4445 90)
			(size 0.1397 0.1397)
			(layers "F.Cu" "F.Mask" "F.Paste")
			(net "P3V3_M2_LL")
			(options
				(clearance outline)
				(anchor circle)
			)
			(primitives
				(gr_poly
					(pts
						(arc
							(start -0.1778 -0.2794)
							(mid -0.249642 -0.249642)
							(end -0.2794 -0.1778)
						)
						(arc
							(start -0.2794 0.1778)
							(mid -0.249642 0.249642)
							(end -0.1778 0.2794)
						)
						(arc
							(start 0.1778 0.2794)
							(mid 0.249642 0.249642)
							(end 0.2794 0.1778)
						)
						(arc
							(start 0.2794 -0.1778)
							(mid 0.249642 -0.249642)
							(end 0.1778 -0.2794)
						)
					)
					(width 0)
					(fill yes)
				)
			)
		)
	)
	(footprint ""
		(layer "F.Cu")
		(at 64.83604 -150.76805 -90)
		(property "Reference" "R766"
			(at 0 0 270)
			(layer "F.SilkS")
			(hide yes)
			(effects
				(font
					(size 1.27 1.27)
				)
			)
		)
		(property "Value" "33R2J-2-GP"
			(at 0.064008 -3.993896 270)
			(unlocked yes)
			(layer "F.Fab")
			(hide yes)
			(effects
				(font
					(size 1.016 1.016)
					(thickness 0.1524)
				)
			)
		)
		(property "Device Type" "R402H16"
			(at 0.064008 -5.517896 270)
			(unlocked yes)
			(layer "F.Fab")
			(hide yes)
			(effects
				(font
					(size 1.016 1.016)
					(thickness 0.1524)
				)
			)
		)
		(duplicate_pad_numbers_are_jumpers no)
		(fp_line
			(start -0.508 -0.9398)
			(end -0.508 0.9398)
			(stroke
				(width 0.1524)
				(type default)
			)
			(layer "F.SilkS")
		)
		(fp_line
			(start 0.508 -0.9398)
			(end -0.508 -0.9398)
			(stroke
				(width 0.1524)
				(type default)
			)
			(layer "F.SilkS")
		)
		(fp_rect
			(start -0.508 0.9398)
			(end 0.508 -0.9398)
			(stroke
				(width 0)
				(type default)
			)
			(fill no)
			(layer "F.CrtYd")
		)
		(fp_rect
			(start -0.508 0.9398)
			(end 0.508 -0.9398)
			(stroke
				(width 0)
				(type default)
			)
			(fill no)
			(layer "F.Fab")
		)
		(pad "1" smd custom
			(at 0 -0.4445 270)
			(size 0.1397 0.1397)
			(layers "F.Cu" "F.Mask" "F.Paste")
			(net "U30_Q1")
			(options
				(clearance outline)
				(anchor circle)
			)
			(primitives
				(gr_poly
					(pts
						(arc
							(start -0.1778 -0.2794)
							(mid -0.249642 -0.249642)
							(end -0.2794 -0.1778)
						)
						(arc
							(start -0.2794 0.1778)
							(mid -0.249642 0.249642)
							(end -0.1778 0.2794)
						)
						(arc
							(start 0.1778 0.2794)
							(mid 0.249642 0.249642)
							(end 0.2794 0.1778)
						)
						(arc
							(start 0.2794 -0.1778)
							(mid 0.249642 -0.249642)
							(end 0.1778 -0.2794)
						)
					)
					(width 0)
					(fill yes)
				)
			)
		)
		(pad "2" smd custom
			(at 0 0.4445 270)
			(size 0.1397 0.1397)
			(layers "F.Cu" "F.Mask" "F.Paste")
			(net "CLK_50M_BMC_NCSI")
			(options
				(clearance outline)
				(anchor circle)
			)
			(primitives
				(gr_poly
					(pts
						(arc
							(start -0.1778 -0.2794)
							(mid -0.249642 -0.249642)
							(end -0.2794 -0.1778)
						)
						(arc
							(start -0.2794 0.1778)
							(mid -0.249642 0.249642)
							(end -0.1778 0.2794)
						)
						(arc
							(start 0.1778 0.2794)
							(mid 0.249642 0.249642)
							(end 0.2794 0.1778)
						)
						(arc
							(start 0.2794 -0.1778)
							(mid 0.249642 -0.249642)
							(end 0.1778 -0.2794)
						)
					)
					(width 0)
					(fill yes)
				)
			)
		)
	)
	(footprint ""
		(layer "F.Cu")
		(at 91.639644 -162.52952 -90)
		(property "Reference" "C17"
			(at 0 0 270)
			(layer "F.SilkS")
			(hide yes)
			(effects
				(font
					(size 1.27 1.27)
				)
			)
		)
		(property "Value" "SC18P50V2JN-1-GP"
			(at 1.1811 -2.7051 270)
			(unlocked yes)
			(layer "F.Fab")
			(hide yes)
			(effects
				(font
					(size 1.016 1.016)
					(thickness 0.1524)
				)
			)
		)
		(property "Device Type" "C402H22"
			(at 1.1811 -4.2291 270)
			(unlocked yes)
			(layer "F.Fab")
			(hide yes)
			(effects
				(font
					(size 1.016 1.016)
					(thickness 0.1524)
				)
			)
		)
		(duplicate_pad_numbers_are_jumpers no)
		(fp_rect
			(start -0.4318 0.9525)
			(end 0.4318 -0.9525)
			(stroke
				(width 0)
				(type default)
			)
			(fill no)
			(layer "F.CrtYd")
		)
		(fp_rect
			(start -0.4318 0.9525)
			(end 0.4318 -0.9525)
			(stroke
				(width 0)
				(type default)
			)
			(fill no)
			(layer "F.Fab")
		)
		(pad "1" smd custom
			(at 0 -0.4445 270)
			(size 0.1524 0.1524)
			(layers "F.Cu" "F.Mask" "F.Paste")
			(net "USB_HUB_XTAL_IN")
			(options
				(clearance outline)
				(anchor circle)
			)
			(primitives
				(gr_poly
					(pts
						(arc
							(start 0.3048 -0.2032)
							(mid 0.275042 -0.275042)
							(end 0.2032 -0.3048)
						)
						(arc
							(start -0.2032 -0.3048)
							(mid -0.275042 -0.275042)
							(end -0.3048 -0.2032)
						)
						(arc
							(start -0.3048 0.2032)
							(mid -0.275042 0.275042)
							(end -0.2032 0.3048)
						)
						(arc
							(start 0.2032 0.3048)
							(mid 0.275042 0.275042)
							(end 0.3048 0.2032)
						)
					)
					(width 0)
					(fill yes)
				)
			)
		)
		(pad "2" smd custom
			(at 0 0.4445 270)
			(size 0.1524 0.1524)
			(layers "F.Cu" "F.Mask" "F.Paste")
			(net "GND")
			(options
				(clearance outline)
				(anchor circle)
			)
			(primitives
				(gr_poly
					(pts
						(arc
							(start 0.3048 -0.2032)
							(mid 0.275042 -0.275042)
							(end 0.2032 -0.3048)
						)
						(arc
							(start -0.2032 -0.3048)
							(mid -0.275042 -0.275042)
							(end -0.3048 -0.2032)
						)
						(arc
							(start -0.3048 0.2032)
							(mid -0.275042 0.275042)
							(end -0.2032 0.3048)
						)
						(arc
							(start 0.2032 0.3048)
							(mid 0.275042 0.275042)
							(end 0.3048 0.2032)
						)
					)
					(width 0)
					(fill yes)
				)
			)
		)
	)
	(footprint ""
		(layer "F.Cu")
		(at 32.6898 -134.6962 90)
		(property "Reference" "R369"
			(at 0 0 90)
			(layer "F.SilkS")
			(hide yes)
			(effects
				(font
					(size 1.27 1.27)
				)
			)
		)
		(property "Value" "4K7R2F-GP"
			(at 0.064008 -3.993896 90)
			(unlocked yes)
			(layer "F.Fab")
			(hide yes)
			(effects
				(font
					(size 1.016 1.016)
					(thickness 0.1524)
				)
			)
		)
		(property "Device Type" "R402H16"
			(at 0.064008 -5.517896 90)
			(unlocked yes)
			(layer "F.Fab")
			(hide yes)
			(effects
				(font
					(size 1.016 1.016)
					(thickness 0.1524)
				)
			)
		)
		(duplicate_pad_numbers_are_jumpers no)
		(fp_line
			(start 0.508 -0.9398)
			(end -0.508 -0.9398)
			(stroke
				(width 0.1524)
				(type default)
			)
			(layer "F.SilkS")
		)
		(fp_line
			(start -0.508 -0.9398)
			(end -0.508 0.9398)
			(stroke
				(width 0.1524)
				(type default)
			)
			(layer "F.SilkS")
		)
		(fp_rect
			(start -0.508 0.9398)
			(end 0.508 -0.9398)
			(stroke
				(width 0)
				(type default)
			)
			(fill no)
			(layer "F.CrtYd")
		)
		(fp_rect
			(start -0.508 0.9398)
			(end 0.508 -0.9398)
			(stroke
				(width 0)
				(type default)
			)
			(fill no)
			(layer "F.Fab")
		)
		(pad "1" smd custom
			(at 0 -0.4445 90)
			(size 0.1397 0.1397)
			(layers "F.Cu" "F.Mask" "F.Paste")
			(net "P3V3_STBY")
			(options
				(clearance outline)
				(anchor circle)
			)
			(primitives
				(gr_poly
					(pts
						(arc
							(start -0.1778 -0.2794)
							(mid -0.249642 -0.249642)
							(end -0.2794 -0.1778)
						)
						(arc
							(start -0.2794 0.1778)
							(mid -0.249642 0.249642)
							(end -0.1778 0.2794)
						)
						(arc
							(start 0.1778 0.2794)
							(mid 0.249642 0.249642)
							(end 0.2794 0.1778)
						)
						(arc
							(start 0.2794 -0.1778)
							(mid 0.249642 -0.249642)
							(end 0.1778 -0.2794)
						)
					)
					(width 0)
					(fill yes)
				)
			)
		)
		(pad "2" smd custom
			(at 0 0.4445 90)
			(size 0.1397 0.1397)
			(layers "F.Cu" "F.Mask" "F.Paste")
			(net "BMC_SPI_CLK")
			(options
				(clearance outline)
				(anchor circle)
			)
			(primitives
				(gr_poly
					(pts
						(arc
							(start -0.1778 -0.2794)
							(mid -0.249642 -0.249642)
							(end -0.2794 -0.1778)
						)
						(arc
							(start -0.2794 0.1778)
							(mid -0.249642 0.249642)
							(end -0.1778 0.2794)
						)
						(arc
							(start 0.1778 0.2794)
							(mid 0.249642 0.249642)
							(end 0.2794 0.1778)
						)
						(arc
							(start 0.2794 -0.1778)
							(mid 0.249642 -0.249642)
							(end 0.1778 -0.2794)
						)
					)
					(width 0)
					(fill yes)
				)
			)
		)
	)
	(footprint ""
		(layer "F.Cu")
		(at 94.98838 -20.7518 90)
		(property "Reference" "D16"
			(at 0 0 90)
			(layer "F.SilkS")
			(hide yes)
			(effects
				(font
					(size 1.27 1.27)
				)
			)
		)
		(property "Value" "PESD5V0S1BL-1-GP"
			(at 1.8923 -1.5621 90)
			(unlocked yes)
			(layer "F.Fab")
			(hide yes)
			(effects
				(font
					(size 1.016 1.016)
					(thickness 0.1524)
				)
			)
		)
		(property "Device Type" "SOD882-10D6-1H20"
			(at 1.8923 -3.0861 90)
			(unlocked yes)
			(layer "F.Fab")
			(hide yes)
			(effects
				(font
					(size 1.016 1.016)
					(thickness 0.1524)
				)
			)
		)
		(duplicate_pad_numbers_are_jumpers no)
		(fp_line
			(start -0.3048 -0.9271)
			(end 0.3048 -0.9271)
			(stroke
				(width 0.254)
				(type default)
			)
			(layer "F.SilkS")
		)
		(fp_rect
			(start -0.2921 0.4953)
			(end 0.2921 -0.4953)
			(stroke
				(width 0)
				(type default)
			)
			(fill no)
			(layer "F.CrtYd")
		)
		(fp_poly
			(pts
				(xy -0.4318 0.8001) (xy -0.4318 -0.266192) (xy -0.2921 -0.266192) (xy -0.2921 0.4953) (xy 0.2921 0.4953)
				(xy 0.2921 -0.4953) (xy -0.2921 -0.4953) (xy -0.2921 -0.2667) (xy -0.4318 -0.2667) (xy -0.4318 -0.8001)
				(xy 0.4318 -0.8001) (xy 0.4318 0.8001)
			)
			(stroke
				(width 0)
				(type default)
			)
			(fill no)
			(layer "F.CrtYd")
		)
		(fp_rect
			(start -0.4318 0.8001)
			(end 0.4318 -0.8001)
			(stroke
				(width 0)
				(type default)
			)
			(fill no)
			(layer "F.Fab")
		)
		(pad "1" smd custom
			(at 0 -0.4445 90)
			(size 0.1143 0.1143)
			(layers "F.Cu" "F.Mask" "F.Paste")
			(net "UART_IOM_TX")
			(options
				(clearance outline)
				(anchor circle)
			)
			(primitives
				(gr_poly
					(pts
						(arc
							(start -0.2032 0.2286)
							(mid -0.275042 0.198842)
							(end -0.3048 0.127)
						)
						(arc
							(start -0.3048 -0.127)
							(mid -0.275042 -0.198842)
							(end -0.2032 -0.2286)
						)
						(arc
							(start 0.2032 -0.2286)
							(mid 0.275042 -0.198842)
							(end 0.3048 -0.127)
						)
						(arc
							(start 0.3048 0.127)
							(mid 0.275042 0.198842)
							(end 0.2032 0.2286)
						)
					)
					(width 0)
					(fill yes)
				)
			)
		)
		(pad "2" smd custom
			(at 0 0.4445 90)
			(size 0.1143 0.1143)
			(layers "F.Cu" "F.Mask" "F.Paste")
			(net "GND")
			(options
				(clearance outline)
				(anchor circle)
			)
			(primitives
				(gr_poly
					(pts
						(arc
							(start 0.2032 -0.2286)
							(mid 0.275042 -0.198842)
							(end 0.3048 -0.127)
						)
						(arc
							(start 0.3048 0.127)
							(mid 0.275042 0.198842)
							(end 0.2032 0.2286)
						)
						(arc
							(start -0.2032 0.2286)
							(mid -0.275042 0.198842)
							(end -0.3048 0.127)
						)
						(arc
							(start -0.3048 -0.127)
							(mid -0.275042 -0.198842)
							(end -0.2032 -0.2286)
						)
					)
					(width 0)
					(fill yes)
				)
			)
		)
	)
	(footprint ""
		(layer "F.Cu")
		(at 48.533304 -161.264092 180)
		(property "Reference" "R203"
			(at 0 0 180)
			(layer "F.SilkS")
			(hide yes)
			(effects
				(font
					(size 1.27 1.27)
				)
			)
		)
		(property "Value" "2K2R2F-GP"
			(at 0.064008 -3.993896 180)
			(unlocked yes)
			(layer "F.Fab")
			(hide yes)
			(effects
				(font
					(size 1.016 1.016)
					(thickness 0.1524)
				)
			)
		)
		(property "Device Type" "R402H16"
			(at 0.064008 -5.517896 180)
			(unlocked yes)
			(layer "F.Fab")
			(hide yes)
			(effects
				(font
					(size 1.016 1.016)
					(thickness 0.1524)
				)
			)
		)
		(duplicate_pad_numbers_are_jumpers no)
		(fp_line
			(start 0.508 -0.9398)
			(end -0.508 -0.9398)
			(stroke
				(width 0.1524)
				(type default)
			)
			(layer "F.SilkS")
		)
		(fp_line
			(start -0.508 -0.9398)
			(end -0.508 0.9398)
			(stroke
				(width 0.1524)
				(type default)
			)
			(layer "F.SilkS")
		)
		(fp_rect
			(start -0.508 0.9398)
			(end 0.508 -0.9398)
			(stroke
				(width 0)
				(type default)
			)
			(fill no)
			(layer "F.CrtYd")
		)
		(fp_rect
			(start -0.508 0.9398)
			(end 0.508 -0.9398)
			(stroke
				(width 0)
				(type default)
			)
			(fill no)
			(layer "F.Fab")
		)
		(pad "1" smd custom
			(at 0 -0.4445 180)
			(size 0.1397 0.1397)
			(layers "F.Cu" "F.Mask" "F.Paste")
			(net "I2C_DPB_MISC_SCL_OUT")
			(options
				(clearance outline)
				(anchor circle)
			)
			(primitives
				(gr_poly
					(pts
						(arc
							(start -0.1778 -0.2794)
							(mid -0.249642 -0.249642)
							(end -0.2794 -0.1778)
						)
						(arc
							(start -0.2794 0.1778)
							(mid -0.249642 0.249642)
							(end -0.1778 0.2794)
						)
						(arc
							(start 0.1778 0.2794)
							(mid 0.249642 0.249642)
							(end 0.2794 0.1778)
						)
						(arc
							(start 0.2794 -0.1778)
							(mid 0.249642 -0.249642)
							(end 0.1778 -0.2794)
						)
					)
					(width 0)
					(fill yes)
				)
			)
		)
		(pad "2" smd custom
			(at 0 0.4445 180)
			(size 0.1397 0.1397)
			(layers "F.Cu" "F.Mask" "F.Paste")
			(net "P3V3_STBY")
			(options
				(clearance outline)
				(anchor circle)
			)
			(primitives
				(gr_poly
					(pts
						(arc
							(start -0.1778 -0.2794)
							(mid -0.249642 -0.249642)
							(end -0.2794 -0.1778)
						)
						(arc
							(start -0.2794 0.1778)
							(mid -0.249642 0.249642)
							(end -0.1778 0.2794)
						)
						(arc
							(start 0.1778 0.2794)
							(mid 0.249642 0.249642)
							(end 0.2794 0.1778)
						)
						(arc
							(start 0.2794 -0.1778)
							(mid 0.249642 -0.249642)
							(end 0.1778 -0.2794)
						)
					)
					(width 0)
					(fill yes)
				)
			)
		)
	)
	(footprint ""
		(layer "F.Cu")
		(at 19.15287 -131.007358 180)
		(property "Reference" "R216"
			(at 0 0 180)
			(layer "F.SilkS")
			(hide yes)
			(effects
				(font
					(size 1.27 1.27)
				)
			)
		)
		(property "Value" "120R2F-GP"
			(at 0.064008 -3.993896 180)
			(unlocked yes)
			(layer "F.Fab")
			(hide yes)
			(effects
				(font
					(size 1.016 1.016)
					(thickness 0.1524)
				)
			)
		)
		(property "Device Type" "R402H16"
			(at 0.064008 -5.517896 180)
			(unlocked yes)
			(layer "F.Fab")
			(hide yes)
			(effects
				(font
					(size 1.016 1.016)
					(thickness 0.1524)
				)
			)
		)
		(duplicate_pad_numbers_are_jumpers no)
		(fp_line
			(start 0.508 -0.9398)
			(end -0.508 -0.9398)
			(stroke
				(width 0.1524)
				(type default)
			)
			(layer "F.SilkS")
		)
		(fp_line
			(start -0.508 -0.9398)
			(end -0.508 0.9398)
			(stroke
				(width 0.1524)
				(type default)
			)
			(layer "F.SilkS")
		)
		(fp_rect
			(start -0.508 0.9398)
			(end 0.508 -0.9398)
			(stroke
				(width 0)
				(type default)
			)
			(fill no)
			(layer "F.CrtYd")
		)
		(fp_rect
			(start -0.508 0.9398)
			(end 0.508 -0.9398)
			(stroke
				(width 0)
				(type default)
			)
			(fill no)
			(layer "F.Fab")
		)
		(pad "1" smd custom
			(at 0 -0.4445 180)
			(size 0.1397 0.1397)
			(layers "F.Cu" "F.Mask" "F.Paste")
			(net "MEMCSN")
			(options
				(clearance outline)
				(anchor circle)
			)
			(primitives
				(gr_poly
					(pts
						(arc
							(start -0.1778 -0.2794)
							(mid -0.249642 -0.249642)
							(end -0.2794 -0.1778)
						)
						(arc
							(start -0.2794 0.1778)
							(mid -0.249642 0.249642)
							(end -0.1778 0.2794)
						)
						(arc
							(start 0.1778 0.2794)
							(mid 0.249642 0.249642)
							(end 0.2794 0.1778)
						)
						(arc
							(start 0.2794 -0.1778)
							(mid 0.249642 -0.249642)
							(end 0.1778 -0.2794)
						)
					)
					(width 0)
					(fill yes)
				)
			)
		)
		(pad "2" smd custom
			(at 0 0.4445 180)
			(size 0.1397 0.1397)
			(layers "F.Cu" "F.Mask" "F.Paste")
			(net "P1V2_STBY")
			(options
				(clearance outline)
				(anchor circle)
			)
			(primitives
				(gr_poly
					(pts
						(arc
							(start -0.1778 -0.2794)
							(mid -0.249642 -0.249642)
							(end -0.2794 -0.1778)
						)
						(arc
							(start -0.2794 0.1778)
							(mid -0.249642 0.249642)
							(end -0.1778 0.2794)
						)
						(arc
							(start 0.1778 0.2794)
							(mid 0.249642 0.249642)
							(end 0.2794 0.1778)
						)
						(arc
							(start 0.2794 -0.1778)
							(mid 0.249642 -0.249642)
							(end 0.1778 -0.2794)
						)
					)
					(width 0)
					(fill yes)
				)
			)
		)
	)
	(footprint ""
		(layer "F.Cu")
		(at 43.3324 -161.417 180)
		(property "Reference" "R188"
			(at 0 0 180)
			(layer "F.SilkS")
			(hide yes)
			(effects
				(font
					(size 1.27 1.27)
				)
			)
		)
		(property "Value" "2K2R2F-GP"
			(at 0.064008 -3.993896 180)
			(unlocked yes)
			(layer "F.Fab")
			(hide yes)
			(effects
				(font
					(size 1.016 1.016)
					(thickness 0.1524)
				)
			)
		)
		(property "Device Type" "R402H16"
			(at 0.064008 -5.517896 180)
			(unlocked yes)
			(layer "F.Fab")
			(hide yes)
			(effects
				(font
					(size 1.016 1.016)
					(thickness 0.1524)
				)
			)
		)
		(duplicate_pad_numbers_are_jumpers no)
		(fp_line
			(start 0.508 -0.9398)
			(end -0.508 -0.9398)
			(stroke
				(width 0.1524)
				(type default)
			)
			(layer "F.SilkS")
		)
		(fp_line
			(start -0.508 -0.9398)
			(end -0.508 0.9398)
			(stroke
				(width 0.1524)
				(type default)
			)
			(layer "F.SilkS")
		)
		(fp_rect
			(start -0.508 0.9398)
			(end 0.508 -0.9398)
			(stroke
				(width 0)
				(type default)
			)
			(fill no)
			(layer "F.CrtYd")
		)
		(fp_rect
			(start -0.508 0.9398)
			(end 0.508 -0.9398)
			(stroke
				(width 0)
				(type default)
			)
			(fill no)
			(layer "F.Fab")
		)
		(pad "1" smd custom
			(at 0 -0.4445 180)
			(size 0.1397 0.1397)
			(layers "F.Cu" "F.Mask" "F.Paste")
			(net "I2C_M2_1_SDA")
			(options
				(clearance outline)
				(anchor circle)
			)
			(primitives
				(gr_poly
					(pts
						(arc
							(start -0.1778 -0.2794)
							(mid -0.249642 -0.249642)
							(end -0.2794 -0.1778)
						)
						(arc
							(start -0.2794 0.1778)
							(mid -0.249642 0.249642)
							(end -0.1778 0.2794)
						)
						(arc
							(start 0.1778 0.2794)
							(mid 0.249642 0.249642)
							(end 0.2794 0.1778)
						)
						(arc
							(start 0.2794 -0.1778)
							(mid 0.249642 -0.249642)
							(end 0.1778 -0.2794)
						)
					)
					(width 0)
					(fill yes)
				)
			)
		)
		(pad "2" smd custom
			(at 0 0.4445 180)
			(size 0.1397 0.1397)
			(layers "F.Cu" "F.Mask" "F.Paste")
			(net "P3V3_STBY")
			(options
				(clearance outline)
				(anchor circle)
			)
			(primitives
				(gr_poly
					(pts
						(arc
							(start -0.1778 -0.2794)
							(mid -0.249642 -0.249642)
							(end -0.2794 -0.1778)
						)
						(arc
							(start -0.2794 0.1778)
							(mid -0.249642 0.249642)
							(end -0.1778 0.2794)
						)
						(arc
							(start 0.1778 0.2794)
							(mid 0.249642 0.249642)
							(end 0.2794 0.1778)
						)
						(arc
							(start 0.2794 -0.1778)
							(mid 0.249642 -0.249642)
							(end 0.1778 -0.2794)
						)
					)
					(width 0)
					(fill yes)
				)
			)
		)
	)
	(footprint ""
		(layer "F.Cu")
		(at 222.499936 -153.999946)
		(property "Reference" ""
			(at 0 0 0)
			(layer "F.SilkS")
			(hide yes)
			(effects
				(font
					(size 1.27 1.27)
				)
			)
		)
		(property "Value" "*"
			(at -6.38175 0.19685 0)
			(unlocked yes)
			(layer "F.Fab")
			(hide yes)
			(effects
				(font
					(size 1.016 1.016)
					(thickness 0.1524)
				)
			)
		)
		(duplicate_pad_numbers_are_jumpers no)
		(fp_poly
			(pts
				(arc
					(start 5.0673 0)
					(mid -5.0673 0)
					(end 5.0673 0)
				)
			)
			(stroke
				(width 0)
				(type default)
			)
			(fill no)
			(layer "B.CrtYd")
		)
		(fp_poly
			(pts
				(arc
					(start 5.0673 0)
					(mid -5.0673 0)
					(end 5.0673 0)
				)
			)
			(stroke
				(width 0)
				(type default)
			)
			(fill no)
			(layer "F.CrtYd")
		)
		(fp_poly
			(pts
				(arc
					(start 5.0673 0)
					(mid -5.0673 0)
					(end 5.0673 0)
				)
			)
			(stroke
				(width 0)
				(type default)
			)
			(fill no)
			(layer "B.Fab")
		)
		(fp_poly
			(pts
				(arc
					(start 5.0673 0)
					(mid -5.0673 0)
					(end 5.0673 0)
				)
			)
			(stroke
				(width 0)
				(type default)
			)
			(fill no)
			(layer "F.Fab")
		)
		(pad "1" thru_hole circle
			(at 0 0)
			(size 9.525 9.525)
			(drill 3.5052)
			(layers "*.Cu" "*.Mask")
			(remove_unused_layers no)
			(net "Net_41")
			(clearance -2.5019)
			(thermal_gap 0.3048)
			(padstack
				(mode front_inner_back)
				(layer "Inner"
					(shape circle)
					(size 3.9116 3.9116)
					(clearance 0.3048)
				)
				(layer "B.Cu"
					(shape circle)
					(size 9.525 9.525)
					(clearance -2.5019)
				)
			)
		)
	)
	(footprint ""
		(layer "F.Cu")
		(at 28.346146 -178.17211 -90)
		(property "Reference" "R492"
			(at 0 0 270)
			(layer "F.SilkS")
			(hide yes)
			(effects
				(font
					(size 1.27 1.27)
				)
			)
		)
		(property "Value" "475KR2F-GP"
			(at 0.064008 -3.993896 270)
			(unlocked yes)
			(layer "F.Fab")
			(hide yes)
			(effects
				(font
					(size 1.016 1.016)
					(thickness 0.1524)
				)
			)
		)
		(property "Device Type" "R402H16"
			(at 0.064008 -5.517896 270)
			(unlocked yes)
			(layer "F.Fab")
			(hide yes)
			(effects
				(font
					(size 1.016 1.016)
					(thickness 0.1524)
				)
			)
		)
		(duplicate_pad_numbers_are_jumpers no)
		(fp_line
			(start -0.508 -0.9398)
			(end -0.508 0.9398)
			(stroke
				(width 0.1524)
				(type default)
			)
			(layer "F.SilkS")
		)
		(fp_line
			(start 0.508 -0.9398)
			(end -0.508 -0.9398)
			(stroke
				(width 0.1524)
				(type default)
			)
			(layer "F.SilkS")
		)
		(fp_rect
			(start -0.508 0.9398)
			(end 0.508 -0.9398)
			(stroke
				(width 0)
				(type default)
			)
			(fill no)
			(layer "F.CrtYd")
		)
		(fp_rect
			(start -0.508 0.9398)
			(end 0.508 -0.9398)
			(stroke
				(width 0)
				(type default)
			)
			(fill no)
			(layer "F.Fab")
		)
		(pad "1" smd custom
			(at 0 -0.4445 270)
			(size 0.1397 0.1397)
			(layers "F.Cu" "F.Mask" "F.Paste")
			(net "P3V3_STBY_MODE")
			(options
				(clearance outline)
				(anchor circle)
			)
			(primitives
				(gr_poly
					(pts
						(arc
							(start -0.1778 -0.2794)
							(mid -0.249642 -0.249642)
							(end -0.2794 -0.1778)
						)
						(arc
							(start -0.2794 0.1778)
							(mid -0.249642 0.249642)
							(end -0.1778 0.2794)
						)
						(arc
							(start 0.1778 0.2794)
							(mid 0.249642 0.249642)
							(end 0.2794 0.1778)
						)
						(arc
							(start 0.2794 -0.1778)
							(mid 0.249642 -0.249642)
							(end 0.1778 -0.2794)
						)
					)
					(width 0)
					(fill yes)
				)
			)
		)
		(pad "2" smd custom
			(at 0 0.4445 270)
			(size 0.1397 0.1397)
			(layers "F.Cu" "F.Mask" "F.Paste")
			(net "PWRGD_P3V3_STBY")
			(options
				(clearance outline)
				(anchor circle)
			)
			(primitives
				(gr_poly
					(pts
						(arc
							(start -0.1778 -0.2794)
							(mid -0.249642 -0.249642)
							(end -0.2794 -0.1778)
						)
						(arc
							(start -0.2794 0.1778)
							(mid -0.249642 0.249642)
							(end -0.1778 0.2794)
						)
						(arc
							(start 0.1778 0.2794)
							(mid 0.249642 0.249642)
							(end 0.2794 0.1778)
						)
						(arc
							(start 0.2794 -0.1778)
							(mid 0.249642 -0.249642)
							(end 0.1778 -0.2794)
						)
					)
					(width 0)
					(fill yes)
				)
			)
		)
	)
	(footprint ""
		(layer "F.Cu")
		(at 188.214 -139.1158)
		(property "Reference" "TP213"
			(at 0 0 0)
			(layer "F.SilkS")
			(hide yes)
			(effects
				(font
					(size 1.27 1.27)
				)
			)
		)
		(property "Value" "TPAD28-2-GP"
			(at -0.0127 -1.6637 0)
			(unlocked yes)
			(layer "F.Fab")
			(hide yes)
			(effects
				(font
					(size 1.016 1.016)
					(thickness 0.1524)
				)
			)
		)
		(property "Device Type" "TPAD28"
			(at -0.0127 -3.1877 0)
			(unlocked yes)
			(layer "F.Fab")
			(hide yes)
			(effects
				(font
					(size 1.016 1.016)
					(thickness 0.1524)
				)
			)
		)
		(duplicate_pad_numbers_are_jumpers no)
		(fp_poly
			(pts
				(arc
					(start 0.3556 0)
					(mid -0.3556 0)
					(end 0.3556 0)
				)
			)
			(stroke
				(width 0)
				(type default)
			)
			(fill no)
			(layer "F.CrtYd")
		)
		(fp_poly
			(pts
				(arc
					(start 0.6096 0)
					(mid -0.6096 0)
					(end 0.6096 0)
				)
			)
			(stroke
				(width 0)
				(type default)
			)
			(fill no)
			(layer "F.Fab")
		)
		(pad "1" smd circle
			(at 0 0)
			(size 0.7112 0.7112)
			(layers "F.Cu" "F.Mask" "F.Paste")
			(net "TP_M2_2_MFG_CLK")
		)
	)
	(footprint ""
		(layer "F.Cu")
		(at 213.77275 -45.587158)
		(property "Reference" "R474"
			(at 0 0 0)
			(layer "F.SilkS")
			(hide yes)
			(effects
				(font
					(size 1.27 1.27)
				)
			)
		)
		(property "Value" "73K2R2F-GP"
			(at 0.064008 -3.993896 0)
			(unlocked yes)
			(layer "F.Fab")
			(hide yes)
			(effects
				(font
					(size 1.016 1.016)
					(thickness 0.1524)
				)
			)
		)
		(property "Device Type" "R402H16"
			(at 0.064008 -5.517896 0)
			(unlocked yes)
			(layer "F.Fab")
			(hide yes)
			(effects
				(font
					(size 1.016 1.016)
					(thickness 0.1524)
				)
			)
		)
		(duplicate_pad_numbers_are_jumpers no)
		(fp_line
			(start -0.508 -0.9398)
			(end -0.508 0.9398)
			(stroke
				(width 0.1524)
				(type default)
			)
			(layer "F.SilkS")
		)
		(fp_line
			(start 0.508 -0.9398)
			(end -0.508 -0.9398)
			(stroke
				(width 0.1524)
				(type default)
			)
			(layer "F.SilkS")
		)
		(fp_rect
			(start -0.508 0.9398)
			(end 0.508 -0.9398)
			(stroke
				(width 0)
				(type default)
			)
			(fill no)
			(layer "F.CrtYd")
		)
		(fp_rect
			(start -0.508 0.9398)
			(end 0.508 -0.9398)
			(stroke
				(width 0)
				(type default)
			)
			(fill no)
			(layer "F.Fab")
		)
		(pad "1" smd custom
			(at 0 -0.4445)
			(size 0.1397 0.1397)
			(layers "F.Cu" "F.Mask" "F.Paste")
			(net "P5V_VFB")
			(options
				(clearance outline)
				(anchor circle)
			)
			(primitives
				(gr_poly
					(pts
						(arc
							(start -0.1778 -0.2794)
							(mid -0.249642 -0.249642)
							(end -0.2794 -0.1778)
						)
						(arc
							(start -0.2794 0.1778)
							(mid -0.249642 0.249642)
							(end -0.1778 0.2794)
						)
						(arc
							(start 0.1778 0.2794)
							(mid 0.249642 0.249642)
							(end 0.2794 0.1778)
						)
						(arc
							(start 0.2794 -0.1778)
							(mid 0.249642 -0.249642)
							(end 0.1778 -0.2794)
						)
					)
					(width 0)
					(fill yes)
				)
			)
		)
		(pad "2" smd custom
			(at 0 0.4445)
			(size 0.1397 0.1397)
			(layers "F.Cu" "F.Mask" "F.Paste")
			(net "P5V_VFB_R")
			(options
				(clearance outline)
				(anchor circle)
			)
			(primitives
				(gr_poly
					(pts
						(arc
							(start -0.1778 -0.2794)
							(mid -0.249642 -0.249642)
							(end -0.2794 -0.1778)
						)
						(arc
							(start -0.2794 0.1778)
							(mid -0.249642 0.249642)
							(end -0.1778 0.2794)
						)
						(arc
							(start 0.1778 0.2794)
							(mid 0.249642 0.249642)
							(end 0.2794 0.1778)
						)
						(arc
							(start 0.2794 -0.1778)
							(mid 0.249642 -0.249642)
							(end 0.1778 -0.2794)
						)
					)
					(width 0)
					(fill yes)
				)
			)
		)
	)
	(footprint ""
		(layer "F.Cu")
		(at 83.358228 -75.749658 90)
		(property "Reference" "VIA10"
			(at 0 0 90)
			(layer "F.SilkS")
			(hide yes)
			(effects
				(font
					(size 1.27 1.27)
				)
			)
		)
		(property "Value" "85OHM-8L-1D6MM-L16L18-GP"
			(at 4.064 0.6096 90)
			(unlocked yes)
			(layer "F.Fab")
			(hide yes)
			(effects
				(font
					(size 1.016 1.016)
					(thickness 0.1524)
				)
			)
		)
		(property "Device Type" "VIA-PCIE-4P-368076"
			(at 4.064 -0.9144 90)
			(unlocked yes)
			(layer "F.Fab")
			(hide yes)
			(effects
				(font
					(size 1.016 1.016)
					(thickness 0.1524)
				)
			)
		)
		(duplicate_pad_numbers_are_jumpers no)
		(fp_rect
			(start -1.8415 0.381)
			(end 1.8415 -0.381)
			(stroke
				(width 0)
				(type default)
			)
			(fill no)
			(layer "F.CrtYd")
		)
		(fp_rect
			(start -1.8415 0.381)
			(end 1.8415 -0.381)
			(stroke
				(width 0)
				(type default)
			)
			(fill no)
			(layer "F.Fab")
		)
		(pad "1" thru_hole circle
			(at -1.4605 0 90)
			(size 0.508 0.508)
			(drill 0.254)
			(layers "*.Cu" "*.Mask")
			(remove_unused_layers no)
			(net "GND")
			(clearance 0.127)
			(thermal_gap 0.127)
		)
		(pad "2" thru_hole circle
			(at -0.4445 0 90)
			(size 0.508 0.508)
			(drill 0.254)
			(layers "*.Cu" "*.Mask")
			(remove_unused_layers no)
			(net "PCIE_IOM_TO_COMP_17_DP")
			(clearance 0.127)
			(thermal_gap 0.127)
		)
		(pad "3" thru_hole circle
			(at 0.4445 0 90)
			(size 0.508 0.508)
			(drill 0.254)
			(layers "*.Cu" "*.Mask")
			(remove_unused_layers no)
			(net "PCIE_IOM_TO_COMP_17_DN")
			(clearance 0.127)
			(thermal_gap 0.127)
		)
		(pad "4" thru_hole circle
			(at 1.4605 0 90)
			(size 0.508 0.508)
			(drill 0.254)
			(layers "*.Cu" "*.Mask")
			(remove_unused_layers no)
			(net "GND")
			(clearance 0.127)
			(thermal_gap 0.127)
		)
	)
	(footprint ""
		(layer "F.Cu")
		(at 186.817 -109.474 -90)
		(property "Reference" "R547"
			(at 0 0 270)
			(layer "F.SilkS")
			(hide yes)
			(effects
				(font
					(size 1.27 1.27)
				)
			)
		)
		(property "Value" "4K7R2F-GP"
			(at 0.064008 -3.993896 270)
			(unlocked yes)
			(layer "F.Fab")
			(hide yes)
			(effects
				(font
					(size 1.016 1.016)
					(thickness 0.1524)
				)
			)
		)
		(property "Device Type" "R402H16"
			(at 0.064008 -5.517896 270)
			(unlocked yes)
			(layer "F.Fab")
			(hide yes)
			(effects
				(font
					(size 1.016 1.016)
					(thickness 0.1524)
				)
			)
		)
		(duplicate_pad_numbers_are_jumpers no)
		(fp_line
			(start -0.508 -0.9398)
			(end -0.508 0.9398)
			(stroke
				(width 0.1524)
				(type default)
			)
			(layer "F.SilkS")
		)
		(fp_line
			(start 0.508 -0.9398)
			(end -0.508 -0.9398)
			(stroke
				(width 0.1524)
				(type default)
			)
			(layer "F.SilkS")
		)
		(fp_rect
			(start -0.508 0.9398)
			(end 0.508 -0.9398)
			(stroke
				(width 0)
				(type default)
			)
			(fill no)
			(layer "F.CrtYd")
		)
		(fp_rect
			(start -0.508 0.9398)
			(end 0.508 -0.9398)
			(stroke
				(width 0)
				(type default)
			)
			(fill no)
			(layer "F.Fab")
		)
		(pad "1" smd custom
			(at 0 -0.4445 270)
			(size 0.1397 0.1397)
			(layers "F.Cu" "F.Mask" "F.Paste")
			(net "P3V3_STBY")
			(options
				(clearance outline)
				(anchor circle)
			)
			(primitives
				(gr_poly
					(pts
						(arc
							(start -0.1778 -0.2794)
							(mid -0.249642 -0.249642)
							(end -0.2794 -0.1778)
						)
						(arc
							(start -0.2794 0.1778)
							(mid -0.249642 0.249642)
							(end -0.1778 0.2794)
						)
						(arc
							(start 0.1778 0.2794)
							(mid 0.249642 0.249642)
							(end 0.2794 0.1778)
						)
						(arc
							(start 0.2794 -0.1778)
							(mid 0.249642 -0.249642)
							(end 0.1778 -0.2794)
						)
					)
					(width 0)
					(fill yes)
				)
			)
		)
		(pad "2" smd custom
			(at 0 0.4445 270)
			(size 0.1397 0.1397)
			(layers "F.Cu" "F.Mask" "F.Paste")
			(net "TEMP_1_A2")
			(options
				(clearance outline)
				(anchor circle)
			)
			(primitives
				(gr_poly
					(pts
						(arc
							(start -0.1778 -0.2794)
							(mid -0.249642 -0.249642)
							(end -0.2794 -0.1778)
						)
						(arc
							(start -0.2794 0.1778)
							(mid -0.249642 0.249642)
							(end -0.1778 0.2794)
						)
						(arc
							(start 0.1778 0.2794)
							(mid 0.249642 0.249642)
							(end 0.2794 0.1778)
						)
						(arc
							(start 0.2794 -0.1778)
							(mid 0.249642 -0.249642)
							(end 0.1778 -0.2794)
						)
					)
					(width 0)
					(fill yes)
				)
			)
		)
	)
	(footprint ""
		(layer "F.Cu")
		(at 85.472016 -142.124176 -90)
		(property "Reference" "R329"
			(at 0 0 270)
			(layer "F.SilkS")
			(hide yes)
			(effects
				(font
					(size 1.27 1.27)
				)
			)
		)
		(property "Value" "0R2J-2-GP"
			(at 0.064008 -3.993896 270)
			(unlocked yes)
			(layer "F.Fab")
			(hide yes)
			(effects
				(font
					(size 1.016 1.016)
					(thickness 0.1524)
				)
			)
		)
		(property "Device Type" "R402H16"
			(at 0.064008 -5.517896 270)
			(unlocked yes)
			(layer "F.Fab")
			(hide yes)
			(effects
				(font
					(size 1.016 1.016)
					(thickness 0.1524)
				)
			)
		)
		(duplicate_pad_numbers_are_jumpers no)
		(fp_line
			(start -0.508 -0.9398)
			(end -0.508 0.9398)
			(stroke
				(width 0.1524)
				(type default)
			)
			(layer "F.SilkS")
		)
		(fp_line
			(start 0.508 -0.9398)
			(end -0.508 -0.9398)
			(stroke
				(width 0.1524)
				(type default)
			)
			(layer "F.SilkS")
		)
		(fp_rect
			(start -0.508 0.9398)
			(end 0.508 -0.9398)
			(stroke
				(width 0)
				(type default)
			)
			(fill no)
			(layer "F.CrtYd")
		)
		(fp_rect
			(start -0.508 0.9398)
			(end 0.508 -0.9398)
			(stroke
				(width 0)
				(type default)
			)
			(fill no)
			(layer "F.Fab")
		)
		(pad "1" smd custom
			(at 0 -0.4445 270)
			(size 0.1397 0.1397)
			(layers "F.Cu" "F.Mask" "F.Paste")
			(net "I2C_DPB_SCL")
			(options
				(clearance outline)
				(anchor circle)
			)
			(primitives
				(gr_poly
					(pts
						(arc
							(start -0.1778 -0.2794)
							(mid -0.249642 -0.249642)
							(end -0.2794 -0.1778)
						)
						(arc
							(start -0.2794 0.1778)
							(mid -0.249642 0.249642)
							(end -0.1778 0.2794)
						)
						(arc
							(start 0.1778 0.2794)
							(mid 0.249642 0.249642)
							(end 0.2794 0.1778)
						)
						(arc
							(start 0.2794 -0.1778)
							(mid 0.249642 -0.249642)
							(end 0.1778 -0.2794)
						)
					)
					(width 0)
					(fill yes)
				)
			)
		)
		(pad "2" smd custom
			(at 0 0.4445 270)
			(size 0.1397 0.1397)
			(layers "F.Cu" "F.Mask" "F.Paste")
			(net "I2C_DPB_SCL_R")
			(options
				(clearance outline)
				(anchor circle)
			)
			(primitives
				(gr_poly
					(pts
						(arc
							(start -0.1778 -0.2794)
							(mid -0.249642 -0.249642)
							(end -0.2794 -0.1778)
						)
						(arc
							(start -0.2794 0.1778)
							(mid -0.249642 0.249642)
							(end -0.1778 0.2794)
						)
						(arc
							(start 0.1778 0.2794)
							(mid 0.249642 0.249642)
							(end 0.2794 0.1778)
						)
						(arc
							(start 0.2794 -0.1778)
							(mid 0.249642 -0.249642)
							(end 0.1778 -0.2794)
						)
					)
					(width 0)
					(fill yes)
				)
			)
		)
	)
	(footprint ""
		(layer "F.Cu")
		(at 23.2537 -167.221916 180)
		(property "Reference" "C224"
			(at 0 0 180)
			(layer "F.SilkS")
			(hide yes)
			(effects
				(font
					(size 1.27 1.27)
				)
			)
		)
		(property "Value" "SC10U6D3V5KX-4GP"
			(at -0.0762 -6.1214 180)
			(unlocked yes)
			(layer "F.Fab")
			(hide yes)
			(effects
				(font
					(size 1.016 1.016)
					(thickness 0.1524)
				)
			)
		)
		(property "Device Type" "C805H58"
			(at -0.0762 -8.1534 180)
			(unlocked yes)
			(layer "F.Fab")
			(hide yes)
			(effects
				(font
					(size 1.016 1.016)
					(thickness 0.1524)
				)
			)
		)
		(duplicate_pad_numbers_are_jumpers no)
		(fp_line
			(start 0.635 0)
			(end -0.635 0)
			(stroke
				(width 0.508)
				(type default)
			)
			(layer "F.SilkS")
		)
		(fp_rect
			(start -0.9652 1.778)
			(end 0.9652 -1.778)
			(stroke
				(width 0)
				(type default)
			)
			(fill no)
			(layer "F.CrtYd")
		)
		(fp_poly
			(pts
				(xy -0.9652 -1.778) (xy 0.9652 -1.778) (xy 0.9652 1.778) (xy -0.9652 1.778)
			)
			(stroke
				(width 0)
				(type default)
			)
			(fill no)
			(layer "F.Fab")
		)
		(pad "1" smd rect
			(at 0 -0.9652 180)
			(size 1.397 1.143)
			(layers "F.Cu" "F.Mask" "F.Paste")
			(net "TPS74801_P1V2_STBY_OUT")
		)
		(pad "2" smd rect
			(at 0 0.9652 180)
			(size 1.397 1.143)
			(layers "F.Cu" "F.Mask" "F.Paste")
			(net "GND")
		)
	)
	(footprint ""
		(layer "F.Cu")
		(at 99.3648 -150.6728 -90)
		(property "Reference" "R36"
			(at 0 0 270)
			(layer "F.SilkS")
			(hide yes)
			(effects
				(font
					(size 1.27 1.27)
				)
			)
		)
		(property "Value" "4K7R2F-GP"
			(at 0.064008 -3.993896 270)
			(unlocked yes)
			(layer "F.Fab")
			(hide yes)
			(effects
				(font
					(size 1.016 1.016)
					(thickness 0.1524)
				)
			)
		)
		(property "Device Type" "R402H16"
			(at 0.064008 -5.517896 270)
			(unlocked yes)
			(layer "F.Fab")
			(hide yes)
			(effects
				(font
					(size 1.016 1.016)
					(thickness 0.1524)
				)
			)
		)
		(duplicate_pad_numbers_are_jumpers no)
		(fp_line
			(start -0.508 -0.9398)
			(end -0.508 0.9398)
			(stroke
				(width 0.1524)
				(type default)
			)
			(layer "F.SilkS")
		)
		(fp_line
			(start 0.508 -0.9398)
			(end -0.508 -0.9398)
			(stroke
				(width 0.1524)
				(type default)
			)
			(layer "F.SilkS")
		)
		(fp_rect
			(start -0.508 0.9398)
			(end 0.508 -0.9398)
			(stroke
				(width 0)
				(type default)
			)
			(fill no)
			(layer "F.CrtYd")
		)
		(fp_rect
			(start -0.508 0.9398)
			(end 0.508 -0.9398)
			(stroke
				(width 0)
				(type default)
			)
			(fill no)
			(layer "F.Fab")
		)
		(pad "1" smd custom
			(at 0 -0.4445 270)
			(size 0.1397 0.1397)
			(layers "F.Cu" "F.Mask" "F.Paste")
			(net "P3V3_STBY")
			(options
				(clearance outline)
				(anchor circle)
			)
			(primitives
				(gr_poly
					(pts
						(arc
							(start -0.1778 -0.2794)
							(mid -0.249642 -0.249642)
							(end -0.2794 -0.1778)
						)
						(arc
							(start -0.2794 0.1778)
							(mid -0.249642 0.249642)
							(end -0.1778 0.2794)
						)
						(arc
							(start 0.1778 0.2794)
							(mid 0.249642 0.249642)
							(end 0.2794 0.1778)
						)
						(arc
							(start 0.2794 -0.1778)
							(mid 0.249642 -0.249642)
							(end 0.1778 -0.2794)
						)
					)
					(width 0)
					(fill yes)
				)
			)
		)
		(pad "2" smd custom
			(at 0 0.4445 270)
			(size 0.1397 0.1397)
			(layers "F.Cu" "F.Mask" "F.Paste")
			(net "USB_EN_4")
			(options
				(clearance outline)
				(anchor circle)
			)
			(primitives
				(gr_poly
					(pts
						(arc
							(start -0.1778 -0.2794)
							(mid -0.249642 -0.249642)
							(end -0.2794 -0.1778)
						)
						(arc
							(start -0.2794 0.1778)
							(mid -0.249642 0.249642)
							(end -0.1778 0.2794)
						)
						(arc
							(start 0.1778 0.2794)
							(mid 0.249642 0.249642)
							(end 0.2794 0.1778)
						)
						(arc
							(start 0.2794 -0.1778)
							(mid 0.249642 -0.249642)
							(end 0.1778 -0.2794)
						)
					)
					(width 0)
					(fill yes)
				)
			)
		)
	)
	(footprint ""
		(layer "F.Cu")
		(at 70.2056 -163.721288 -90)
		(property "Reference" "R73"
			(at 0 0 270)
			(layer "F.SilkS")
			(hide yes)
			(effects
				(font
					(size 1.27 1.27)
				)
			)
		)
		(property "Value" "4K75R2F-1-GP"
			(at 0.064008 -3.993896 270)
			(unlocked yes)
			(layer "F.Fab")
			(hide yes)
			(effects
				(font
					(size 1.016 1.016)
					(thickness 0.1524)
				)
			)
		)
		(property "Device Type" "R402H16"
			(at 0.064008 -5.517896 270)
			(unlocked yes)
			(layer "F.Fab")
			(hide yes)
			(effects
				(font
					(size 1.016 1.016)
					(thickness 0.1524)
				)
			)
		)
		(duplicate_pad_numbers_are_jumpers no)
		(fp_line
			(start -0.508 -0.9398)
			(end -0.508 0.9398)
			(stroke
				(width 0.1524)
				(type default)
			)
			(layer "F.SilkS")
		)
		(fp_line
			(start 0.508 -0.9398)
			(end -0.508 -0.9398)
			(stroke
				(width 0.1524)
				(type default)
			)
			(layer "F.SilkS")
		)
		(fp_rect
			(start -0.508 0.9398)
			(end 0.508 -0.9398)
			(stroke
				(width 0)
				(type default)
			)
			(fill no)
			(layer "F.CrtYd")
		)
		(fp_rect
			(start -0.508 0.9398)
			(end 0.508 -0.9398)
			(stroke
				(width 0)
				(type default)
			)
			(fill no)
			(layer "F.Fab")
		)
		(pad "1" smd custom
			(at 0 -0.4445 270)
			(size 0.1397 0.1397)
			(layers "F.Cu" "F.Mask" "F.Paste")
			(net "P3V3_STBY")
			(options
				(clearance outline)
				(anchor circle)
			)
			(primitives
				(gr_poly
					(pts
						(arc
							(start -0.1778 -0.2794)
							(mid -0.249642 -0.249642)
							(end -0.2794 -0.1778)
						)
						(arc
							(start -0.2794 0.1778)
							(mid -0.249642 0.249642)
							(end -0.1778 0.2794)
						)
						(arc
							(start 0.1778 0.2794)
							(mid 0.249642 0.249642)
							(end 0.2794 0.1778)
						)
						(arc
							(start 0.2794 -0.1778)
							(mid 0.249642 -0.249642)
							(end 0.1778 -0.2794)
						)
					)
					(width 0)
					(fill yes)
				)
			)
		)
		(pad "2" smd custom
			(at 0 0.4445 270)
			(size 0.1397 0.1397)
			(layers "F.Cu" "F.Mask" "F.Paste")
			(net "BMC_TPM_RST_N")
			(options
				(clearance outline)
				(anchor circle)
			)
			(primitives
				(gr_poly
					(pts
						(arc
							(start -0.1778 -0.2794)
							(mid -0.249642 -0.249642)
							(end -0.2794 -0.1778)
						)
						(arc
							(start -0.2794 0.1778)
							(mid -0.249642 0.249642)
							(end -0.1778 0.2794)
						)
						(arc
							(start 0.1778 0.2794)
							(mid 0.249642 0.249642)
							(end 0.2794 0.1778)
						)
						(arc
							(start 0.2794 -0.1778)
							(mid 0.249642 -0.249642)
							(end 0.1778 -0.2794)
						)
					)
					(width 0)
					(fill yes)
				)
			)
		)
	)
	(footprint ""
		(layer "F.Cu")
		(at 56.7436 -162.4838)
		(property "Reference" "R402"
			(at 0 0 0)
			(layer "F.SilkS")
			(hide yes)
			(effects
				(font
					(size 1.27 1.27)
				)
			)
		)
		(property "Value" "330R2F-GP"
			(at 0.064008 -3.993896 0)
			(unlocked yes)
			(layer "F.Fab")
			(hide yes)
			(effects
				(font
					(size 1.016 1.016)
					(thickness 0.1524)
				)
			)
		)
		(property "Device Type" "R402H16"
			(at 0.064008 -5.517896 0)
			(unlocked yes)
			(layer "F.Fab")
			(hide yes)
			(effects
				(font
					(size 1.016 1.016)
					(thickness 0.1524)
				)
			)
		)
		(duplicate_pad_numbers_are_jumpers no)
		(fp_line
			(start -0.508 -0.9398)
			(end -0.508 0.9398)
			(stroke
				(width 0.1524)
				(type default)
			)
			(layer "F.SilkS")
		)
		(fp_line
			(start 0.508 -0.9398)
			(end -0.508 -0.9398)
			(stroke
				(width 0.1524)
				(type default)
			)
			(layer "F.SilkS")
		)
		(fp_rect
			(start -0.508 0.9398)
			(end 0.508 -0.9398)
			(stroke
				(width 0)
				(type default)
			)
			(fill no)
			(layer "F.CrtYd")
		)
		(fp_rect
			(start -0.508 0.9398)
			(end 0.508 -0.9398)
			(stroke
				(width 0)
				(type default)
			)
			(fill no)
			(layer "F.Fab")
		)
		(pad "1" smd custom
			(at 0 -0.4445)
			(size 0.1397 0.1397)
			(layers "F.Cu" "F.Mask" "F.Paste")
			(net "P1V8_STBY")
			(options
				(clearance outline)
				(anchor circle)
			)
			(primitives
				(gr_poly
					(pts
						(arc
							(start -0.1778 -0.2794)
							(mid -0.249642 -0.249642)
							(end -0.2794 -0.1778)
						)
						(arc
							(start -0.2794 0.1778)
							(mid -0.249642 0.249642)
							(end -0.1778 0.2794)
						)
						(arc
							(start 0.1778 0.2794)
							(mid 0.249642 0.249642)
							(end 0.2794 0.1778)
						)
						(arc
							(start 0.2794 -0.1778)
							(mid 0.249642 -0.249642)
							(end 0.1778 -0.2794)
						)
					)
					(width 0)
					(fill yes)
				)
			)
		)
		(pad "2" smd custom
			(at 0 0.4445)
			(size 0.1397 0.1397)
			(layers "F.Cu" "F.Mask" "F.Paste")
			(net "ADC_P1V8_STBY")
			(options
				(clearance outline)
				(anchor circle)
			)
			(primitives
				(gr_poly
					(pts
						(arc
							(start -0.1778 -0.2794)
							(mid -0.249642 -0.249642)
							(end -0.2794 -0.1778)
						)
						(arc
							(start -0.2794 0.1778)
							(mid -0.249642 0.249642)
							(end -0.1778 0.2794)
						)
						(arc
							(start 0.1778 0.2794)
							(mid 0.249642 0.249642)
							(end 0.2794 0.1778)
						)
						(arc
							(start 0.2794 -0.1778)
							(mid 0.249642 -0.249642)
							(end 0.1778 -0.2794)
						)
					)
					(width 0)
					(fill yes)
				)
			)
		)
	)
	(footprint ""
		(layer "F.Cu")
		(at 185.399426 -140.000482 -135)
		(property "Reference" "VIA58"
			(at 0 0 225)
			(layer "F.SilkS")
			(hide yes)
			(effects
				(font
					(size 1.27 1.27)
				)
			)
		)
		(property "Value" "85OHM-8L-1D6MM-L16L18-GP"
			(at 4.064105 0.609655 225)
			(unlocked yes)
			(layer "F.Fab")
			(hide yes)
			(effects
				(font
					(size 1.016 1.016)
					(thickness 0.1524)
				)
			)
		)
		(property "Device Type" "VIA-PCIE-4P-368076"
			(at 4.064105 -0.914474 225)
			(unlocked yes)
			(layer "F.Fab")
			(hide yes)
			(effects
				(font
					(size 1.016 1.016)
					(thickness 0.1524)
				)
			)
		)
		(duplicate_pad_numbers_are_jumpers no)
		(fp_poly
			(pts
				(xy -1.841491 -0.381057) (xy 1.841509 -0.381058) (xy 1.841508 0.380942) (xy -1.841491 0.380942)
			)
			(stroke
				(width 0)
				(type default)
			)
			(fill no)
			(layer "F.CrtYd")
		)
		(fp_poly
			(pts
				(xy -1.841491 -0.381057) (xy 1.841509 -0.381058) (xy 1.841508 0.380942) (xy -1.841491 0.380942)
			)
			(stroke
				(width 0)
				(type default)
			)
			(fill no)
			(layer "F.Fab")
		)
		(pad "1" thru_hole circle
			(at -1.460499 0 225)
			(size 0.508 0.508)
			(drill 0.254)
			(layers "*.Cu" "*.Mask")
			(remove_unused_layers no)
			(net "GND")
			(clearance 0.127)
			(thermal_gap 0.127)
		)
		(pad "2" thru_hole circle
			(at -0.4445 0 225)
			(size 0.508 0.508)
			(drill 0.254)
			(layers "*.Cu" "*.Mask")
			(remove_unused_layers no)
			(net "PCIE_COMP_TO_IOM_12_DP")
			(clearance 0.127)
			(thermal_gap 0.127)
		)
		(pad "3" thru_hole circle
			(at 0.4445 0 225)
			(size 0.508 0.508)
			(drill 0.254)
			(layers "*.Cu" "*.Mask")
			(remove_unused_layers no)
			(net "PCIE_COMP_TO_IOM_12_DN")
			(clearance 0.127)
			(thermal_gap 0.127)
		)
		(pad "4" thru_hole circle
			(at 1.460499 0 225)
			(size 0.508 0.508)
			(drill 0.254)
			(layers "*.Cu" "*.Mask")
			(remove_unused_layers no)
			(net "GND")
			(clearance 0.127)
			(thermal_gap 0.127)
		)
	)
	(footprint ""
		(layer "F.Cu")
		(at 84.963 -150.876 -90)
		(property "Reference" "U12"
			(at 0 0 270)
			(layer "F.SilkS")
			(hide yes)
			(effects
				(font
					(size 1.27 1.27)
				)
			)
		)
		(property "Value" "NX3L1G66GW-GP"
			(at -2.3368 -8.6868 270)
			(unlocked yes)
			(layer "F.Fab")
			(hide yes)
			(effects
				(font
					(size 1.016 1.016)
					(thickness 0.1524)
				)
			)
		)
		(property "Device Type" "SC70-5H44"
			(at -2.3114 -10.414 270)
			(unlocked yes)
			(layer "F.Fab")
			(hide yes)
			(effects
				(font
					(size 1.016 1.016)
					(thickness 0.1524)
				)
			)
		)
		(duplicate_pad_numbers_are_jumpers no)
		(fp_line
			(start -1.27 1.7018)
			(end -1.27 -1.7018)
			(stroke
				(width 0.1524)
				(type default)
			)
			(layer "F.SilkS")
		)
		(fp_line
			(start 1.27 1.7018)
			(end -1.27 1.7018)
			(stroke
				(width 0.1524)
				(type default)
			)
			(layer "F.SilkS")
		)
		(fp_line
			(start -1.27 -1.7018)
			(end 1.27 -1.7018)
			(stroke
				(width 0.1524)
				(type default)
			)
			(layer "F.SilkS")
		)
		(fp_line
			(start 1.27 -1.7018)
			(end 1.27 1.7018)
			(stroke
				(width 0.1524)
				(type default)
			)
			(layer "F.SilkS")
		)
		(fp_line
			(start 0.6604 -1.8034)
			(end 1.3843 -1.8034)
			(stroke
				(width 0.3302)
				(type default)
			)
			(layer "F.SilkS")
		)
		(fp_line
			(start 1.3843 -1.8034)
			(end 1.3843 -1.1176)
			(stroke
				(width 0.3302)
				(type default)
			)
			(layer "F.SilkS")
		)
		(fp_rect
			(start -1.524 1.9558)
			(end 1.524 -1.9558)
			(stroke
				(width 0)
				(type default)
			)
			(fill no)
			(layer "F.CrtYd")
		)
		(fp_poly
			(pts
				(xy -1.524 -1.9558) (xy 1.524 -1.9558) (xy 1.524 1.9558) (xy -1.524 1.9558)
			)
			(stroke
				(width 0)
				(type default)
			)
			(fill no)
			(layer "F.Fab")
		)
		(pad "1" smd rect
			(at 0.65024 -0.8255 270)
			(size 0.4064 1.2192)
			(layers "F.Cu" "F.Mask" "F.Paste")
			(net "I2C_BMC_COMP_SCL_R")
		)
		(pad "2" smd rect
			(at 0 -0.8255 270)
			(size 0.4064 1.2192)
			(layers "F.Cu" "F.Mask" "F.Paste")
			(net "I2C_BMC_COMP_SCL_OUT")
		)
		(pad "3" smd rect
			(at -0.65024 -0.8255 270)
			(size 0.4064 1.2192)
			(layers "F.Cu" "F.Mask" "F.Paste")
			(net "GND")
		)
		(pad "4" smd rect
			(at -0.65024 0.8255 270)
			(size 0.4064 1.2192)
			(layers "F.Cu" "F.Mask" "F.Paste")
			(net "COMP_PWR_EN")
		)
		(pad "5" smd rect
			(at 0.65024 0.8255 270)
			(size 0.4064 1.2192)
			(layers "F.Cu" "F.Mask" "F.Paste")
			(net "P3V3_STBY")
		)
	)
	(footprint ""
		(layer "F.Cu")
		(at 89.0016 -134.6708)
		(property "Reference" "R137"
			(at 0 0 0)
			(layer "F.SilkS")
			(hide yes)
			(effects
				(font
					(size 1.27 1.27)
				)
			)
		)
		(property "Value" "8K2R2J-3-GP"
			(at 0.064008 -3.993896 0)
			(unlocked yes)
			(layer "F.Fab")
			(hide yes)
			(effects
				(font
					(size 1.016 1.016)
					(thickness 0.1524)
				)
			)
		)
		(property "Device Type" "R402H16"
			(at 0.064008 -5.517896 0)
			(unlocked yes)
			(layer "F.Fab")
			(hide yes)
			(effects
				(font
					(size 1.016 1.016)
					(thickness 0.1524)
				)
			)
		)
		(duplicate_pad_numbers_are_jumpers no)
		(fp_line
			(start -0.508 -0.9398)
			(end -0.508 0.9398)
			(stroke
				(width 0.1524)
				(type default)
			)
			(layer "F.SilkS")
		)
		(fp_line
			(start 0.508 -0.9398)
			(end -0.508 -0.9398)
			(stroke
				(width 0.1524)
				(type default)
			)
			(layer "F.SilkS")
		)
		(fp_rect
			(start -0.508 0.9398)
			(end 0.508 -0.9398)
			(stroke
				(width 0)
				(type default)
			)
			(fill no)
			(layer "F.CrtYd")
		)
		(fp_rect
			(start -0.508 0.9398)
			(end 0.508 -0.9398)
			(stroke
				(width 0)
				(type default)
			)
			(fill no)
			(layer "F.Fab")
		)
		(pad "1" smd custom
			(at 0 -0.4445)
			(size 0.1397 0.1397)
			(layers "F.Cu" "F.Mask" "F.Paste")
			(net "EEPROM_A1")
			(options
				(clearance outline)
				(anchor circle)
			)
			(primitives
				(gr_poly
					(pts
						(arc
							(start -0.1778 -0.2794)
							(mid -0.249642 -0.249642)
							(end -0.2794 -0.1778)
						)
						(arc
							(start -0.2794 0.1778)
							(mid -0.249642 0.249642)
							(end -0.1778 0.2794)
						)
						(arc
							(start 0.1778 0.2794)
							(mid 0.249642 0.249642)
							(end 0.2794 0.1778)
						)
						(arc
							(start 0.2794 -0.1778)
							(mid 0.249642 -0.249642)
							(end 0.1778 -0.2794)
						)
					)
					(width 0)
					(fill yes)
				)
			)
		)
		(pad "2" smd custom
			(at 0 0.4445)
			(size 0.1397 0.1397)
			(layers "F.Cu" "F.Mask" "F.Paste")
			(net "GND")
			(options
				(clearance outline)
				(anchor circle)
			)
			(primitives
				(gr_poly
					(pts
						(arc
							(start -0.1778 -0.2794)
							(mid -0.249642 -0.249642)
							(end -0.2794 -0.1778)
						)
						(arc
							(start -0.2794 0.1778)
							(mid -0.249642 0.249642)
							(end -0.1778 0.2794)
						)
						(arc
							(start 0.1778 0.2794)
							(mid 0.249642 0.249642)
							(end 0.2794 0.1778)
						)
						(arc
							(start 0.2794 -0.1778)
							(mid 0.249642 -0.249642)
							(end 0.1778 -0.2794)
						)
					)
					(width 0)
					(fill yes)
				)
			)
		)
	)
	(footprint ""
		(layer "F.Cu")
		(at 14.351 -13.208 -90)
		(property "Reference" "C529"
			(at 0 0 270)
			(layer "F.SilkS")
			(hide yes)
			(effects
				(font
					(size 1.27 1.27)
				)
			)
		)
		(property "Value" "SC1000P2KV6KX-GP-U"
			(at 0.0508 -3.5052 270)
			(unlocked yes)
			(layer "F.Fab")
			(hide yes)
			(effects
				(font
					(size 1.016 1.016)
					(thickness 0.1524)
				)
			)
		)
		(property "Device Type" "C1206H58"
			(at 0.0508 -5.0292 270)
			(unlocked yes)
			(layer "F.Fab")
			(hide yes)
			(effects
				(font
					(size 1.016 1.016)
					(thickness 0.1524)
				)
			)
		)
		(duplicate_pad_numbers_are_jumpers no)
		(fp_line
			(start -1.016 2.2352)
			(end -1.016 0.8128)
			(stroke
				(width 0.1524)
				(type default)
			)
			(layer "F.SilkS")
		)
		(fp_line
			(start 1.016 2.2352)
			(end -1.016 2.2352)
			(stroke
				(width 0.1524)
				(type default)
			)
			(layer "F.SilkS")
		)
		(fp_line
			(start 1.016 0.8382)
			(end 1.016 2.2352)
			(stroke
				(width 0.1524)
				(type default)
			)
			(layer "F.SilkS")
		)
		(fp_line
			(start -1.016 -2.2352)
			(end -1.016 -0.8382)
			(stroke
				(width 0.1524)
				(type default)
			)
			(layer "F.SilkS")
		)
		(fp_line
			(start 1.016 -2.2352)
			(end 1.016 -0.8382)
			(stroke
				(width 0.1524)
				(type default)
			)
			(layer "F.SilkS")
		)
		(fp_line
			(start 1.016 -2.2352)
			(end -1.016 -2.2352)
			(stroke
				(width 0.1524)
				(type default)
			)
			(layer "F.SilkS")
		)
		(fp_rect
			(start -1.0922 2.3114)
			(end 1.0922 -2.3114)
			(stroke
				(width 0)
				(type default)
			)
			(fill no)
			(layer "F.CrtYd")
		)
		(fp_poly
			(pts
				(xy -1.0922 -2.3114) (xy 1.0922 -2.3114) (xy 1.0922 2.3114) (xy -1.0922 2.3114)
			)
			(stroke
				(width 0)
				(type default)
			)
			(fill no)
			(layer "F.Fab")
		)
		(pad "1" smd rect
			(at 0 -1.397 270)
			(size 1.651 1.27)
			(layers "F.Cu" "F.Mask" "F.Paste")
			(net "RST_BTN_GND")
		)
		(pad "2" smd rect
			(at 0 1.397 270)
			(size 1.651 1.27)
			(layers "F.Cu" "F.Mask" "F.Paste")
			(net "GND")
		)
	)
	(footprint ""
		(layer "F.Cu")
		(at 29.755846 -186.56681 180)
		(property "Reference" "C177"
			(at 0 0 180)
			(layer "F.SilkS")
			(hide yes)
			(effects
				(font
					(size 1.27 1.27)
				)
			)
		)
		(property "Value" "SC10U16V5KX-7-GP-U"
			(at -0.0762 -6.1214 180)
			(unlocked yes)
			(layer "F.Fab")
			(hide yes)
			(effects
				(font
					(size 1.016 1.016)
					(thickness 0.1524)
				)
			)
		)
		(property "Device Type" "C805H58"
			(at -0.0762 -8.1534 180)
			(unlocked yes)
			(layer "F.Fab")
			(hide yes)
			(effects
				(font
					(size 1.016 1.016)
					(thickness 0.1524)
				)
			)
		)
		(duplicate_pad_numbers_are_jumpers no)
		(fp_line
			(start 0.635 0)
			(end -0.635 0)
			(stroke
				(width 0.508)
				(type default)
			)
			(layer "F.SilkS")
		)
		(fp_rect
			(start -0.9652 1.778)
			(end 0.9652 -1.778)
			(stroke
				(width 0)
				(type default)
			)
			(fill no)
			(layer "F.CrtYd")
		)
		(fp_poly
			(pts
				(xy -0.9652 -1.778) (xy 0.9652 -1.778) (xy 0.9652 1.778) (xy -0.9652 1.778)
			)
			(stroke
				(width 0)
				(type default)
			)
			(fill no)
			(layer "F.Fab")
		)
		(pad "1" smd rect
			(at 0 -0.9652 180)
			(size 1.397 1.143)
			(layers "F.Cu" "F.Mask" "F.Paste")
			(net "P12V_STBY_VIN_PU2")
		)
		(pad "2" smd rect
			(at 0 0.9652 180)
			(size 1.397 1.143)
			(layers "F.Cu" "F.Mask" "F.Paste")
			(net "GND")
		)
	)
	(footprint ""
		(layer "F.Cu")
		(at 72.4408 -133.9342 90)
		(property "Reference" "R105"
			(at 0 0 90)
			(layer "F.SilkS")
			(hide yes)
			(effects
				(font
					(size 1.27 1.27)
				)
			)
		)
		(property "Value" "4K7R2F-GP"
			(at 0.064008 -3.993896 90)
			(unlocked yes)
			(layer "F.Fab")
			(hide yes)
			(effects
				(font
					(size 1.016 1.016)
					(thickness 0.1524)
				)
			)
		)
		(property "Device Type" "R402H16"
			(at 0.064008 -5.517896 90)
			(unlocked yes)
			(layer "F.Fab")
			(hide yes)
			(effects
				(font
					(size 1.016 1.016)
					(thickness 0.1524)
				)
			)
		)
		(duplicate_pad_numbers_are_jumpers no)
		(fp_line
			(start 0.508 -0.9398)
			(end -0.508 -0.9398)
			(stroke
				(width 0.1524)
				(type default)
			)
			(layer "F.SilkS")
		)
		(fp_line
			(start -0.508 -0.9398)
			(end -0.508 0.9398)
			(stroke
				(width 0.1524)
				(type default)
			)
			(layer "F.SilkS")
		)
		(fp_rect
			(start -0.508 0.9398)
			(end 0.508 -0.9398)
			(stroke
				(width 0)
				(type default)
			)
			(fill no)
			(layer "F.CrtYd")
		)
		(fp_rect
			(start -0.508 0.9398)
			(end 0.508 -0.9398)
			(stroke
				(width 0)
				(type default)
			)
			(fill no)
			(layer "F.Fab")
		)
		(pad "1" smd custom
			(at 0 -0.4445 90)
			(size 0.1397 0.1397)
			(layers "F.Cu" "F.Mask" "F.Paste")
			(net "P3V3_STBY")
			(options
				(clearance outline)
				(anchor circle)
			)
			(primitives
				(gr_poly
					(pts
						(arc
							(start -0.1778 -0.2794)
							(mid -0.249642 -0.249642)
							(end -0.2794 -0.1778)
						)
						(arc
							(start -0.2794 0.1778)
							(mid -0.249642 0.249642)
							(end -0.1778 0.2794)
						)
						(arc
							(start 0.1778 0.2794)
							(mid 0.249642 0.249642)
							(end 0.2794 0.1778)
						)
						(arc
							(start 0.2794 -0.1778)
							(mid 0.249642 -0.249642)
							(end 0.1778 -0.2794)
						)
					)
					(width 0)
					(fill yes)
				)
			)
		)
		(pad "2" smd custom
			(at 0 0.4445 90)
			(size 0.1397 0.1397)
			(layers "F.Cu" "F.Mask" "F.Paste")
			(net "D_FLIP_CLR#")
			(options
				(clearance outline)
				(anchor circle)
			)
			(primitives
				(gr_poly
					(pts
						(arc
							(start -0.1778 -0.2794)
							(mid -0.249642 -0.249642)
							(end -0.2794 -0.1778)
						)
						(arc
							(start -0.2794 0.1778)
							(mid -0.249642 0.249642)
							(end -0.1778 0.2794)
						)
						(arc
							(start 0.1778 0.2794)
							(mid 0.249642 0.249642)
							(end 0.2794 0.1778)
						)
						(arc
							(start 0.2794 -0.1778)
							(mid 0.249642 -0.249642)
							(end 0.1778 -0.2794)
						)
					)
					(width 0)
					(fill yes)
				)
			)
		)
	)
	(footprint ""
		(layer "F.Cu")
		(at 48.216312 -163.566602 90)
		(property "Reference" "R367"
			(at 0 0 90)
			(layer "F.SilkS")
			(hide yes)
			(effects
				(font
					(size 1.27 1.27)
				)
			)
		)
		(property "Value" "18KR2F-5-GP"
			(at 0.064008 -3.993896 90)
			(unlocked yes)
			(layer "F.Fab")
			(hide yes)
			(effects
				(font
					(size 1.016 1.016)
					(thickness 0.1524)
				)
			)
		)
		(property "Device Type" "R402H16"
			(at 0.064008 -5.517896 90)
			(unlocked yes)
			(layer "F.Fab")
			(hide yes)
			(effects
				(font
					(size 1.016 1.016)
					(thickness 0.1524)
				)
			)
		)
		(duplicate_pad_numbers_are_jumpers no)
		(fp_line
			(start 0.508 -0.9398)
			(end -0.508 -0.9398)
			(stroke
				(width 0.1524)
				(type default)
			)
			(layer "F.SilkS")
		)
		(fp_line
			(start -0.508 -0.9398)
			(end -0.508 0.9398)
			(stroke
				(width 0.1524)
				(type default)
			)
			(layer "F.SilkS")
		)
		(fp_rect
			(start -0.508 0.9398)
			(end 0.508 -0.9398)
			(stroke
				(width 0)
				(type default)
			)
			(fill no)
			(layer "F.CrtYd")
		)
		(fp_rect
			(start -0.508 0.9398)
			(end 0.508 -0.9398)
			(stroke
				(width 0)
				(type default)
			)
			(fill no)
			(layer "F.Fab")
		)
		(pad "1" smd custom
			(at 0 -0.4445 90)
			(size 0.1397 0.1397)
			(layers "F.Cu" "F.Mask" "F.Paste")
			(net "GND")
			(options
				(clearance outline)
				(anchor circle)
			)
			(primitives
				(gr_poly
					(pts
						(arc
							(start -0.1778 -0.2794)
							(mid -0.249642 -0.249642)
							(end -0.2794 -0.1778)
						)
						(arc
							(start -0.2794 0.1778)
							(mid -0.249642 0.249642)
							(end -0.1778 0.2794)
						)
						(arc
							(start 0.1778 0.2794)
							(mid 0.249642 0.249642)
							(end 0.2794 0.1778)
						)
						(arc
							(start 0.2794 -0.1778)
							(mid 0.249642 -0.249642)
							(end 0.1778 -0.2794)
						)
					)
					(width 0)
					(fill yes)
				)
			)
		)
		(pad "2" smd custom
			(at 0 0.4445 90)
			(size 0.1397 0.1397)
			(layers "F.Cu" "F.Mask" "F.Paste")
			(net "DACRSET")
			(options
				(clearance outline)
				(anchor circle)
			)
			(primitives
				(gr_poly
					(pts
						(arc
							(start -0.1778 -0.2794)
							(mid -0.249642 -0.249642)
							(end -0.2794 -0.1778)
						)
						(arc
							(start -0.2794 0.1778)
							(mid -0.249642 0.249642)
							(end -0.1778 0.2794)
						)
						(arc
							(start 0.1778 0.2794)
							(mid 0.249642 0.249642)
							(end 0.2794 0.1778)
						)
						(arc
							(start 0.2794 -0.1778)
							(mid 0.249642 -0.249642)
							(end 0.1778 -0.2794)
						)
					)
					(width 0)
					(fill yes)
				)
			)
		)
	)
	(footprint ""
		(layer "F.Cu")
		(at 129.29997 -6.401308)
		(property "Reference" "R455"
			(at 0 0 0)
			(layer "F.SilkS")
			(hide yes)
			(effects
				(font
					(size 1.27 1.27)
				)
			)
		)
		(property "Value" "1MR3J-L-GP"
			(at -0.0254 -2.5146 0)
			(unlocked yes)
			(layer "F.Fab")
			(hide yes)
			(effects
				(font
					(size 1.016 1.016)
					(thickness 0.1524)
				)
			)
		)
		(property "Device Type" "R603H22"
			(at -0.0254 -4.0386 0)
			(unlocked yes)
			(layer "F.Fab")
			(hide yes)
			(effects
				(font
					(size 1.016 1.016)
					(thickness 0.1524)
				)
			)
		)
		(duplicate_pad_numbers_are_jumpers no)
		(fp_line
			(start -0.4826 0)
			(end -0.2032 0)
			(stroke
				(width 0.2032)
				(type default)
			)
			(layer "F.SilkS")
		)
		(fp_line
			(start 0.2032 0)
			(end 0.4826 0)
			(stroke
				(width 0.2032)
				(type default)
			)
			(layer "F.SilkS")
		)
		(fp_rect
			(start -0.5842 1.3335)
			(end 0.5842 -1.3335)
			(stroke
				(width 0)
				(type default)
			)
			(fill no)
			(layer "F.CrtYd")
		)
		(fp_rect
			(start -0.5842 1.3335)
			(end 0.5842 -1.3335)
			(stroke
				(width 0)
				(type default)
			)
			(fill no)
			(layer "F.Fab")
		)
		(pad "1" smd custom
			(at 0 -0.762)
			(size 0.2159 0.2159)
			(layers "F.Cu" "F.Mask" "F.Paste")
			(net "MB0_CM_GATE_R")
			(options
				(clearance outline)
				(anchor circle)
			)
			(primitives
				(gr_poly
					(pts
						(arc
							(start -0.3302 -0.4318)
							(mid -0.402042 -0.402042)
							(end -0.4318 -0.3302)
						)
						(arc
							(start -0.4318 0.3302)
							(mid -0.402042 0.402042)
							(end -0.3302 0.4318)
						)
						(arc
							(start 0.3302 0.4318)
							(mid 0.402042 0.402042)
							(end 0.4318 0.3302)
						)
						(arc
							(start 0.4318 -0.3302)
							(mid 0.402042 -0.402042)
							(end 0.3302 -0.4318)
						)
					)
					(width 0)
					(fill yes)
				)
			)
		)
		(pad "2" smd custom
			(at 0 0.762)
			(size 0.2159 0.2159)
			(layers "F.Cu" "F.Mask" "F.Paste")
			(net "GND")
			(options
				(clearance outline)
				(anchor circle)
			)
			(primitives
				(gr_poly
					(pts
						(arc
							(start -0.3302 -0.4318)
							(mid -0.402042 -0.402042)
							(end -0.4318 -0.3302)
						)
						(arc
							(start -0.4318 0.3302)
							(mid -0.402042 0.402042)
							(end -0.3302 0.4318)
						)
						(arc
							(start 0.3302 0.4318)
							(mid 0.402042 0.402042)
							(end 0.4318 0.3302)
						)
						(arc
							(start 0.4318 -0.3302)
							(mid 0.402042 -0.402042)
							(end 0.3302 -0.4318)
						)
					)
					(width 0)
					(fill yes)
				)
			)
		)
	)
	(footprint ""
		(layer "F.Cu")
		(at 61.3664 -152.654 90)
		(property "Reference" "R340"
			(at 0 0 90)
			(layer "F.SilkS")
			(hide yes)
			(effects
				(font
					(size 1.27 1.27)
				)
			)
		)
		(property "Value" "8K2R2J-3-GP"
			(at 0.064008 -3.993896 90)
			(unlocked yes)
			(layer "F.Fab")
			(hide yes)
			(effects
				(font
					(size 1.016 1.016)
					(thickness 0.1524)
				)
			)
		)
		(property "Device Type" "R402H16"
			(at 0.064008 -5.517896 90)
			(unlocked yes)
			(layer "F.Fab")
			(hide yes)
			(effects
				(font
					(size 1.016 1.016)
					(thickness 0.1524)
				)
			)
		)
		(duplicate_pad_numbers_are_jumpers no)
		(fp_line
			(start 0.508 -0.9398)
			(end -0.508 -0.9398)
			(stroke
				(width 0.1524)
				(type default)
			)
			(layer "F.SilkS")
		)
		(fp_line
			(start -0.508 -0.9398)
			(end -0.508 0.9398)
			(stroke
				(width 0.1524)
				(type default)
			)
			(layer "F.SilkS")
		)
		(fp_rect
			(start -0.508 0.9398)
			(end 0.508 -0.9398)
			(stroke
				(width 0)
				(type default)
			)
			(fill no)
			(layer "F.CrtYd")
		)
		(fp_rect
			(start -0.508 0.9398)
			(end 0.508 -0.9398)
			(stroke
				(width 0)
				(type default)
			)
			(fill no)
			(layer "F.Fab")
		)
		(pad "1" smd custom
			(at 0 -0.4445 90)
			(size 0.1397 0.1397)
			(layers "F.Cu" "F.Mask" "F.Paste")
			(net "PD_USB2BVRES")
			(options
				(clearance outline)
				(anchor circle)
			)
			(primitives
				(gr_poly
					(pts
						(arc
							(start -0.1778 -0.2794)
							(mid -0.249642 -0.249642)
							(end -0.2794 -0.1778)
						)
						(arc
							(start -0.2794 0.1778)
							(mid -0.249642 0.249642)
							(end -0.1778 0.2794)
						)
						(arc
							(start 0.1778 0.2794)
							(mid 0.249642 0.249642)
							(end 0.2794 0.1778)
						)
						(arc
							(start 0.2794 -0.1778)
							(mid 0.249642 -0.249642)
							(end 0.1778 -0.2794)
						)
					)
					(width 0)
					(fill yes)
				)
			)
		)
		(pad "2" smd custom
			(at 0 0.4445 90)
			(size 0.1397 0.1397)
			(layers "F.Cu" "F.Mask" "F.Paste")
			(net "GND")
			(options
				(clearance outline)
				(anchor circle)
			)
			(primitives
				(gr_poly
					(pts
						(arc
							(start -0.1778 -0.2794)
							(mid -0.249642 -0.249642)
							(end -0.2794 -0.1778)
						)
						(arc
							(start -0.2794 0.1778)
							(mid -0.249642 0.249642)
							(end -0.1778 0.2794)
						)
						(arc
							(start 0.1778 0.2794)
							(mid 0.249642 0.249642)
							(end 0.2794 0.1778)
						)
						(arc
							(start 0.2794 -0.1778)
							(mid 0.249642 -0.249642)
							(end 0.1778 -0.2794)
						)
					)
					(width 0)
					(fill yes)
				)
			)
		)
	)
	(footprint ""
		(layer "F.Cu")
		(at 63.5762 -145.669 90)
		(property "Reference" "R182"
			(at 0 0 90)
			(layer "F.SilkS")
			(hide yes)
			(effects
				(font
					(size 1.27 1.27)
				)
			)
		)
		(property "Value" "2K2R2F-GP"
			(at 0.064008 -3.993896 90)
			(unlocked yes)
			(layer "F.Fab")
			(hide yes)
			(effects
				(font
					(size 1.016 1.016)
					(thickness 0.1524)
				)
			)
		)
		(property "Device Type" "R402H16"
			(at 0.064008 -5.517896 90)
			(unlocked yes)
			(layer "F.Fab")
			(hide yes)
			(effects
				(font
					(size 1.016 1.016)
					(thickness 0.1524)
				)
			)
		)
		(duplicate_pad_numbers_are_jumpers no)
		(fp_line
			(start 0.508 -0.9398)
			(end -0.508 -0.9398)
			(stroke
				(width 0.1524)
				(type default)
			)
			(layer "F.SilkS")
		)
		(fp_line
			(start -0.508 -0.9398)
			(end -0.508 0.9398)
			(stroke
				(width 0.1524)
				(type default)
			)
			(layer "F.SilkS")
		)
		(fp_rect
			(start -0.508 0.9398)
			(end 0.508 -0.9398)
			(stroke
				(width 0)
				(type default)
			)
			(fill no)
			(layer "F.CrtYd")
		)
		(fp_rect
			(start -0.508 0.9398)
			(end 0.508 -0.9398)
			(stroke
				(width 0)
				(type default)
			)
			(fill no)
			(layer "F.Fab")
		)
		(pad "1" smd custom
			(at 0 -0.4445 90)
			(size 0.1397 0.1397)
			(layers "F.Cu" "F.Mask" "F.Paste")
			(net "I2C_SCC_SDA_OUT")
			(options
				(clearance outline)
				(anchor circle)
			)
			(primitives
				(gr_poly
					(pts
						(arc
							(start -0.1778 -0.2794)
							(mid -0.249642 -0.249642)
							(end -0.2794 -0.1778)
						)
						(arc
							(start -0.2794 0.1778)
							(mid -0.249642 0.249642)
							(end -0.1778 0.2794)
						)
						(arc
							(start 0.1778 0.2794)
							(mid 0.249642 0.249642)
							(end 0.2794 0.1778)
						)
						(arc
							(start 0.2794 -0.1778)
							(mid 0.249642 -0.249642)
							(end 0.1778 -0.2794)
						)
					)
					(width 0)
					(fill yes)
				)
			)
		)
		(pad "2" smd custom
			(at 0 0.4445 90)
			(size 0.1397 0.1397)
			(layers "F.Cu" "F.Mask" "F.Paste")
			(net "P3V3_STBY")
			(options
				(clearance outline)
				(anchor circle)
			)
			(primitives
				(gr_poly
					(pts
						(arc
							(start -0.1778 -0.2794)
							(mid -0.249642 -0.249642)
							(end -0.2794 -0.1778)
						)
						(arc
							(start -0.2794 0.1778)
							(mid -0.249642 0.249642)
							(end -0.1778 0.2794)
						)
						(arc
							(start 0.1778 0.2794)
							(mid 0.249642 0.249642)
							(end 0.2794 0.1778)
						)
						(arc
							(start 0.2794 -0.1778)
							(mid 0.249642 -0.249642)
							(end 0.1778 -0.2794)
						)
					)
					(width 0)
					(fill yes)
				)
			)
		)
	)
	(footprint ""
		(layer "F.Cu")
		(at 69.62775 -137.444734 90)
		(property "Reference" "R49"
			(at 0 0 90)
			(layer "F.SilkS")
			(hide yes)
			(effects
				(font
					(size 1.27 1.27)
				)
			)
		)
		(property "Value" "10KR2F-2-GP"
			(at 0.064008 -3.993896 90)
			(unlocked yes)
			(layer "F.Fab")
			(hide yes)
			(effects
				(font
					(size 1.016 1.016)
					(thickness 0.1524)
				)
			)
		)
		(property "Device Type" "R402H16"
			(at 0.064008 -5.517896 90)
			(unlocked yes)
			(layer "F.Fab")
			(hide yes)
			(effects
				(font
					(size 1.016 1.016)
					(thickness 0.1524)
				)
			)
		)
		(duplicate_pad_numbers_are_jumpers no)
		(fp_line
			(start 0.508 -0.9398)
			(end -0.508 -0.9398)
			(stroke
				(width 0.1524)
				(type default)
			)
			(layer "F.SilkS")
		)
		(fp_line
			(start -0.508 -0.9398)
			(end -0.508 0.9398)
			(stroke
				(width 0.1524)
				(type default)
			)
			(layer "F.SilkS")
		)
		(fp_rect
			(start -0.508 0.9398)
			(end 0.508 -0.9398)
			(stroke
				(width 0)
				(type default)
			)
			(fill no)
			(layer "F.CrtYd")
		)
		(fp_rect
			(start -0.508 0.9398)
			(end 0.508 -0.9398)
			(stroke
				(width 0)
				(type default)
			)
			(fill no)
			(layer "F.Fab")
		)
		(pad "1" smd custom
			(at 0 -0.4445 90)
			(size 0.1397 0.1397)
			(layers "F.Cu" "F.Mask" "F.Paste")
			(net "P3V3_STBY")
			(options
				(clearance outline)
				(anchor circle)
			)
			(primitives
				(gr_poly
					(pts
						(arc
							(start -0.1778 -0.2794)
							(mid -0.249642 -0.249642)
							(end -0.2794 -0.1778)
						)
						(arc
							(start -0.2794 0.1778)
							(mid -0.249642 0.249642)
							(end -0.1778 0.2794)
						)
						(arc
							(start 0.1778 0.2794)
							(mid 0.249642 0.249642)
							(end 0.2794 0.1778)
						)
						(arc
							(start 0.2794 -0.1778)
							(mid 0.249642 -0.249642)
							(end 0.1778 -0.2794)
						)
					)
					(width 0)
					(fill yes)
				)
			)
		)
		(pad "2" smd custom
			(at 0 0.4445 90)
			(size 0.1397 0.1397)
			(layers "F.Cu" "F.Mask" "F.Paste")
			(net "FP_PWRBTN")
			(options
				(clearance outline)
				(anchor circle)
			)
			(primitives
				(gr_poly
					(pts
						(arc
							(start -0.1778 -0.2794)
							(mid -0.249642 -0.249642)
							(end -0.2794 -0.1778)
						)
						(arc
							(start -0.2794 0.1778)
							(mid -0.249642 0.249642)
							(end -0.1778 0.2794)
						)
						(arc
							(start 0.1778 0.2794)
							(mid 0.249642 0.249642)
							(end 0.2794 0.1778)
						)
						(arc
							(start 0.2794 -0.1778)
							(mid 0.249642 -0.249642)
							(end 0.1778 -0.2794)
						)
					)
					(width 0)
					(fill yes)
				)
			)
		)
	)
	(footprint ""
		(layer "F.Cu")
		(at 93.177106 -142.653766 -90)
		(property "Reference" "U34"
			(at 0 0 270)
			(layer "F.SilkS")
			(hide yes)
			(effects
				(font
					(size 1.27 1.27)
				)
			)
		)
		(property "Value" "TCA9555PWR-GP"
			(at 0 -6.9342 270)
			(unlocked yes)
			(layer "F.Fab")
			(hide yes)
			(effects
				(font
					(size 1.016 1.016)
					(thickness 0.1524)
				)
			)
		)
		(property "Device Type" "TSOIC24H48"
			(at 0 -8.5852 270)
			(unlocked yes)
			(layer "F.Fab")
			(hide yes)
			(effects
				(font
					(size 1.016 1.016)
					(thickness 0.1524)
				)
			)
		)
		(duplicate_pad_numbers_are_jumpers no)
		(fp_line
			(start -4.2291 3.937)
			(end -4.2291 -1.397)
			(stroke
				(width 0.1524)
				(type default)
			)
			(layer "F.SilkS")
		)
		(fp_line
			(start -4.22656 3.81)
			(end -4.2291 1.397)
			(stroke
				(width 0.508)
				(type default)
			)
			(layer "F.SilkS")
		)
		(fp_line
			(start 3.81 1.397)
			(end -4.2291 1.397)
			(stroke
				(width 0.1524)
				(type default)
			)
			(layer "F.SilkS")
		)
		(fp_line
			(start -3.429 0)
			(end -4.2291 0.8001)
			(stroke
				(width 0.1524)
				(type default)
			)
			(layer "F.SilkS")
		)
		(fp_line
			(start -4.2291 -0.8001)
			(end -3.429 0)
			(stroke
				(width 0.1524)
				(type default)
			)
			(layer "F.SilkS")
		)
		(fp_line
			(start -4.2291 -1.397)
			(end 3.81 -1.397)
			(stroke
				(width 0.1524)
				(type default)
			)
			(layer "F.SilkS")
		)
		(fp_line
			(start 3.81 -1.397)
			(end 3.81 1.397)
			(stroke
				(width 0.1524)
				(type default)
			)
			(layer "F.SilkS")
		)
		(fp_poly
			(pts
				(xy -3.90652 -1.8542) (xy 3.90652 -1.8542) (xy 3.90652 1.8542) (xy -3.90652 1.8542)
			)
			(stroke
				(width 0)
				(type default)
			)
			(fill yes)
			(layer "F.SilkS")
		)
		(fp_poly
			(pts
				(xy -4.2164 3.81) (xy 4.2164 3.81) (xy 4.22656 -3.81) (xy -4.2164 -3.81)
			)
			(stroke
				(width 0)
				(type default)
			)
			(fill no)
			(layer "F.CrtYd")
		)
		(fp_poly
			(pts
				(xy -4.22656 -3.81) (xy 4.22656 -3.81) (xy 4.22656 3.81) (xy -4.22656 3.81)
			)
			(stroke
				(width 0)
				(type default)
			)
			(fill no)
			(layer "F.Fab")
		)
		(pad "1" smd rect
			(at -3.57632 2.8194 270)
			(size 0.3556 1.524)
			(layers "F.Cu" "F.Mask" "F.Paste")
			(net "IO_EXP0_RESET#_FLT")
		)
		(pad "2" smd rect
			(at -2.92608 2.8194 270)
			(size 0.3556 1.524)
			(layers "F.Cu" "F.Mask" "F.Paste")
			(net "TCA9555_A1")
		)
		(pad "3" smd rect
			(at -2.27584 2.8194 270)
			(size 0.3556 1.524)
			(layers "F.Cu" "F.Mask" "F.Paste")
			(net "TCA9555_A2")
		)
		(pad "4" smd rect
			(at -1.6256 2.8194 270)
			(size 0.3556 1.524)
			(layers "F.Cu" "F.Mask" "F.Paste")
			(net "LED_POSTCODE_0")
		)
		(pad "5" smd rect
			(at -0.97536 2.8194 270)
			(size 0.3556 1.524)
			(layers "F.Cu" "F.Mask" "F.Paste")
			(net "LED_POSTCODE_1")
		)
		(pad "6" smd rect
			(at -0.32512 2.8194 270)
			(size 0.3556 1.524)
			(layers "F.Cu" "F.Mask" "F.Paste")
			(net "LED_POSTCODE_2")
		)
		(pad "7" smd rect
			(at 0.32512 2.8194 270)
			(size 0.3556 1.524)
			(layers "F.Cu" "F.Mask" "F.Paste")
			(net "LED_POSTCODE_3")
		)
		(pad "8" smd rect
			(at 0.97536 2.8194 270)
			(size 0.3556 1.524)
			(layers "F.Cu" "F.Mask" "F.Paste")
			(net "LED_POSTCODE_4")
		)
		(pad "9" smd rect
			(at 1.6256 2.8194 270)
			(size 0.3556 1.524)
			(layers "F.Cu" "F.Mask" "F.Paste")
			(net "LED_POSTCODE_5")
		)
		(pad "10" smd rect
			(at 2.27584 2.8194 270)
			(size 0.3556 1.524)
			(layers "F.Cu" "F.Mask" "F.Paste")
			(net "LED_POSTCODE_6")
		)
		(pad "11" smd rect
			(at 2.92608 2.8194 270)
			(size 0.3556 1.524)
			(layers "F.Cu" "F.Mask" "F.Paste")
			(net "LED_POSTCODE_7")
		)
		(pad "12" smd rect
			(at 3.57632 2.8194 270)
			(size 0.3556 1.524)
			(layers "F.Cu" "F.Mask" "F.Paste")
			(net "GND")
		)
		(pad "13" smd rect
			(at 3.57632 -2.8194 270)
			(size 0.3556 1.524)
			(layers "F.Cu" "F.Mask" "F.Paste")
			(net "DEBUG_RST_BTN_N")
		)
		(pad "14" smd rect
			(at 2.92608 -2.8194 270)
			(size 0.3556 1.524)
			(layers "F.Cu" "F.Mask" "F.Paste")
			(net "DEBUG_GPIO_BMC_1")
		)
		(pad "15" smd rect
			(at 2.27584 -2.8194 270)
			(size 0.3556 1.524)
			(layers "F.Cu" "F.Mask" "F.Paste")
			(net "DEBUG_GPIO_BMC_2")
		)
		(pad "16" smd rect
			(at 1.6256 -2.8194 270)
			(size 0.3556 1.524)
			(layers "F.Cu" "F.Mask" "F.Paste")
			(net "DEBUG_GPIO_BMC_3")
		)
		(pad "17" smd rect
			(at 0.97536 -2.8194 270)
			(size 0.3556 1.524)
			(layers "F.Cu" "F.Mask" "F.Paste")
			(net "DEBUG_GPIO_BMC_4")
		)
		(pad "18" smd rect
			(at 0.32512 -2.8194 270)
			(size 0.3556 1.524)
			(layers "F.Cu" "F.Mask" "F.Paste")
			(net "DEBUG_GPIO_BMC_5")
		)
		(pad "19" smd rect
			(at -0.32512 -2.8194 270)
			(size 0.3556 1.524)
			(layers "F.Cu" "F.Mask" "F.Paste")
			(net "DEBUG_GPIO_BMC_6")
		)
		(pad "20" smd rect
			(at -0.97536 -2.8194 270)
			(size 0.3556 1.524)
			(layers "F.Cu" "F.Mask" "F.Paste")
			(net "DEBUG_HDR_UART_SEL")
		)
		(pad "21" smd rect
			(at -1.6256 -2.8194 270)
			(size 0.3556 1.524)
			(layers "F.Cu" "F.Mask" "F.Paste")
			(net "TCA9555_A0")
		)
		(pad "22" smd rect
			(at -2.27584 -2.8194 270)
			(size 0.3556 1.524)
			(layers "F.Cu" "F.Mask" "F.Paste")
			(net "I2C_DEBUG_SCL_R")
		)
		(pad "23" smd rect
			(at -2.92608 -2.8194 270)
			(size 0.3556 1.524)
			(layers "F.Cu" "F.Mask" "F.Paste")
			(net "I2C_DEBUG_SDA_R")
		)
		(pad "24" smd rect
			(at -3.57632 -2.8194 270)
			(size 0.3556 1.524)
			(layers "F.Cu" "F.Mask" "F.Paste")
			(net "P3V3_STBY")
		)
	)
	(footprint ""
		(layer "F.Cu")
		(at 98.425 -135.4836 90)
		(property "Reference" "R139"
			(at 0 0 90)
			(layer "F.SilkS")
			(hide yes)
			(effects
				(font
					(size 1.27 1.27)
				)
			)
		)
		(property "Value" "8K2R2J-3-GP"
			(at 0.064008 -3.993896 90)
			(unlocked yes)
			(layer "F.Fab")
			(hide yes)
			(effects
				(font
					(size 1.016 1.016)
					(thickness 0.1524)
				)
			)
		)
		(property "Device Type" "R402H16"
			(at 0.064008 -5.517896 90)
			(unlocked yes)
			(layer "F.Fab")
			(hide yes)
			(effects
				(font
					(size 1.016 1.016)
					(thickness 0.1524)
				)
			)
		)
		(duplicate_pad_numbers_are_jumpers no)
		(fp_line
			(start 0.508 -0.9398)
			(end -0.508 -0.9398)
			(stroke
				(width 0.1524)
				(type default)
			)
			(layer "F.SilkS")
		)
		(fp_line
			(start -0.508 -0.9398)
			(end -0.508 0.9398)
			(stroke
				(width 0.1524)
				(type default)
			)
			(layer "F.SilkS")
		)
		(fp_rect
			(start -0.508 0.9398)
			(end 0.508 -0.9398)
			(stroke
				(width 0)
				(type default)
			)
			(fill no)
			(layer "F.CrtYd")
		)
		(fp_rect
			(start -0.508 0.9398)
			(end 0.508 -0.9398)
			(stroke
				(width 0)
				(type default)
			)
			(fill no)
			(layer "F.Fab")
		)
		(pad "1" smd custom
			(at 0 -0.4445 90)
			(size 0.1397 0.1397)
			(layers "F.Cu" "F.Mask" "F.Paste")
			(net "EEPROM_WP")
			(options
				(clearance outline)
				(anchor circle)
			)
			(primitives
				(gr_poly
					(pts
						(arc
							(start -0.1778 -0.2794)
							(mid -0.249642 -0.249642)
							(end -0.2794 -0.1778)
						)
						(arc
							(start -0.2794 0.1778)
							(mid -0.249642 0.249642)
							(end -0.1778 0.2794)
						)
						(arc
							(start 0.1778 0.2794)
							(mid 0.249642 0.249642)
							(end 0.2794 0.1778)
						)
						(arc
							(start 0.2794 -0.1778)
							(mid 0.249642 -0.249642)
							(end 0.1778 -0.2794)
						)
					)
					(width 0)
					(fill yes)
				)
			)
		)
		(pad "2" smd custom
			(at 0 0.4445 90)
			(size 0.1397 0.1397)
			(layers "F.Cu" "F.Mask" "F.Paste")
			(net "GND")
			(options
				(clearance outline)
				(anchor circle)
			)
			(primitives
				(gr_poly
					(pts
						(arc
							(start -0.1778 -0.2794)
							(mid -0.249642 -0.249642)
							(end -0.2794 -0.1778)
						)
						(arc
							(start -0.2794 0.1778)
							(mid -0.249642 0.249642)
							(end -0.1778 0.2794)
						)
						(arc
							(start 0.1778 0.2794)
							(mid 0.249642 0.249642)
							(end 0.2794 0.1778)
						)
						(arc
							(start 0.2794 -0.1778)
							(mid 0.249642 -0.249642)
							(end 0.1778 -0.2794)
						)
					)
					(width 0)
					(fill yes)
				)
			)
		)
	)
	(footprint ""
		(layer "F.Cu")
		(at 8.904732 -138.145774 90)
		(property "Reference" "R229"
			(at 0 0 90)
			(layer "F.SilkS")
			(hide yes)
			(effects
				(font
					(size 1.27 1.27)
				)
			)
		)
		(property "Value" "120R2F-GP"
			(at 0.064008 -3.993896 90)
			(unlocked yes)
			(layer "F.Fab")
			(hide yes)
			(effects
				(font
					(size 1.016 1.016)
					(thickness 0.1524)
				)
			)
		)
		(property "Device Type" "R402H16"
			(at 0.064008 -5.517896 90)
			(unlocked yes)
			(layer "F.Fab")
			(hide yes)
			(effects
				(font
					(size 1.016 1.016)
					(thickness 0.1524)
				)
			)
		)
		(duplicate_pad_numbers_are_jumpers no)
		(fp_line
			(start 0.508 -0.9398)
			(end -0.508 -0.9398)
			(stroke
				(width 0.1524)
				(type default)
			)
			(layer "F.SilkS")
		)
		(fp_line
			(start -0.508 -0.9398)
			(end -0.508 0.9398)
			(stroke
				(width 0.1524)
				(type default)
			)
			(layer "F.SilkS")
		)
		(fp_rect
			(start -0.508 0.9398)
			(end 0.508 -0.9398)
			(stroke
				(width 0)
				(type default)
			)
			(fill no)
			(layer "F.CrtYd")
		)
		(fp_rect
			(start -0.508 0.9398)
			(end 0.508 -0.9398)
			(stroke
				(width 0)
				(type default)
			)
			(fill no)
			(layer "F.Fab")
		)
		(pad "1" smd custom
			(at 0 -0.4445 90)
			(size 0.1397 0.1397)
			(layers "F.Cu" "F.Mask" "F.Paste")
			(net "GND")
			(options
				(clearance outline)
				(anchor circle)
			)
			(primitives
				(gr_poly
					(pts
						(arc
							(start -0.1778 -0.2794)
							(mid -0.249642 -0.249642)
							(end -0.2794 -0.1778)
						)
						(arc
							(start -0.2794 0.1778)
							(mid -0.249642 0.249642)
							(end -0.1778 0.2794)
						)
						(arc
							(start 0.1778 0.2794)
							(mid 0.249642 0.249642)
							(end 0.2794 0.1778)
						)
						(arc
							(start 0.2794 -0.1778)
							(mid 0.249642 -0.249642)
							(end 0.1778 -0.2794)
						)
					)
					(width 0)
					(fill yes)
				)
			)
		)
		(pad "2" smd custom
			(at 0 0.4445 90)
			(size 0.1397 0.1397)
			(layers "F.Cu" "F.Mask" "F.Paste")
			(net "MEMBA_0")
			(options
				(clearance outline)
				(anchor circle)
			)
			(primitives
				(gr_poly
					(pts
						(arc
							(start -0.1778 -0.2794)
							(mid -0.249642 -0.249642)
							(end -0.2794 -0.1778)
						)
						(arc
							(start -0.2794 0.1778)
							(mid -0.249642 0.249642)
							(end -0.1778 0.2794)
						)
						(arc
							(start 0.1778 0.2794)
							(mid 0.249642 0.249642)
							(end 0.2794 0.1778)
						)
						(arc
							(start 0.2794 -0.1778)
							(mid 0.249642 -0.249642)
							(end 0.1778 -0.2794)
						)
					)
					(width 0)
					(fill yes)
				)
			)
		)
	)
	(footprint ""
		(layer "F.Cu")
		(at 68.5038 -119.4562 -90)
		(property "Reference" "R266"
			(at 0 0 270)
			(layer "F.SilkS")
			(hide yes)
			(effects
				(font
					(size 1.27 1.27)
				)
			)
		)
		(property "Value" "2K2R2J-2-GP"
			(at 0.064008 -3.993896 270)
			(unlocked yes)
			(layer "F.Fab")
			(hide yes)
			(effects
				(font
					(size 1.016 1.016)
					(thickness 0.1524)
				)
			)
		)
		(property "Device Type" "R402H16"
			(at 0.064008 -5.517896 270)
			(unlocked yes)
			(layer "F.Fab")
			(hide yes)
			(effects
				(font
					(size 1.016 1.016)
					(thickness 0.1524)
				)
			)
		)
		(duplicate_pad_numbers_are_jumpers no)
		(fp_line
			(start -0.508 -0.9398)
			(end -0.508 0.9398)
			(stroke
				(width 0.1524)
				(type default)
			)
			(layer "F.SilkS")
		)
		(fp_line
			(start 0.508 -0.9398)
			(end -0.508 -0.9398)
			(stroke
				(width 0.1524)
				(type default)
			)
			(layer "F.SilkS")
		)
		(fp_rect
			(start -0.508 0.9398)
			(end 0.508 -0.9398)
			(stroke
				(width 0)
				(type default)
			)
			(fill no)
			(layer "F.CrtYd")
		)
		(fp_rect
			(start -0.508 0.9398)
			(end 0.508 -0.9398)
			(stroke
				(width 0)
				(type default)
			)
			(fill no)
			(layer "F.Fab")
		)
		(pad "1" smd custom
			(at 0 -0.4445 270)
			(size 0.1397 0.1397)
			(layers "F.Cu" "F.Mask" "F.Paste")
			(net "P3V3_STBY")
			(options
				(clearance outline)
				(anchor circle)
			)
			(primitives
				(gr_poly
					(pts
						(arc
							(start -0.1778 -0.2794)
							(mid -0.249642 -0.249642)
							(end -0.2794 -0.1778)
						)
						(arc
							(start -0.2794 0.1778)
							(mid -0.249642 0.249642)
							(end -0.1778 0.2794)
						)
						(arc
							(start 0.1778 0.2794)
							(mid 0.249642 0.249642)
							(end 0.2794 0.1778)
						)
						(arc
							(start 0.2794 -0.1778)
							(mid 0.249642 -0.249642)
							(end 0.1778 -0.2794)
						)
					)
					(width 0)
					(fill yes)
				)
			)
		)
		(pad "2" smd custom
			(at 0 0.4445 270)
			(size 0.1397 0.1397)
			(layers "F.Cu" "F.Mask" "F.Paste")
			(net "FLA1_SPI_RST")
			(options
				(clearance outline)
				(anchor circle)
			)
			(primitives
				(gr_poly
					(pts
						(arc
							(start -0.1778 -0.2794)
							(mid -0.249642 -0.249642)
							(end -0.2794 -0.1778)
						)
						(arc
							(start -0.2794 0.1778)
							(mid -0.249642 0.249642)
							(end -0.1778 0.2794)
						)
						(arc
							(start 0.1778 0.2794)
							(mid 0.249642 0.249642)
							(end 0.2794 0.1778)
						)
						(arc
							(start 0.2794 -0.1778)
							(mid 0.249642 -0.249642)
							(end 0.1778 -0.2794)
						)
					)
					(width 0)
					(fill yes)
				)
			)
		)
	)
	(footprint ""
		(layer "F.Cu")
		(at 31.75 -152.146 90)
		(property "Reference" "R701"
			(at 0 0 90)
			(layer "F.SilkS")
			(hide yes)
			(effects
				(font
					(size 1.27 1.27)
				)
			)
		)
		(property "Value" "4K7R2F-GP"
			(at 0.064008 -3.993896 90)
			(unlocked yes)
			(layer "F.Fab")
			(hide yes)
			(effects
				(font
					(size 1.016 1.016)
					(thickness 0.1524)
				)
			)
		)
		(property "Device Type" "R402H16"
			(at 0.064008 -5.517896 90)
			(unlocked yes)
			(layer "F.Fab")
			(hide yes)
			(effects
				(font
					(size 1.016 1.016)
					(thickness 0.1524)
				)
			)
		)
		(duplicate_pad_numbers_are_jumpers no)
		(fp_line
			(start 0.508 -0.9398)
			(end -0.508 -0.9398)
			(stroke
				(width 0.1524)
				(type default)
			)
			(layer "F.SilkS")
		)
		(fp_line
			(start -0.508 -0.9398)
			(end -0.508 0.9398)
			(stroke
				(width 0.1524)
				(type default)
			)
			(layer "F.SilkS")
		)
		(fp_rect
			(start -0.508 0.9398)
			(end 0.508 -0.9398)
			(stroke
				(width 0)
				(type default)
			)
			(fill no)
			(layer "F.CrtYd")
		)
		(fp_rect
			(start -0.508 0.9398)
			(end 0.508 -0.9398)
			(stroke
				(width 0)
				(type default)
			)
			(fill no)
			(layer "F.Fab")
		)
		(pad "1" smd custom
			(at 0 -0.4445 90)
			(size 0.1397 0.1397)
			(layers "F.Cu" "F.Mask" "F.Paste")
			(net "P3V3_STBY")
			(options
				(clearance outline)
				(anchor circle)
			)
			(primitives
				(gr_poly
					(pts
						(arc
							(start -0.1778 -0.2794)
							(mid -0.249642 -0.249642)
							(end -0.2794 -0.1778)
						)
						(arc
							(start -0.2794 0.1778)
							(mid -0.249642 0.249642)
							(end -0.1778 0.2794)
						)
						(arc
							(start 0.1778 0.2794)
							(mid 0.249642 0.249642)
							(end 0.2794 0.1778)
						)
						(arc
							(start 0.2794 -0.1778)
							(mid 0.249642 -0.249642)
							(end 0.1778 -0.2794)
						)
					)
					(width 0)
					(fill yes)
				)
			)
		)
		(pad "2" smd custom
			(at 0 0.4445 90)
			(size 0.1397 0.1397)
			(layers "F.Cu" "F.Mask" "F.Paste")
			(net "COMP_FAST_THROTTLE_N")
			(options
				(clearance outline)
				(anchor circle)
			)
			(primitives
				(gr_poly
					(pts
						(arc
							(start -0.1778 -0.2794)
							(mid -0.249642 -0.249642)
							(end -0.2794 -0.1778)
						)
						(arc
							(start -0.2794 0.1778)
							(mid -0.249642 0.249642)
							(end -0.1778 0.2794)
						)
						(arc
							(start 0.1778 0.2794)
							(mid 0.249642 0.249642)
							(end 0.2794 0.1778)
						)
						(arc
							(start 0.2794 -0.1778)
							(mid 0.249642 -0.249642)
							(end 0.1778 -0.2794)
						)
					)
					(width 0)
					(fill yes)
				)
			)
		)
	)
	(footprint ""
		(layer "F.Cu")
		(at 112.87379 -6.643878 -90)
		(property "Reference" "R460"
			(at 0 0 270)
			(layer "F.SilkS")
			(hide yes)
			(effects
				(font
					(size 1.27 1.27)
				)
			)
		)
		(property "Value" "0R2J-2-GP"
			(at 0.064008 -3.993896 270)
			(unlocked yes)
			(layer "F.Fab")
			(hide yes)
			(effects
				(font
					(size 1.016 1.016)
					(thickness 0.1524)
				)
			)
		)
		(property "Device Type" "R402H16"
			(at 0.064008 -5.517896 270)
			(unlocked yes)
			(layer "F.Fab")
			(hide yes)
			(effects
				(font
					(size 1.016 1.016)
					(thickness 0.1524)
				)
			)
		)
		(duplicate_pad_numbers_are_jumpers no)
		(fp_line
			(start -0.508 -0.9398)
			(end -0.508 0.9398)
			(stroke
				(width 0.1524)
				(type default)
			)
			(layer "F.SilkS")
		)
		(fp_line
			(start 0.508 -0.9398)
			(end -0.508 -0.9398)
			(stroke
				(width 0.1524)
				(type default)
			)
			(layer "F.SilkS")
		)
		(fp_rect
			(start -0.508 0.9398)
			(end 0.508 -0.9398)
			(stroke
				(width 0)
				(type default)
			)
			(fill no)
			(layer "F.CrtYd")
		)
		(fp_rect
			(start -0.508 0.9398)
			(end 0.508 -0.9398)
			(stroke
				(width 0)
				(type default)
			)
			(fill no)
			(layer "F.Fab")
		)
		(pad "1" smd custom
			(at 0 -0.4445 270)
			(size 0.1397 0.1397)
			(layers "F.Cu" "F.Mask" "F.Paste")
			(net "MB0_CM_ADR2_R")
			(options
				(clearance outline)
				(anchor circle)
			)
			(primitives
				(gr_poly
					(pts
						(arc
							(start -0.1778 -0.2794)
							(mid -0.249642 -0.249642)
							(end -0.2794 -0.1778)
						)
						(arc
							(start -0.2794 0.1778)
							(mid -0.249642 0.249642)
							(end -0.1778 0.2794)
						)
						(arc
							(start 0.1778 0.2794)
							(mid 0.249642 0.249642)
							(end 0.2794 0.1778)
						)
						(arc
							(start 0.2794 -0.1778)
							(mid 0.249642 -0.249642)
							(end 0.1778 -0.2794)
						)
					)
					(width 0)
					(fill yes)
				)
			)
		)
		(pad "2" smd custom
			(at 0 0.4445 270)
			(size 0.1397 0.1397)
			(layers "F.Cu" "F.Mask" "F.Paste")
			(net "AGND_CURRENT_MON")
			(options
				(clearance outline)
				(anchor circle)
			)
			(primitives
				(gr_poly
					(pts
						(arc
							(start -0.1778 -0.2794)
							(mid -0.249642 -0.249642)
							(end -0.2794 -0.1778)
						)
						(arc
							(start -0.2794 0.1778)
							(mid -0.249642 0.249642)
							(end -0.1778 0.2794)
						)
						(arc
							(start 0.1778 0.2794)
							(mid 0.249642 0.249642)
							(end 0.2794 0.1778)
						)
						(arc
							(start 0.2794 -0.1778)
							(mid 0.249642 -0.249642)
							(end 0.1778 -0.2794)
						)
					)
					(width 0)
					(fill yes)
				)
			)
		)
	)
	(footprint ""
		(layer "F.Cu")
		(at 79.231744 -153.745184 180)
		(property "Reference" "R536"
			(at 0 0 180)
			(layer "F.SilkS")
			(hide yes)
			(effects
				(font
					(size 1.27 1.27)
				)
			)
		)
		(property "Value" "0R5J-5-GP"
			(at 0 -8.9535 180)
			(unlocked yes)
			(layer "F.Fab")
			(hide yes)
			(effects
				(font
					(size 1.27 1.016)
					(thickness 0.1524)
				)
			)
		)
		(property "Device Type" "R805H24"
			(at 0 -10.6299 180)
			(unlocked yes)
			(layer "F.Fab")
			(hide yes)
			(effects
				(font
					(size 1.27 1.016)
					(thickness 0.1524)
				)
			)
		)
		(duplicate_pad_numbers_are_jumpers no)
		(fp_line
			(start 0.889 1.7018)
			(end 0.889 -0.508)
			(stroke
				(width 0.1524)
				(type default)
			)
			(layer "F.SilkS")
		)
		(fp_line
			(start 0.889 -1.7018)
			(end 0.889 -0.381)
			(stroke
				(width 0.1524)
				(type default)
			)
			(layer "F.SilkS")
		)
		(fp_line
			(start 0.889 -1.7018)
			(end -0.889 -1.7018)
			(stroke
				(width 0.1524)
				(type default)
			)
			(layer "F.SilkS")
		)
		(fp_line
			(start -0.889 1.7018)
			(end 0.889 1.7018)
			(stroke
				(width 0.1524)
				(type default)
			)
			(layer "F.SilkS")
		)
		(fp_line
			(start -0.889 0.0762)
			(end -0.889 1.7018)
			(stroke
				(width 0.1524)
				(type default)
			)
			(layer "F.SilkS")
		)
		(fp_line
			(start -0.889 -1.7018)
			(end -0.889 0.2794)
			(stroke
				(width 0.1524)
				(type default)
			)
			(layer "F.SilkS")
		)
		(fp_poly
			(pts
				(xy 0.9652 -1.778) (xy 0.9652 1.778) (xy -0.9652 1.778) (xy -0.9652 -1.778)
			)
			(stroke
				(width 0)
				(type default)
			)
			(fill no)
			(layer "F.CrtYd")
		)
		(fp_rect
			(start -0.9652 1.778)
			(end 0.9652 -1.778)
			(stroke
				(width 0)
				(type default)
			)
			(fill no)
			(layer "F.Fab")
		)
		(pad "1" smd rect
			(at 0 -0.9652 180)
			(size 1.397 1.143)
			(layers "F.Cu" "F.Mask" "F.Paste")
			(net "P1V15_STBY")
		)
		(pad "2" smd rect
			(at 0 0.9652 180)
			(size 1.397 1.143)
			(layers "F.Cu" "F.Mask" "F.Paste")
			(net "TPS74801_P1V15_STBY_OUT")
		)
	)
	(footprint ""
		(layer "F.Cu")
		(at 25.6794 -130.4544 180)
		(property "Reference" "R231"
			(at 0 0 180)
			(layer "F.SilkS")
			(hide yes)
			(effects
				(font
					(size 1.27 1.27)
				)
			)
		)
		(property "Value" "120R2F-GP"
			(at 0.064008 -3.993896 180)
			(unlocked yes)
			(layer "F.Fab")
			(hide yes)
			(effects
				(font
					(size 1.016 1.016)
					(thickness 0.1524)
				)
			)
		)
		(property "Device Type" "R402H16"
			(at 0.064008 -5.517896 180)
			(unlocked yes)
			(layer "F.Fab")
			(hide yes)
			(effects
				(font
					(size 1.016 1.016)
					(thickness 0.1524)
				)
			)
		)
		(duplicate_pad_numbers_are_jumpers no)
		(fp_line
			(start 0.508 -0.9398)
			(end -0.508 -0.9398)
			(stroke
				(width 0.1524)
				(type default)
			)
			(layer "F.SilkS")
		)
		(fp_line
			(start -0.508 -0.9398)
			(end -0.508 0.9398)
			(stroke
				(width 0.1524)
				(type default)
			)
			(layer "F.SilkS")
		)
		(fp_rect
			(start -0.508 0.9398)
			(end 0.508 -0.9398)
			(stroke
				(width 0)
				(type default)
			)
			(fill no)
			(layer "F.CrtYd")
		)
		(fp_rect
			(start -0.508 0.9398)
			(end 0.508 -0.9398)
			(stroke
				(width 0)
				(type default)
			)
			(fill no)
			(layer "F.Fab")
		)
		(pad "1" smd custom
			(at 0 -0.4445 180)
			(size 0.1397 0.1397)
			(layers "F.Cu" "F.Mask" "F.Paste")
			(net "GND")
			(options
				(clearance outline)
				(anchor circle)
			)
			(primitives
				(gr_poly
					(pts
						(arc
							(start -0.1778 -0.2794)
							(mid -0.249642 -0.249642)
							(end -0.2794 -0.1778)
						)
						(arc
							(start -0.2794 0.1778)
							(mid -0.249642 0.249642)
							(end -0.1778 0.2794)
						)
						(arc
							(start 0.1778 0.2794)
							(mid 0.249642 0.249642)
							(end 0.2794 0.1778)
						)
						(arc
							(start 0.2794 -0.1778)
							(mid 0.249642 -0.249642)
							(end 0.1778 -0.2794)
						)
					)
					(width 0)
					(fill yes)
				)
			)
		)
		(pad "2" smd custom
			(at 0 0.4445 180)
			(size 0.1397 0.1397)
			(layers "F.Cu" "F.Mask" "F.Paste")
			(net "MEMBA_1")
			(options
				(clearance outline)
				(anchor circle)
			)
			(primitives
				(gr_poly
					(pts
						(arc
							(start -0.1778 -0.2794)
							(mid -0.249642 -0.249642)
							(end -0.2794 -0.1778)
						)
						(arc
							(start -0.2794 0.1778)
							(mid -0.249642 0.249642)
							(end -0.1778 0.2794)
						)
						(arc
							(start 0.1778 0.2794)
							(mid 0.249642 0.249642)
							(end 0.2794 0.1778)
						)
						(arc
							(start 0.2794 -0.1778)
							(mid 0.249642 -0.249642)
							(end 0.1778 -0.2794)
						)
					)
					(width 0)
					(fill yes)
				)
			)
		)
	)
	(footprint ""
		(layer "F.Cu")
		(at 74.426572 -173.774862 -90)
		(property "Reference" "R505"
			(at 0 0 270)
			(layer "F.SilkS")
			(hide yes)
			(effects
				(font
					(size 1.27 1.27)
				)
			)
		)
		(property "Value" "3K57R2F-GP"
			(at 0.064008 -3.993896 270)
			(unlocked yes)
			(layer "F.Fab")
			(hide yes)
			(effects
				(font
					(size 1.016 1.016)
					(thickness 0.1524)
				)
			)
		)
		(property "Device Type" "R402H16"
			(at 0.064008 -5.517896 270)
			(unlocked yes)
			(layer "F.Fab")
			(hide yes)
			(effects
				(font
					(size 1.016 1.016)
					(thickness 0.1524)
				)
			)
		)
		(duplicate_pad_numbers_are_jumpers no)
		(fp_line
			(start -0.508 -0.9398)
			(end -0.508 0.9398)
			(stroke
				(width 0.1524)
				(type default)
			)
			(layer "F.SilkS")
		)
		(fp_line
			(start 0.508 -0.9398)
			(end -0.508 -0.9398)
			(stroke
				(width 0.1524)
				(type default)
			)
			(layer "F.SilkS")
		)
		(fp_rect
			(start -0.508 0.9398)
			(end 0.508 -0.9398)
			(stroke
				(width 0)
				(type default)
			)
			(fill no)
			(layer "F.CrtYd")
		)
		(fp_rect
			(start -0.508 0.9398)
			(end 0.508 -0.9398)
			(stroke
				(width 0)
				(type default)
			)
			(fill no)
			(layer "F.Fab")
		)
		(pad "1" smd custom
			(at 0 -0.4445 270)
			(size 0.1397 0.1397)
			(layers "F.Cu" "F.Mask" "F.Paste")
			(net "TPS74801_P2V5_STBY_OUT")
			(options
				(clearance outline)
				(anchor circle)
			)
			(primitives
				(gr_poly
					(pts
						(arc
							(start -0.1778 -0.2794)
							(mid -0.249642 -0.249642)
							(end -0.2794 -0.1778)
						)
						(arc
							(start -0.2794 0.1778)
							(mid -0.249642 0.249642)
							(end -0.1778 0.2794)
						)
						(arc
							(start 0.1778 0.2794)
							(mid 0.249642 0.249642)
							(end 0.2794 0.1778)
						)
						(arc
							(start 0.2794 -0.1778)
							(mid 0.249642 -0.249642)
							(end 0.1778 -0.2794)
						)
					)
					(width 0)
					(fill yes)
				)
			)
		)
		(pad "2" smd custom
			(at 0 0.4445 270)
			(size 0.1397 0.1397)
			(layers "F.Cu" "F.Mask" "F.Paste")
			(net "TPS74801_P2V5_STBY_FB")
			(options
				(clearance outline)
				(anchor circle)
			)
			(primitives
				(gr_poly
					(pts
						(arc
							(start -0.1778 -0.2794)
							(mid -0.249642 -0.249642)
							(end -0.2794 -0.1778)
						)
						(arc
							(start -0.2794 0.1778)
							(mid -0.249642 0.249642)
							(end -0.1778 0.2794)
						)
						(arc
							(start 0.1778 0.2794)
							(mid 0.249642 0.249642)
							(end 0.2794 0.1778)
						)
						(arc
							(start 0.2794 -0.1778)
							(mid 0.249642 -0.249642)
							(end 0.1778 -0.2794)
						)
					)
					(width 0)
					(fill yes)
				)
			)
		)
	)
	(footprint ""
		(layer "F.Cu")
		(at 98.3234 -173.7106 -90)
		(property "Reference" "R124"
			(at 0 0 270)
			(layer "F.SilkS")
			(hide yes)
			(effects
				(font
					(size 1.27 1.27)
				)
			)
		)
		(property "Value" "0R2J-2-GP"
			(at 0.064008 -3.993896 270)
			(unlocked yes)
			(layer "F.Fab")
			(hide yes)
			(effects
				(font
					(size 1.016 1.016)
					(thickness 0.1524)
				)
			)
		)
		(property "Device Type" "R402H16"
			(at 0.064008 -5.517896 270)
			(unlocked yes)
			(layer "F.Fab")
			(hide yes)
			(effects
				(font
					(size 1.016 1.016)
					(thickness 0.1524)
				)
			)
		)
		(duplicate_pad_numbers_are_jumpers no)
		(fp_line
			(start -0.508 -0.9398)
			(end -0.508 0.9398)
			(stroke
				(width 0.1524)
				(type default)
			)
			(layer "F.SilkS")
		)
		(fp_line
			(start 0.508 -0.9398)
			(end -0.508 -0.9398)
			(stroke
				(width 0.1524)
				(type default)
			)
			(layer "F.SilkS")
		)
		(fp_rect
			(start -0.508 0.9398)
			(end 0.508 -0.9398)
			(stroke
				(width 0)
				(type default)
			)
			(fill no)
			(layer "F.CrtYd")
		)
		(fp_rect
			(start -0.508 0.9398)
			(end 0.508 -0.9398)
			(stroke
				(width 0)
				(type default)
			)
			(fill no)
			(layer "F.Fab")
		)
		(pad "1" smd custom
			(at 0 -0.4445 270)
			(size 0.1397 0.1397)
			(layers "F.Cu" "F.Mask" "F.Paste")
			(net "I2C_DPB_MISC_SCL")
			(options
				(clearance outline)
				(anchor circle)
			)
			(primitives
				(gr_poly
					(pts
						(arc
							(start -0.1778 -0.2794)
							(mid -0.249642 -0.249642)
							(end -0.2794 -0.1778)
						)
						(arc
							(start -0.2794 0.1778)
							(mid -0.249642 0.249642)
							(end -0.1778 0.2794)
						)
						(arc
							(start 0.1778 0.2794)
							(mid 0.249642 0.249642)
							(end 0.2794 0.1778)
						)
						(arc
							(start 0.2794 -0.1778)
							(mid 0.249642 -0.249642)
							(end 0.1778 -0.2794)
						)
					)
					(width 0)
					(fill yes)
				)
			)
		)
		(pad "2" smd custom
			(at 0 0.4445 270)
			(size 0.1397 0.1397)
			(layers "F.Cu" "F.Mask" "F.Paste")
			(net "I2C_DPB_MISC_SCL_R")
			(options
				(clearance outline)
				(anchor circle)
			)
			(primitives
				(gr_poly
					(pts
						(arc
							(start -0.1778 -0.2794)
							(mid -0.249642 -0.249642)
							(end -0.2794 -0.1778)
						)
						(arc
							(start -0.2794 0.1778)
							(mid -0.249642 0.249642)
							(end -0.1778 0.2794)
						)
						(arc
							(start 0.1778 0.2794)
							(mid 0.249642 0.249642)
							(end 0.2794 0.1778)
						)
						(arc
							(start 0.2794 -0.1778)
							(mid 0.249642 -0.249642)
							(end 0.1778 -0.2794)
						)
					)
					(width 0)
					(fill yes)
				)
			)
		)
	)
	(footprint ""
		(layer "F.Cu")
		(at 61.101732 -147.74926 -90)
		(property "Reference" "R166"
			(at 0 0 270)
			(layer "F.SilkS")
			(hide yes)
			(effects
				(font
					(size 1.27 1.27)
				)
			)
		)
		(property "Value" "0R2J-2-GP"
			(at 0.064008 -3.993896 270)
			(unlocked yes)
			(layer "F.Fab")
			(hide yes)
			(effects
				(font
					(size 1.016 1.016)
					(thickness 0.1524)
				)
			)
		)
		(property "Device Type" "R402H16"
			(at 0.064008 -5.517896 270)
			(unlocked yes)
			(layer "F.Fab")
			(hide yes)
			(effects
				(font
					(size 1.016 1.016)
					(thickness 0.1524)
				)
			)
		)
		(duplicate_pad_numbers_are_jumpers no)
		(fp_line
			(start -0.508 -0.9398)
			(end -0.508 0.9398)
			(stroke
				(width 0.1524)
				(type default)
			)
			(layer "F.SilkS")
		)
		(fp_line
			(start 0.508 -0.9398)
			(end -0.508 -0.9398)
			(stroke
				(width 0.1524)
				(type default)
			)
			(layer "F.SilkS")
		)
		(fp_rect
			(start -0.508 0.9398)
			(end 0.508 -0.9398)
			(stroke
				(width 0)
				(type default)
			)
			(fill no)
			(layer "F.CrtYd")
		)
		(fp_rect
			(start -0.508 0.9398)
			(end 0.508 -0.9398)
			(stroke
				(width 0)
				(type default)
			)
			(fill no)
			(layer "F.Fab")
		)
		(pad "1" smd custom
			(at 0 -0.4445 270)
			(size 0.1397 0.1397)
			(layers "F.Cu" "F.Mask" "F.Paste")
			(net "I2C_BMC_COMP_SDA_OUT")
			(options
				(clearance outline)
				(anchor circle)
			)
			(primitives
				(gr_poly
					(pts
						(arc
							(start -0.1778 -0.2794)
							(mid -0.249642 -0.249642)
							(end -0.2794 -0.1778)
						)
						(arc
							(start -0.2794 0.1778)
							(mid -0.249642 0.249642)
							(end -0.1778 0.2794)
						)
						(arc
							(start 0.1778 0.2794)
							(mid 0.249642 0.249642)
							(end 0.2794 0.1778)
						)
						(arc
							(start 0.2794 -0.1778)
							(mid 0.249642 -0.249642)
							(end 0.1778 -0.2794)
						)
					)
					(width 0)
					(fill yes)
				)
			)
		)
		(pad "2" smd custom
			(at 0 0.4445 270)
			(size 0.1397 0.1397)
			(layers "F.Cu" "F.Mask" "F.Paste")
			(net "BMC_SMB4_DAT")
			(options
				(clearance outline)
				(anchor circle)
			)
			(primitives
				(gr_poly
					(pts
						(arc
							(start -0.1778 -0.2794)
							(mid -0.249642 -0.249642)
							(end -0.2794 -0.1778)
						)
						(arc
							(start -0.2794 0.1778)
							(mid -0.249642 0.249642)
							(end -0.1778 0.2794)
						)
						(arc
							(start 0.1778 0.2794)
							(mid 0.249642 0.249642)
							(end 0.2794 0.1778)
						)
						(arc
							(start 0.2794 -0.1778)
							(mid 0.249642 -0.249642)
							(end 0.1778 -0.2794)
						)
					)
					(width 0)
					(fill yes)
				)
			)
		)
	)
	(footprint ""
		(layer "F.Cu")
		(at 178.6382 -5.969)
		(property "Reference" "R528"
			(at 0 0 0)
			(layer "F.SilkS")
			(hide yes)
			(effects
				(font
					(size 1.27 1.27)
				)
			)
		)
		(property "Value" "0R2J-2-GP"
			(at 0.064008 -3.993896 0)
			(unlocked yes)
			(layer "F.Fab")
			(hide yes)
			(effects
				(font
					(size 1.016 1.016)
					(thickness 0.1524)
				)
			)
		)
		(property "Device Type" "R402H16"
			(at 0.064008 -5.517896 0)
			(unlocked yes)
			(layer "F.Fab")
			(hide yes)
			(effects
				(font
					(size 1.016 1.016)
					(thickness 0.1524)
				)
			)
		)
		(duplicate_pad_numbers_are_jumpers no)
		(fp_line
			(start -0.508 -0.9398)
			(end -0.508 0.9398)
			(stroke
				(width 0.1524)
				(type default)
			)
			(layer "F.SilkS")
		)
		(fp_line
			(start 0.508 -0.9398)
			(end -0.508 -0.9398)
			(stroke
				(width 0.1524)
				(type default)
			)
			(layer "F.SilkS")
		)
		(fp_rect
			(start -0.508 0.9398)
			(end 0.508 -0.9398)
			(stroke
				(width 0)
				(type default)
			)
			(fill no)
			(layer "F.CrtYd")
		)
		(fp_rect
			(start -0.508 0.9398)
			(end 0.508 -0.9398)
			(stroke
				(width 0)
				(type default)
			)
			(fill no)
			(layer "F.Fab")
		)
		(pad "1" smd custom
			(at 0 -0.4445)
			(size 0.1397 0.1397)
			(layers "F.Cu" "F.Mask" "F.Paste")
			(net "BMC_ML_PWR_BLUE_LED_R")
			(options
				(clearance outline)
				(anchor circle)
			)
			(primitives
				(gr_poly
					(pts
						(arc
							(start -0.1778 -0.2794)
							(mid -0.249642 -0.249642)
							(end -0.2794 -0.1778)
						)
						(arc
							(start -0.2794 0.1778)
							(mid -0.249642 0.249642)
							(end -0.1778 0.2794)
						)
						(arc
							(start 0.1778 0.2794)
							(mid 0.249642 0.249642)
							(end 0.2794 0.1778)
						)
						(arc
							(start 0.2794 -0.1778)
							(mid 0.249642 -0.249642)
							(end 0.1778 -0.2794)
						)
					)
					(width 0)
					(fill yes)
				)
			)
		)
		(pad "2" smd custom
			(at 0 0.4445)
			(size 0.1397 0.1397)
			(layers "F.Cu" "F.Mask" "F.Paste")
			(net "BMC_ML_PWR_BLUE_LED")
			(options
				(clearance outline)
				(anchor circle)
			)
			(primitives
				(gr_poly
					(pts
						(arc
							(start -0.1778 -0.2794)
							(mid -0.249642 -0.249642)
							(end -0.2794 -0.1778)
						)
						(arc
							(start -0.2794 0.1778)
							(mid -0.249642 0.249642)
							(end -0.1778 0.2794)
						)
						(arc
							(start 0.1778 0.2794)
							(mid 0.249642 0.249642)
							(end 0.2794 0.1778)
						)
						(arc
							(start 0.2794 -0.1778)
							(mid 0.249642 -0.249642)
							(end 0.1778 -0.2794)
						)
					)
					(width 0)
					(fill yes)
				)
			)
		)
	)
	(footprint ""
		(layer "F.Cu")
		(at 51.2064 -127.8382 90)
		(property "Reference" "R87"
			(at 0 0 90)
			(layer "F.SilkS")
			(hide yes)
			(effects
				(font
					(size 1.27 1.27)
				)
			)
		)
		(property "Value" "100KR2F-L1-GP"
			(at 0.064008 -3.993896 90)
			(unlocked yes)
			(layer "F.Fab")
			(hide yes)
			(effects
				(font
					(size 1.016 1.016)
					(thickness 0.1524)
				)
			)
		)
		(property "Device Type" "R402H16"
			(at 0.064008 -5.517896 90)
			(unlocked yes)
			(layer "F.Fab")
			(hide yes)
			(effects
				(font
					(size 1.016 1.016)
					(thickness 0.1524)
				)
			)
		)
		(duplicate_pad_numbers_are_jumpers no)
		(fp_line
			(start 0.508 -0.9398)
			(end -0.508 -0.9398)
			(stroke
				(width 0.1524)
				(type default)
			)
			(layer "F.SilkS")
		)
		(fp_line
			(start -0.508 -0.9398)
			(end -0.508 0.9398)
			(stroke
				(width 0.1524)
				(type default)
			)
			(layer "F.SilkS")
		)
		(fp_rect
			(start -0.508 0.9398)
			(end 0.508 -0.9398)
			(stroke
				(width 0)
				(type default)
			)
			(fill no)
			(layer "F.CrtYd")
		)
		(fp_rect
			(start -0.508 0.9398)
			(end 0.508 -0.9398)
			(stroke
				(width 0)
				(type default)
			)
			(fill no)
			(layer "F.Fab")
		)
		(pad "1" smd custom
			(at 0 -0.4445 90)
			(size 0.1397 0.1397)
			(layers "F.Cu" "F.Mask" "F.Paste")
			(net "SCC_RMT_FULL_PWR_EN")
			(options
				(clearance outline)
				(anchor circle)
			)
			(primitives
				(gr_poly
					(pts
						(arc
							(start -0.1778 -0.2794)
							(mid -0.249642 -0.249642)
							(end -0.2794 -0.1778)
						)
						(arc
							(start -0.2794 0.1778)
							(mid -0.249642 0.249642)
							(end -0.1778 0.2794)
						)
						(arc
							(start 0.1778 0.2794)
							(mid 0.249642 0.249642)
							(end 0.2794 0.1778)
						)
						(arc
							(start 0.2794 -0.1778)
							(mid 0.249642 -0.249642)
							(end 0.1778 -0.2794)
						)
					)
					(width 0)
					(fill yes)
				)
			)
		)
		(pad "2" smd custom
			(at 0 0.4445 90)
			(size 0.1397 0.1397)
			(layers "F.Cu" "F.Mask" "F.Paste")
			(net "GND")
			(options
				(clearance outline)
				(anchor circle)
			)
			(primitives
				(gr_poly
					(pts
						(arc
							(start -0.1778 -0.2794)
							(mid -0.249642 -0.249642)
							(end -0.2794 -0.1778)
						)
						(arc
							(start -0.2794 0.1778)
							(mid -0.249642 0.249642)
							(end -0.1778 0.2794)
						)
						(arc
							(start 0.1778 0.2794)
							(mid 0.249642 0.249642)
							(end 0.2794 0.1778)
						)
						(arc
							(start 0.2794 -0.1778)
							(mid 0.249642 -0.249642)
							(end 0.1778 -0.2794)
						)
					)
					(width 0)
					(fill yes)
				)
			)
		)
	)
	(footprint ""
		(layer "F.Cu")
		(at 87.3506 -170.688 90)
		(property "Reference" "R726"
			(at 0 0 90)
			(layer "F.SilkS")
			(hide yes)
			(effects
				(font
					(size 1.27 1.27)
				)
			)
		)
		(property "Value" "4K7R2F-GP"
			(at 0.064008 -3.993896 90)
			(unlocked yes)
			(layer "F.Fab")
			(hide yes)
			(effects
				(font
					(size 1.016 1.016)
					(thickness 0.1524)
				)
			)
		)
		(property "Device Type" "R402H16"
			(at 0.064008 -5.517896 90)
			(unlocked yes)
			(layer "F.Fab")
			(hide yes)
			(effects
				(font
					(size 1.016 1.016)
					(thickness 0.1524)
				)
			)
		)
		(duplicate_pad_numbers_are_jumpers no)
		(fp_line
			(start 0.508 -0.9398)
			(end -0.508 -0.9398)
			(stroke
				(width 0.1524)
				(type default)
			)
			(layer "F.SilkS")
		)
		(fp_line
			(start -0.508 -0.9398)
			(end -0.508 0.9398)
			(stroke
				(width 0.1524)
				(type default)
			)
			(layer "F.SilkS")
		)
		(fp_rect
			(start -0.508 0.9398)
			(end 0.508 -0.9398)
			(stroke
				(width 0)
				(type default)
			)
			(fill no)
			(layer "F.CrtYd")
		)
		(fp_rect
			(start -0.508 0.9398)
			(end 0.508 -0.9398)
			(stroke
				(width 0)
				(type default)
			)
			(fill no)
			(layer "F.Fab")
		)
		(pad "1" smd custom
			(at 0 -0.4445 90)
			(size 0.1397 0.1397)
			(layers "F.Cu" "F.Mask" "F.Paste")
			(net "P3V3_STBY")
			(options
				(clearance outline)
				(anchor circle)
			)
			(primitives
				(gr_poly
					(pts
						(arc
							(start -0.1778 -0.2794)
							(mid -0.249642 -0.249642)
							(end -0.2794 -0.1778)
						)
						(arc
							(start -0.2794 0.1778)
							(mid -0.249642 0.249642)
							(end -0.1778 0.2794)
						)
						(arc
							(start 0.1778 0.2794)
							(mid 0.249642 0.249642)
							(end 0.2794 0.1778)
						)
						(arc
							(start 0.2794 -0.1778)
							(mid 0.249642 -0.249642)
							(end 0.1778 -0.2794)
						)
					)
					(width 0)
					(fill yes)
				)
			)
		)
		(pad "2" smd custom
			(at 0 0.4445 90)
			(size 0.1397 0.1397)
			(layers "F.Cu" "F.Mask" "F.Paste")
			(net "IOM_STBY_PGOOD")
			(options
				(clearance outline)
				(anchor circle)
			)
			(primitives
				(gr_poly
					(pts
						(arc
							(start -0.1778 -0.2794)
							(mid -0.249642 -0.249642)
							(end -0.2794 -0.1778)
						)
						(arc
							(start -0.2794 0.1778)
							(mid -0.249642 0.249642)
							(end -0.1778 0.2794)
						)
						(arc
							(start 0.1778 0.2794)
							(mid 0.249642 0.249642)
							(end 0.2794 0.1778)
						)
						(arc
							(start 0.2794 -0.1778)
							(mid 0.249642 -0.249642)
							(end 0.1778 -0.2794)
						)
					)
					(width 0)
					(fill yes)
				)
			)
		)
	)
	(footprint ""
		(layer "F.Cu")
		(at 93.09989 -52.526946)
		(property "Reference" "U38"
			(at 0 0 0)
			(layer "F.SilkS")
			(hide yes)
			(effects
				(font
					(size 1.27 1.27)
				)
			)
		)
		(property "Value" "SN74LVC1G08DCKR-GP"
			(at -2.3368 -8.6868 0)
			(unlocked yes)
			(layer "F.Fab")
			(hide yes)
			(effects
				(font
					(size 1.016 1.016)
					(thickness 0.1524)
				)
			)
		)
		(property "Device Type" "SC70-5H44"
			(at -2.3114 -10.414 0)
			(unlocked yes)
			(layer "F.Fab")
			(hide yes)
			(effects
				(font
					(size 1.016 1.016)
					(thickness 0.1524)
				)
			)
		)
		(duplicate_pad_numbers_are_jumpers no)
		(fp_line
			(start -1.27 -1.7018)
			(end 1.27 -1.7018)
			(stroke
				(width 0.1524)
				(type default)
			)
			(layer "F.SilkS")
		)
		(fp_line
			(start -1.27 1.7018)
			(end -1.27 -1.7018)
			(stroke
				(width 0.1524)
				(type default)
			)
			(layer "F.SilkS")
		)
		(fp_line
			(start 0.6604 -1.8034)
			(end 1.3843 -1.8034)
			(stroke
				(width 0.3302)
				(type default)
			)
			(layer "F.SilkS")
		)
		(fp_line
			(start 1.27 -1.7018)
			(end 1.27 1.7018)
			(stroke
				(width 0.1524)
				(type default)
			)
			(layer "F.SilkS")
		)
		(fp_line
			(start 1.27 1.7018)
			(end -1.27 1.7018)
			(stroke
				(width 0.1524)
				(type default)
			)
			(layer "F.SilkS")
		)
		(fp_line
			(start 1.3843 -1.8034)
			(end 1.3843 -1.1176)
			(stroke
				(width 0.3302)
				(type default)
			)
			(layer "F.SilkS")
		)
		(fp_rect
			(start -1.524 1.9558)
			(end 1.524 -1.9558)
			(stroke
				(width 0)
				(type default)
			)
			(fill no)
			(layer "F.CrtYd")
		)
		(fp_poly
			(pts
				(xy -1.524 -1.9558) (xy 1.524 -1.9558) (xy 1.524 1.9558) (xy -1.524 1.9558)
			)
			(stroke
				(width 0)
				(type default)
			)
			(fill no)
			(layer "F.Fab")
		)
		(pad "1" smd rect
			(at 0.65024 -0.8255)
			(size 0.4064 1.2192)
			(layers "F.Cu" "F.Mask" "F.Paste")
			(net "IOM_FULL_PWR_EN")
		)
		(pad "2" smd rect
			(at 0 -0.8255)
			(size 0.4064 1.2192)
			(layers "F.Cu" "F.Mask" "F.Paste")
			(net "IOM_STBY_PGOOD")
		)
		(pad "3" smd rect
			(at -0.65024 -0.8255)
			(size 0.4064 1.2192)
			(layers "F.Cu" "F.Mask" "F.Paste")
			(net "GND")
		)
		(pad "4" smd rect
			(at -0.65024 0.8255)
			(size 0.4064 1.2192)
			(layers "F.Cu" "F.Mask" "F.Paste")
			(net "P3V3_EN")
		)
		(pad "5" smd rect
			(at 0.65024 0.8255)
			(size 0.4064 1.2192)
			(layers "F.Cu" "F.Mask" "F.Paste")
			(net "P3V3_STBY")
		)
	)
	(footprint ""
		(layer "F.Cu")
		(at 82.441796 -175.76038 90)
		(property "Reference" "C191"
			(at 0 0 90)
			(layer "F.SilkS")
			(hide yes)
			(effects
				(font
					(size 1.27 1.27)
				)
			)
		)
		(property "Value" "SC10U6D3V5KX-4GP"
			(at -0.0762 -6.1214 90)
			(unlocked yes)
			(layer "F.Fab")
			(hide yes)
			(effects
				(font
					(size 1.016 1.016)
					(thickness 0.1524)
				)
			)
		)
		(property "Device Type" "C805H58"
			(at -0.0762 -8.1534 90)
			(unlocked yes)
			(layer "F.Fab")
			(hide yes)
			(effects
				(font
					(size 1.016 1.016)
					(thickness 0.1524)
				)
			)
		)
		(duplicate_pad_numbers_are_jumpers no)
		(fp_line
			(start 0.635 0)
			(end -0.635 0)
			(stroke
				(width 0.508)
				(type default)
			)
			(layer "F.SilkS")
		)
		(fp_rect
			(start -0.9652 1.778)
			(end 0.9652 -1.778)
			(stroke
				(width 0)
				(type default)
			)
			(fill no)
			(layer "F.CrtYd")
		)
		(fp_poly
			(pts
				(xy -0.9652 -1.778) (xy 0.9652 -1.778) (xy 0.9652 1.778) (xy -0.9652 1.778)
			)
			(stroke
				(width 0)
				(type default)
			)
			(fill no)
			(layer "F.Fab")
		)
		(pad "1" smd rect
			(at 0 -0.9652 90)
			(size 1.397 1.143)
			(layers "F.Cu" "F.Mask" "F.Paste")
			(net "TPS74801_P2V5_STBY_OUT")
		)
		(pad "2" smd rect
			(at 0 0.9652 90)
			(size 1.397 1.143)
			(layers "F.Cu" "F.Mask" "F.Paste")
			(net "GND")
		)
	)
	(footprint ""
		(layer "F.Cu")
		(at 200.3552 -107.3912 -90)
		(property "Reference" "C602"
			(at 0 0 270)
			(layer "F.SilkS")
			(hide yes)
			(effects
				(font
					(size 1.27 1.27)
				)
			)
		)
		(property "Value" "SCD1U16V2KX-3GP"
			(at 1.1811 -2.7051 270)
			(unlocked yes)
			(layer "F.Fab")
			(hide yes)
			(effects
				(font
					(size 1.016 1.016)
					(thickness 0.1524)
				)
			)
		)
		(property "Device Type" "C402H22"
			(at 1.1811 -4.2291 270)
			(unlocked yes)
			(layer "F.Fab")
			(hide yes)
			(effects
				(font
					(size 1.016 1.016)
					(thickness 0.1524)
				)
			)
		)
		(duplicate_pad_numbers_are_jumpers no)
		(fp_rect
			(start -0.4318 0.9525)
			(end 0.4318 -0.9525)
			(stroke
				(width 0)
				(type default)
			)
			(fill no)
			(layer "F.CrtYd")
		)
		(fp_rect
			(start -0.4318 0.9525)
			(end 0.4318 -0.9525)
			(stroke
				(width 0)
				(type default)
			)
			(fill no)
			(layer "F.Fab")
		)
		(pad "1" smd custom
			(at 0 -0.4445 270)
			(size 0.1524 0.1524)
			(layers "F.Cu" "F.Mask" "F.Paste")
			(net "P3V3_STBY")
			(options
				(clearance outline)
				(anchor circle)
			)
			(primitives
				(gr_poly
					(pts
						(arc
							(start 0.3048 -0.2032)
							(mid 0.275042 -0.275042)
							(end 0.2032 -0.3048)
						)
						(arc
							(start -0.2032 -0.3048)
							(mid -0.275042 -0.275042)
							(end -0.3048 -0.2032)
						)
						(arc
							(start -0.3048 0.2032)
							(mid -0.275042 0.275042)
							(end -0.2032 0.3048)
						)
						(arc
							(start 0.2032 0.3048)
							(mid 0.275042 0.275042)
							(end 0.3048 0.2032)
						)
					)
					(width 0)
					(fill yes)
				)
			)
		)
		(pad "2" smd custom
			(at 0 0.4445 270)
			(size 0.1524 0.1524)
			(layers "F.Cu" "F.Mask" "F.Paste")
			(net "GND")
			(options
				(clearance outline)
				(anchor circle)
			)
			(primitives
				(gr_poly
					(pts
						(arc
							(start 0.3048 -0.2032)
							(mid 0.275042 -0.275042)
							(end 0.2032 -0.3048)
						)
						(arc
							(start -0.2032 -0.3048)
							(mid -0.275042 -0.275042)
							(end -0.3048 -0.2032)
						)
						(arc
							(start -0.3048 0.2032)
							(mid -0.275042 0.275042)
							(end -0.2032 0.3048)
						)
						(arc
							(start 0.2032 0.3048)
							(mid 0.275042 0.275042)
							(end 0.3048 0.2032)
						)
					)
					(width 0)
					(fill yes)
				)
			)
		)
	)
	(footprint ""
		(layer "F.Cu")
		(at 119.528844 -13.467588 90)
		(property "Reference" "C133"
			(at 0 0 90)
			(layer "F.SilkS")
			(hide yes)
			(effects
				(font
					(size 1.27 1.27)
				)
			)
		)
		(property "Value" "SCD015U25V2KX-GP"
			(at 1.1811 -2.7051 90)
			(unlocked yes)
			(layer "F.Fab")
			(hide yes)
			(effects
				(font
					(size 1.016 1.016)
					(thickness 0.1524)
				)
			)
		)
		(property "Device Type" "C402H22"
			(at 1.1811 -4.2291 90)
			(unlocked yes)
			(layer "F.Fab")
			(hide yes)
			(effects
				(font
					(size 1.016 1.016)
					(thickness 0.1524)
				)
			)
		)
		(duplicate_pad_numbers_are_jumpers no)
		(fp_rect
			(start -0.4318 0.9525)
			(end 0.4318 -0.9525)
			(stroke
				(width 0)
				(type default)
			)
			(fill no)
			(layer "F.CrtYd")
		)
		(fp_rect
			(start -0.4318 0.9525)
			(end 0.4318 -0.9525)
			(stroke
				(width 0)
				(type default)
			)
			(fill no)
			(layer "F.Fab")
		)
		(pad "1" smd custom
			(at 0 -0.4445 90)
			(size 0.1524 0.1524)
			(layers "F.Cu" "F.Mask" "F.Paste")
			(net "MB0_CM_SENSE_P")
			(options
				(clearance outline)
				(anchor circle)
			)
			(primitives
				(gr_poly
					(pts
						(arc
							(start 0.3048 -0.2032)
							(mid 0.275042 -0.275042)
							(end 0.2032 -0.3048)
						)
						(arc
							(start -0.2032 -0.3048)
							(mid -0.275042 -0.275042)
							(end -0.3048 -0.2032)
						)
						(arc
							(start -0.3048 0.2032)
							(mid -0.275042 0.275042)
							(end -0.2032 0.3048)
						)
						(arc
							(start 0.2032 0.3048)
							(mid 0.275042 0.275042)
							(end 0.3048 0.2032)
						)
					)
					(width 0)
					(fill yes)
				)
			)
		)
		(pad "2" smd custom
			(at 0 0.4445 90)
			(size 0.1524 0.1524)
			(layers "F.Cu" "F.Mask" "F.Paste")
			(net "MB0_CM_SENSE_N")
			(options
				(clearance outline)
				(anchor circle)
			)
			(primitives
				(gr_poly
					(pts
						(arc
							(start 0.3048 -0.2032)
							(mid 0.275042 -0.275042)
							(end 0.2032 -0.3048)
						)
						(arc
							(start -0.2032 -0.3048)
							(mid -0.275042 -0.275042)
							(end -0.3048 -0.2032)
						)
						(arc
							(start -0.3048 0.2032)
							(mid -0.275042 0.275042)
							(end -0.2032 0.3048)
						)
						(arc
							(start 0.2032 0.3048)
							(mid 0.275042 0.275042)
							(end 0.3048 0.2032)
						)
					)
					(width 0)
					(fill yes)
				)
			)
		)
	)
	(footprint ""
		(layer "F.Cu")
		(at 183.460644 -132.973826 180)
		(property "Reference" "VIA67"
			(at 0 0 180)
			(layer "F.SilkS")
			(hide yes)
			(effects
				(font
					(size 1.27 1.27)
				)
			)
		)
		(property "Value" "85OHM-8L-1D6MM-L16L18-GP"
			(at 4.064 0.6096 180)
			(unlocked yes)
			(layer "F.Fab")
			(hide yes)
			(effects
				(font
					(size 1.016 1.016)
					(thickness 0.1524)
				)
			)
		)
		(property "Device Type" "VIA-PCIE-4P-368076"
			(at 4.064 -0.9144 180)
			(unlocked yes)
			(layer "F.Fab")
			(hide yes)
			(effects
				(font
					(size 1.016 1.016)
					(thickness 0.1524)
				)
			)
		)
		(duplicate_pad_numbers_are_jumpers no)
		(fp_rect
			(start -1.8415 0.381)
			(end 1.8415 -0.381)
			(stroke
				(width 0)
				(type default)
			)
			(fill no)
			(layer "F.CrtYd")
		)
		(fp_rect
			(start -1.8415 0.381)
			(end 1.8415 -0.381)
			(stroke
				(width 0)
				(type default)
			)
			(fill no)
			(layer "F.Fab")
		)
		(pad "1" thru_hole circle
			(at -1.4605 0 180)
			(size 0.508 0.508)
			(drill 0.254)
			(layers "*.Cu" "*.Mask")
			(remove_unused_layers no)
			(net "GND")
			(clearance 0.127)
			(thermal_gap 0.127)
		)
		(pad "2" thru_hole circle
			(at -0.4445 0 180)
			(size 0.508 0.508)
			(drill 0.254)
			(layers "*.Cu" "*.Mask")
			(remove_unused_layers no)
			(net "PCIE_COMP_TO_IOM_CLK_3_DP")
			(clearance 0.127)
			(thermal_gap 0.127)
		)
		(pad "3" thru_hole circle
			(at 0.4445 0 180)
			(size 0.508 0.508)
			(drill 0.254)
			(layers "*.Cu" "*.Mask")
			(remove_unused_layers no)
			(net "PCIE_COMP_TO_IOM_CLK_3_DN")
			(clearance 0.127)
			(thermal_gap 0.127)
		)
		(pad "4" thru_hole circle
			(at 1.4605 0 180)
			(size 0.508 0.508)
			(drill 0.254)
			(layers "*.Cu" "*.Mask")
			(remove_unused_layers no)
			(net "GND")
			(clearance 0.127)
			(thermal_gap 0.127)
		)
	)
	(footprint ""
		(layer "F.Cu")
		(at 42.1132 -158.4198)
		(property "Reference" "TP186"
			(at 0 0 0)
			(layer "F.SilkS")
			(hide yes)
			(effects
				(font
					(size 1.27 1.27)
				)
			)
		)
		(property "Value" "TPAD28-2-GP"
			(at -0.0127 -1.6637 0)
			(unlocked yes)
			(layer "F.Fab")
			(hide yes)
			(effects
				(font
					(size 1.016 1.016)
					(thickness 0.1524)
				)
			)
		)
		(property "Device Type" "TPAD28"
			(at -0.0127 -3.1877 0)
			(unlocked yes)
			(layer "F.Fab")
			(hide yes)
			(effects
				(font
					(size 1.016 1.016)
					(thickness 0.1524)
				)
			)
		)
		(duplicate_pad_numbers_are_jumpers no)
		(fp_poly
			(pts
				(arc
					(start 0.3556 0)
					(mid -0.3556 0)
					(end 0.3556 0)
				)
			)
			(stroke
				(width 0)
				(type default)
			)
			(fill no)
			(layer "F.CrtYd")
		)
		(fp_poly
			(pts
				(arc
					(start 0.6096 0)
					(mid -0.6096 0)
					(end 0.6096 0)
				)
			)
			(stroke
				(width 0)
				(type default)
			)
			(fill no)
			(layer "F.Fab")
		)
		(pad "1" smd circle
			(at 0 0)
			(size 0.7112 0.7112)
			(layers "F.Cu" "F.Mask" "F.Paste")
			(net "TP_BMC_GPIOL0")
		)
	)
	(footprint ""
		(layer "F.Cu")
		(at 22.011386 -131.007358 180)
		(property "Reference" "R144"
			(at 0 0 180)
			(layer "F.SilkS")
			(hide yes)
			(effects
				(font
					(size 1.27 1.27)
				)
			)
		)
		(property "Value" "4K7R2F-GP"
			(at 0.064008 -3.993896 180)
			(unlocked yes)
			(layer "F.Fab")
			(hide yes)
			(effects
				(font
					(size 1.016 1.016)
					(thickness 0.1524)
				)
			)
		)
		(property "Device Type" "R402H16"
			(at 0.064008 -5.517896 180)
			(unlocked yes)
			(layer "F.Fab")
			(hide yes)
			(effects
				(font
					(size 1.016 1.016)
					(thickness 0.1524)
				)
			)
		)
		(duplicate_pad_numbers_are_jumpers no)
		(fp_line
			(start 0.508 -0.9398)
			(end -0.508 -0.9398)
			(stroke
				(width 0.1524)
				(type default)
			)
			(layer "F.SilkS")
		)
		(fp_line
			(start -0.508 -0.9398)
			(end -0.508 0.9398)
			(stroke
				(width 0.1524)
				(type default)
			)
			(layer "F.SilkS")
		)
		(fp_rect
			(start -0.508 0.9398)
			(end 0.508 -0.9398)
			(stroke
				(width 0)
				(type default)
			)
			(fill no)
			(layer "F.CrtYd")
		)
		(fp_rect
			(start -0.508 0.9398)
			(end 0.508 -0.9398)
			(stroke
				(width 0)
				(type default)
			)
			(fill no)
			(layer "F.Fab")
		)
		(pad "1" smd custom
			(at 0 -0.4445 180)
			(size 0.1397 0.1397)
			(layers "F.Cu" "F.Mask" "F.Paste")
			(net "DDR4_ALERT")
			(options
				(clearance outline)
				(anchor circle)
			)
			(primitives
				(gr_poly
					(pts
						(arc
							(start -0.1778 -0.2794)
							(mid -0.249642 -0.249642)
							(end -0.2794 -0.1778)
						)
						(arc
							(start -0.2794 0.1778)
							(mid -0.249642 0.249642)
							(end -0.1778 0.2794)
						)
						(arc
							(start 0.1778 0.2794)
							(mid 0.249642 0.249642)
							(end 0.2794 0.1778)
						)
						(arc
							(start 0.2794 -0.1778)
							(mid 0.249642 -0.249642)
							(end 0.1778 -0.2794)
						)
					)
					(width 0)
					(fill yes)
				)
			)
		)
		(pad "2" smd custom
			(at 0 0.4445 180)
			(size 0.1397 0.1397)
			(layers "F.Cu" "F.Mask" "F.Paste")
			(net "P1V2_STBY")
			(options
				(clearance outline)
				(anchor circle)
			)
			(primitives
				(gr_poly
					(pts
						(arc
							(start -0.1778 -0.2794)
							(mid -0.249642 -0.249642)
							(end -0.2794 -0.1778)
						)
						(arc
							(start -0.2794 0.1778)
							(mid -0.249642 0.249642)
							(end -0.1778 0.2794)
						)
						(arc
							(start 0.1778 0.2794)
							(mid 0.249642 0.249642)
							(end 0.2794 0.1778)
						)
						(arc
							(start 0.2794 -0.1778)
							(mid 0.249642 -0.249642)
							(end 0.1778 -0.2794)
						)
					)
					(width 0)
					(fill yes)
				)
			)
		)
	)
	(footprint ""
		(layer "F.Cu")
		(at 94.488 -17.8562)
		(property "Reference" "D19"
			(at 0 0 0)
			(layer "F.SilkS")
			(hide yes)
			(effects
				(font
					(size 1.27 1.27)
				)
			)
		)
		(property "Value" "PESD5V0F1BL-GP"
			(at 1.8923 -1.5621 0)
			(unlocked yes)
			(layer "F.Fab")
			(hide yes)
			(effects
				(font
					(size 1.016 1.016)
					(thickness 0.1524)
				)
			)
		)
		(property "Device Type" "SOD882-10D6-1H20"
			(at 1.8923 -3.0861 0)
			(unlocked yes)
			(layer "F.Fab")
			(hide yes)
			(effects
				(font
					(size 1.016 1.016)
					(thickness 0.1524)
				)
			)
		)
		(duplicate_pad_numbers_are_jumpers no)
		(fp_line
			(start -0.3048 -0.9271)
			(end 0.3048 -0.9271)
			(stroke
				(width 0.254)
				(type default)
			)
			(layer "F.SilkS")
		)
		(fp_rect
			(start -0.2921 0.4953)
			(end 0.2921 -0.4953)
			(stroke
				(width 0)
				(type default)
			)
			(fill no)
			(layer "F.CrtYd")
		)
		(fp_poly
			(pts
				(xy -0.4318 0.8001) (xy -0.4318 -0.266192) (xy -0.2921 -0.266192) (xy -0.2921 0.4953) (xy 0.2921 0.4953)
				(xy 0.2921 -0.4953) (xy -0.2921 -0.4953) (xy -0.2921 -0.2667) (xy -0.4318 -0.2667) (xy -0.4318 -0.8001)
				(xy 0.4318 -0.8001) (xy 0.4318 0.8001)
			)
			(stroke
				(width 0)
				(type default)
			)
			(fill no)
			(layer "F.CrtYd")
		)
		(fp_rect
			(start -0.4318 0.8001)
			(end 0.4318 -0.8001)
			(stroke
				(width 0)
				(type default)
			)
			(fill no)
			(layer "F.Fab")
		)
		(pad "1" smd custom
			(at 0 -0.4445)
			(size 0.1143 0.1143)
			(layers "F.Cu" "F.Mask" "F.Paste")
			(net "GND")
			(options
				(clearance outline)
				(anchor circle)
			)
			(primitives
				(gr_poly
					(pts
						(arc
							(start -0.2032 0.2286)
							(mid -0.275042 0.198842)
							(end -0.3048 0.127)
						)
						(arc
							(start -0.3048 -0.127)
							(mid -0.275042 -0.198842)
							(end -0.2032 -0.2286)
						)
						(arc
							(start 0.2032 -0.2286)
							(mid 0.275042 -0.198842)
							(end 0.3048 -0.127)
						)
						(arc
							(start 0.3048 0.127)
							(mid 0.275042 0.198842)
							(end 0.2032 0.2286)
						)
					)
					(width 0)
					(fill yes)
				)
			)
		)
		(pad "2" smd custom
			(at 0 0.4445)
			(size 0.1143 0.1143)
			(layers "F.Cu" "F.Mask" "F.Paste")
			(net "USB_P1_F_DN1")
			(options
				(clearance outline)
				(anchor circle)
			)
			(primitives
				(gr_poly
					(pts
						(arc
							(start 0.2032 -0.2286)
							(mid 0.275042 -0.198842)
							(end 0.3048 -0.127)
						)
						(arc
							(start 0.3048 0.127)
							(mid 0.275042 0.198842)
							(end 0.2032 0.2286)
						)
						(arc
							(start -0.2032 0.2286)
							(mid -0.275042 0.198842)
							(end -0.3048 0.127)
						)
						(arc
							(start -0.3048 -0.127)
							(mid -0.275042 -0.198842)
							(end -0.2032 -0.2286)
						)
					)
					(width 0)
					(fill yes)
				)
			)
		)
	)
	(footprint ""
		(layer "F.Cu")
		(at 60.494672 -134.434326)
		(property "Reference" "TP207"
			(at 0 0 0)
			(layer "F.SilkS")
			(hide yes)
			(effects
				(font
					(size 1.27 1.27)
				)
			)
		)
		(property "Value" "TPAD28-2-GP"
			(at -0.0127 -1.6637 0)
			(unlocked yes)
			(layer "F.Fab")
			(hide yes)
			(effects
				(font
					(size 1.016 1.016)
					(thickness 0.1524)
				)
			)
		)
		(property "Device Type" "TPAD28"
			(at -0.0127 -3.1877 0)
			(unlocked yes)
			(layer "F.Fab")
			(hide yes)
			(effects
				(font
					(size 1.016 1.016)
					(thickness 0.1524)
				)
			)
		)
		(duplicate_pad_numbers_are_jumpers no)
		(fp_poly
			(pts
				(arc
					(start 0.3556 0)
					(mid -0.3556 0)
					(end 0.3556 0)
				)
			)
			(stroke
				(width 0)
				(type default)
			)
			(fill no)
			(layer "F.CrtYd")
		)
		(fp_poly
			(pts
				(arc
					(start 0.6096 0)
					(mid -0.6096 0)
					(end 0.6096 0)
				)
			)
			(stroke
				(width 0)
				(type default)
			)
			(fill no)
			(layer "F.Fab")
		)
		(pad "1" smd circle
			(at 0 0)
			(size 0.7112 0.7112)
			(layers "F.Cu" "F.Mask" "F.Paste")
			(net "TP_BMC_EXT2_LED_B")
		)
	)
	(footprint ""
		(layer "F.Cu")
		(at 124.8156 -5.5372 -90)
		(property "Reference" "R712"
			(at 0 0 270)
			(layer "F.SilkS")
			(hide yes)
			(effects
				(font
					(size 1.27 1.27)
				)
			)
		)
		(property "Value" "0R2J-2-GP"
			(at 0.064008 -3.993896 270)
			(unlocked yes)
			(layer "F.Fab")
			(hide yes)
			(effects
				(font
					(size 1.016 1.016)
					(thickness 0.1524)
				)
			)
		)
		(property "Device Type" "R402H16"
			(at 0.064008 -5.517896 270)
			(unlocked yes)
			(layer "F.Fab")
			(hide yes)
			(effects
				(font
					(size 1.016 1.016)
					(thickness 0.1524)
				)
			)
		)
		(duplicate_pad_numbers_are_jumpers no)
		(fp_line
			(start -0.508 -0.9398)
			(end -0.508 0.9398)
			(stroke
				(width 0.1524)
				(type default)
			)
			(layer "F.SilkS")
		)
		(fp_line
			(start 0.508 -0.9398)
			(end -0.508 -0.9398)
			(stroke
				(width 0.1524)
				(type default)
			)
			(layer "F.SilkS")
		)
		(fp_rect
			(start -0.508 0.9398)
			(end 0.508 -0.9398)
			(stroke
				(width 0)
				(type default)
			)
			(fill no)
			(layer "F.CrtYd")
		)
		(fp_rect
			(start -0.508 0.9398)
			(end 0.508 -0.9398)
			(stroke
				(width 0)
				(type default)
			)
			(fill no)
			(layer "F.Fab")
		)
		(pad "1" smd custom
			(at 0 -0.4445 270)
			(size 0.1397 0.1397)
			(layers "F.Cu" "F.Mask" "F.Paste")
			(net "I2C_IOM_SDA")
			(options
				(clearance outline)
				(anchor circle)
			)
			(primitives
				(gr_poly
					(pts
						(arc
							(start -0.1778 -0.2794)
							(mid -0.249642 -0.249642)
							(end -0.2794 -0.1778)
						)
						(arc
							(start -0.2794 0.1778)
							(mid -0.249642 0.249642)
							(end -0.1778 0.2794)
						)
						(arc
							(start 0.1778 0.2794)
							(mid 0.249642 0.249642)
							(end 0.2794 0.1778)
						)
						(arc
							(start 0.2794 -0.1778)
							(mid 0.249642 -0.249642)
							(end 0.1778 -0.2794)
						)
					)
					(width 0)
					(fill yes)
				)
			)
		)
		(pad "2" smd custom
			(at 0 0.4445 270)
			(size 0.1397 0.1397)
			(layers "F.Cu" "F.Mask" "F.Paste")
			(net "HSW_SDA")
			(options
				(clearance outline)
				(anchor circle)
			)
			(primitives
				(gr_poly
					(pts
						(arc
							(start -0.1778 -0.2794)
							(mid -0.249642 -0.249642)
							(end -0.2794 -0.1778)
						)
						(arc
							(start -0.2794 0.1778)
							(mid -0.249642 0.249642)
							(end -0.1778 0.2794)
						)
						(arc
							(start 0.1778 0.2794)
							(mid 0.249642 0.249642)
							(end 0.2794 0.1778)
						)
						(arc
							(start 0.2794 -0.1778)
							(mid 0.249642 -0.249642)
							(end 0.1778 -0.2794)
						)
					)
					(width 0)
					(fill yes)
				)
			)
		)
	)
	(footprint ""
		(layer "F.Cu")
		(at 83.4644 -168.1734)
		(property "Reference" "Q11"
			(at 0 0 0)
			(layer "F.SilkS")
			(hide yes)
			(effects
				(font
					(size 1.27 1.27)
				)
			)
		)
		(property "Value" "2N7002K-1-GP"
			(at 0.127 -8.9662 0)
			(unlocked yes)
			(layer "F.Fab")
			(hide yes)
			(effects
				(font
					(size 1.016 1.016)
					(thickness 0.1524)
				)
			)
		)
		(property "Device Type" "SOT23DGS2D4H44"
			(at 0.127 -10.4902 0)
			(unlocked yes)
			(layer "F.Fab")
			(hide yes)
			(effects
				(font
					(size 1.016 1.016)
					(thickness 0.1524)
				)
			)
		)
		(duplicate_pad_numbers_are_jumpers no)
		(fp_line
			(start -1.651 -1.778)
			(end -1.651 1.778)
			(stroke
				(width 0.1524)
				(type default)
			)
			(layer "F.SilkS")
		)
		(fp_line
			(start -1.651 1.778)
			(end 1.651 1.778)
			(stroke
				(width 0.1524)
				(type default)
			)
			(layer "F.SilkS")
		)
		(fp_line
			(start 1.651 -1.778)
			(end -1.651 -1.778)
			(stroke
				(width 0.1524)
				(type default)
			)
			(layer "F.SilkS")
		)
		(fp_line
			(start 1.651 1.778)
			(end 1.651 -1.778)
			(stroke
				(width 0.1524)
				(type default)
			)
			(layer "F.SilkS")
		)
		(fp_poly
			(pts
				(xy -1.778 1.8796) (xy -1.778 -1.8796) (xy 1.778 -1.8796) (xy 1.778 1.8796)
			)
			(stroke
				(width 0)
				(type default)
			)
			(fill no)
			(layer "F.CrtYd")
		)
		(fp_poly
			(pts
				(xy -1.778 1.8796) (xy -1.778 -1.8796) (xy 1.778 -1.8796) (xy 1.778 1.8796)
			)
			(stroke
				(width 0)
				(type default)
			)
			(fill no)
			(layer "F.Fab")
		)
		(pad "D" smd custom
			(at 0 -0.9525)
			(size 0.1905 0.1905)
			(layers "F.Cu" "F.Mask" "F.Paste")
			(net "P1V15_STBY_PG_G")
			(options
				(clearance outline)
				(anchor circle)
			)
			(primitives
				(gr_poly
					(pts
						(arc
							(start -0.1778 0.5715)
							(mid -0.321484 0.511984)
							(end -0.381 0.3683)
						)
						(arc
							(start -0.381 -0.3683)
							(mid -0.321484 -0.511984)
							(end -0.1778 -0.5715)
						)
						(arc
							(start 0.1778 -0.5715)
							(mid 0.321484 -0.511984)
							(end 0.381 -0.3683)
						)
						(arc
							(start 0.381 0.3683)
							(mid 0.321484 0.511984)
							(end 0.1778 0.5715)
						)
					)
					(width 0)
					(fill yes)
				)
			)
		)
		(pad "G" smd custom
			(at -0.98425 0.9525)
			(size 0.1905 0.1905)
			(layers "F.Cu" "F.Mask" "F.Paste")
			(net "P1V15_STBY_PG")
			(options
				(clearance outline)
				(anchor circle)
			)
			(primitives
				(gr_poly
					(pts
						(arc
							(start -0.1778 0.5715)
							(mid -0.321484 0.511984)
							(end -0.381 0.3683)
						)
						(arc
							(start -0.381 -0.3683)
							(mid -0.321484 -0.511984)
							(end -0.1778 -0.5715)
						)
						(arc
							(start 0.1778 -0.5715)
							(mid 0.321484 -0.511984)
							(end 0.381 -0.3683)
						)
						(arc
							(start 0.381 0.3683)
							(mid 0.321484 0.511984)
							(end 0.1778 0.5715)
						)
					)
					(width 0)
					(fill yes)
				)
			)
		)
		(pad "S" smd custom
			(at 0.98425 0.9525)
			(size 0.1905 0.1905)
			(layers "F.Cu" "F.Mask" "F.Paste")
			(net "GND")
			(options
				(clearance outline)
				(anchor circle)
			)
			(primitives
				(gr_poly
					(pts
						(arc
							(start -0.1778 0.5715)
							(mid -0.321484 0.511984)
							(end -0.381 0.3683)
						)
						(arc
							(start -0.381 -0.3683)
							(mid -0.321484 -0.511984)
							(end -0.1778 -0.5715)
						)
						(arc
							(start 0.1778 -0.5715)
							(mid 0.321484 -0.511984)
							(end 0.381 -0.3683)
						)
						(arc
							(start 0.381 0.3683)
							(mid 0.321484 0.511984)
							(end 0.1778 0.5715)
						)
					)
					(width 0)
					(fill yes)
				)
			)
		)
	)
	(footprint ""
		(layer "F.Cu")
		(at 218.52128 -103.040688 90)
		(property "Reference" "C645"
			(at 0 0 90)
			(layer "F.SilkS")
			(hide yes)
			(effects
				(font
					(size 1.27 1.27)
				)
			)
		)
		(property "Value" "SC1U16V3KX-5GP"
			(at 0 -2.8194 90)
			(unlocked yes)
			(layer "F.Fab")
			(hide yes)
			(effects
				(font
					(size 1.016 1.016)
					(thickness 0.1524)
				)
			)
		)
		(property "Device Type" "C603H36"
			(at 0 -4.3434 90)
			(unlocked yes)
			(layer "F.Fab")
			(hide yes)
			(effects
				(font
					(size 1.016 1.016)
					(thickness 0.1524)
				)
			)
		)
		(duplicate_pad_numbers_are_jumpers no)
		(fp_line
			(start 0.508 0)
			(end -0.508 0)
			(stroke
				(width 0.2032)
				(type default)
			)
			(layer "F.SilkS")
		)
		(fp_rect
			(start -0.5842 1.3335)
			(end 0.5842 -1.3335)
			(stroke
				(width 0)
				(type default)
			)
			(fill no)
			(layer "F.CrtYd")
		)
		(fp_rect
			(start -0.5842 1.3335)
			(end 0.5842 -1.3335)
			(stroke
				(width 0)
				(type default)
			)
			(fill no)
			(layer "F.Fab")
		)
		(pad "1" smd custom
			(at 0 -0.762 90)
			(size 0.2159 0.2159)
			(layers "F.Cu" "F.Mask" "F.Paste")
			(net "GND")
			(options
				(clearance outline)
				(anchor circle)
			)
			(primitives
				(gr_poly
					(pts
						(arc
							(start -0.3302 -0.4318)
							(mid -0.402042 -0.402042)
							(end -0.4318 -0.3302)
						)
						(arc
							(start -0.4318 0.3302)
							(mid -0.402042 0.402042)
							(end -0.3302 0.4318)
						)
						(arc
							(start 0.3302 0.4318)
							(mid 0.402042 0.402042)
							(end 0.4318 0.3302)
						)
						(arc
							(start 0.4318 -0.3302)
							(mid 0.402042 -0.402042)
							(end 0.3302 -0.4318)
						)
					)
					(width 0)
					(fill yes)
				)
			)
		)
		(pad "2" smd custom
			(at 0 0.762 90)
			(size 0.2159 0.2159)
			(layers "F.Cu" "F.Mask" "F.Paste")
			(net "P3V3_M2_VREG")
			(options
				(clearance outline)
				(anchor circle)
			)
			(primitives
				(gr_poly
					(pts
						(arc
							(start -0.3302 -0.4318)
							(mid -0.402042 -0.402042)
							(end -0.4318 -0.3302)
						)
						(arc
							(start -0.4318 0.3302)
							(mid -0.402042 0.402042)
							(end -0.3302 0.4318)
						)
						(arc
							(start 0.3302 0.4318)
							(mid 0.402042 0.402042)
							(end 0.4318 0.3302)
						)
						(arc
							(start 0.4318 -0.3302)
							(mid 0.402042 -0.402042)
							(end 0.3302 -0.4318)
						)
					)
					(width 0)
					(fill yes)
				)
			)
		)
	)
	(footprint ""
		(layer "F.Cu")
		(at 61.8998 -140.6652)
		(property "Reference" "R271"
			(at 0 0 0)
			(layer "F.SilkS")
			(hide yes)
			(effects
				(font
					(size 1.27 1.27)
				)
			)
		)
		(property "Value" "4K7R2F-GP"
			(at 0.064008 -3.993896 0)
			(unlocked yes)
			(layer "F.Fab")
			(hide yes)
			(effects
				(font
					(size 1.016 1.016)
					(thickness 0.1524)
				)
			)
		)
		(property "Device Type" "R402H16"
			(at 0.064008 -5.517896 0)
			(unlocked yes)
			(layer "F.Fab")
			(hide yes)
			(effects
				(font
					(size 1.016 1.016)
					(thickness 0.1524)
				)
			)
		)
		(duplicate_pad_numbers_are_jumpers no)
		(fp_line
			(start -0.508 -0.9398)
			(end -0.508 0.9398)
			(stroke
				(width 0.1524)
				(type default)
			)
			(layer "F.SilkS")
		)
		(fp_line
			(start 0.508 -0.9398)
			(end -0.508 -0.9398)
			(stroke
				(width 0.1524)
				(type default)
			)
			(layer "F.SilkS")
		)
		(fp_rect
			(start -0.508 0.9398)
			(end 0.508 -0.9398)
			(stroke
				(width 0)
				(type default)
			)
			(fill no)
			(layer "F.CrtYd")
		)
		(fp_rect
			(start -0.508 0.9398)
			(end 0.508 -0.9398)
			(stroke
				(width 0)
				(type default)
			)
			(fill no)
			(layer "F.Fab")
		)
		(pad "1" smd custom
			(at 0 -0.4445)
			(size 0.1397 0.1397)
			(layers "F.Cu" "F.Mask" "F.Paste")
			(net "BMC_TO_EXP_RESET_OUT")
			(options
				(clearance outline)
				(anchor circle)
			)
			(primitives
				(gr_poly
					(pts
						(arc
							(start -0.1778 -0.2794)
							(mid -0.249642 -0.249642)
							(end -0.2794 -0.1778)
						)
						(arc
							(start -0.2794 0.1778)
							(mid -0.249642 0.249642)
							(end -0.1778 0.2794)
						)
						(arc
							(start 0.1778 0.2794)
							(mid 0.249642 0.249642)
							(end 0.2794 0.1778)
						)
						(arc
							(start 0.2794 -0.1778)
							(mid 0.249642 -0.249642)
							(end 0.1778 -0.2794)
						)
					)
					(width 0)
					(fill yes)
				)
			)
		)
		(pad "2" smd custom
			(at 0 0.4445)
			(size 0.1397 0.1397)
			(layers "F.Cu" "F.Mask" "F.Paste")
			(net "P3V3_STBY")
			(options
				(clearance outline)
				(anchor circle)
			)
			(primitives
				(gr_poly
					(pts
						(arc
							(start -0.1778 -0.2794)
							(mid -0.249642 -0.249642)
							(end -0.2794 -0.1778)
						)
						(arc
							(start -0.2794 0.1778)
							(mid -0.249642 0.249642)
							(end -0.1778 0.2794)
						)
						(arc
							(start 0.1778 0.2794)
							(mid 0.249642 0.249642)
							(end 0.2794 0.1778)
						)
						(arc
							(start 0.2794 -0.1778)
							(mid 0.249642 -0.249642)
							(end 0.1778 -0.2794)
						)
					)
					(width 0)
					(fill yes)
				)
			)
		)
	)
	(footprint ""
		(layer "F.Cu")
		(at 225.880168 -55.07609 90)
		(property "Reference" "C155"
			(at 0 0 90)
			(layer "F.SilkS")
			(hide yes)
			(effects
				(font
					(size 1.27 1.27)
				)
			)
		)
		(property "Value" "SC10U16V5KX-7-GP-U"
			(at -0.0762 -6.1214 90)
			(unlocked yes)
			(layer "F.Fab")
			(hide yes)
			(effects
				(font
					(size 1.016 1.016)
					(thickness 0.1524)
				)
			)
		)
		(property "Device Type" "C805H58"
			(at -0.0762 -8.1534 90)
			(unlocked yes)
			(layer "F.Fab")
			(hide yes)
			(effects
				(font
					(size 1.016 1.016)
					(thickness 0.1524)
				)
			)
		)
		(duplicate_pad_numbers_are_jumpers no)
		(fp_line
			(start 0.635 0)
			(end -0.635 0)
			(stroke
				(width 0.508)
				(type default)
			)
			(layer "F.SilkS")
		)
		(fp_rect
			(start -0.9652 1.778)
			(end 0.9652 -1.778)
			(stroke
				(width 0)
				(type default)
			)
			(fill no)
			(layer "F.CrtYd")
		)
		(fp_poly
			(pts
				(xy -0.9652 -1.778) (xy 0.9652 -1.778) (xy 0.9652 1.778) (xy -0.9652 1.778)
			)
			(stroke
				(width 0)
				(type default)
			)
			(fill no)
			(layer "F.Fab")
		)
		(pad "1" smd rect
			(at 0 -0.9652 90)
			(size 1.397 1.143)
			(layers "F.Cu" "F.Mask" "F.Paste")
			(net "P12V_STBY_VIN_PU1")
		)
		(pad "2" smd rect
			(at 0 0.9652 90)
			(size 1.397 1.143)
			(layers "F.Cu" "F.Mask" "F.Paste")
			(net "GND")
		)
	)
	(footprint ""
		(layer "F.Cu")
		(at 93.875606 -129.811526 -90)
		(property "Reference" "U33"
			(at 0 0 270)
			(layer "F.SilkS")
			(hide yes)
			(effects
				(font
					(size 1.27 1.27)
				)
			)
		)
		(property "Value" "TS5A23157DGSR-GP"
			(at 0 -11.1252 270)
			(unlocked yes)
			(layer "F.Fab")
			(hide yes)
			(effects
				(font
					(size 1.016 1.016)
					(thickness 0.1524)
				)
			)
		)
		(property "Device Type" "MSOP10H44"
			(at 0 -12.6492 270)
			(unlocked yes)
			(layer "F.Fab")
			(hide yes)
			(effects
				(font
					(size 1.016 1.016)
					(thickness 0.1524)
				)
			)
		)
		(duplicate_pad_numbers_are_jumpers no)
		(fp_line
			(start -2.0066 1.016)
			(end -2.0066 -1.016)
			(stroke
				(width 0.1524)
				(type default)
			)
			(layer "F.SilkS")
		)
		(fp_line
			(start -1.8288 1.016)
			(end -1.8288 3.048)
			(stroke
				(width 0.508)
				(type default)
			)
			(layer "F.SilkS")
		)
		(fp_line
			(start 1.143 1.016)
			(end -2.0066 1.016)
			(stroke
				(width 0.1524)
				(type default)
			)
			(layer "F.SilkS")
		)
		(fp_line
			(start -1.5748 0)
			(end -1.9558 0.381)
			(stroke
				(width 0.1524)
				(type default)
			)
			(layer "F.SilkS")
		)
		(fp_line
			(start -1.5748 0)
			(end -1.9558 -0.381)
			(stroke
				(width 0.1524)
				(type default)
			)
			(layer "F.SilkS")
		)
		(fp_line
			(start -2.0066 -1.016)
			(end 1.143 -1.016)
			(stroke
				(width 0.1524)
				(type default)
			)
			(layer "F.SilkS")
		)
		(fp_line
			(start 1.143 -1.016)
			(end 1.143 1.016)
			(stroke
				(width 0.1524)
				(type default)
			)
			(layer "F.SilkS")
		)
		(fp_poly
			(pts
				(xy -2.0828 3.3401) (xy 2.0828 3.3401) (xy 2.0828 -3.3401) (xy -2.0828 -3.3401)
			)
			(stroke
				(width 0)
				(type default)
			)
			(fill no)
			(layer "F.CrtYd")
		)
		(fp_poly
			(pts
				(xy -2.0828 3.3401) (xy 2.0828 3.3401) (xy 2.0828 -3.3401) (xy -2.0828 -3.3401)
			)
			(stroke
				(width 0)
				(type default)
			)
			(fill no)
			(layer "F.Fab")
		)
		(pad "1" smd rect
			(at -0.99949 2.0701 270)
			(size 0.3048 1.524)
			(layers "F.Cu" "F.Mask" "F.Paste")
			(net "UART_SEL_MUX")
		)
		(pad "2" smd rect
			(at -0.50038 2.0701 270)
			(size 0.3048 1.524)
			(layers "F.Cu" "F.Mask" "F.Paste")
			(net "UART_BMC_TX")
		)
		(pad "3" smd rect
			(at 0 2.0701 270)
			(size 0.3048 1.524)
			(layers "F.Cu" "F.Mask" "F.Paste")
			(net "GND")
		)
		(pad "4" smd rect
			(at 0.50038 2.0701 270)
			(size 0.3048 1.524)
			(layers "F.Cu" "F.Mask" "F.Paste")
			(net "UART_BMC_RX")
		)
		(pad "5" smd rect
			(at 0.99949 2.0701 270)
			(size 0.3048 1.524)
			(layers "F.Cu" "F.Mask" "F.Paste")
			(net "UART_SEL_MUX")
		)
		(pad "6" smd rect
			(at 0.99949 -2.0701 270)
			(size 0.3048 1.524)
			(layers "F.Cu" "F.Mask" "F.Paste")
			(net "DEBUG_UART_IOM_RX")
		)
		(pad "7" smd rect
			(at 0.50038 -2.0701 270)
			(size 0.3048 1.524)
			(layers "F.Cu" "F.Mask" "F.Paste")
			(net "UART_COMP_IN_RX")
		)
		(pad "8" smd rect
			(at 0 -2.0701 270)
			(size 0.3048 1.524)
			(layers "F.Cu" "F.Mask" "F.Paste")
			(net "P3V3_STBY")
		)
		(pad "9" smd rect
			(at -0.50038 -2.0701 270)
			(size 0.3048 1.524)
			(layers "F.Cu" "F.Mask" "F.Paste")
			(net "UART_COMP_OUT_TX")
		)
		(pad "10" smd rect
			(at -0.99949 -2.0701 270)
			(size 0.3048 1.524)
			(layers "F.Cu" "F.Mask" "F.Paste")
			(net "DEBUG_UART_IOM_TX")
		)
	)
	(footprint ""
		(layer "F.Cu")
		(at 118.9736 -16.002)
		(property "Reference" "R440"
			(at 0 0 0)
			(layer "F.SilkS")
			(hide yes)
			(effects
				(font
					(size 1.27 1.27)
				)
			)
		)
		(property "Value" "10R2F-L-GP"
			(at 0.064008 -3.993896 0)
			(unlocked yes)
			(layer "F.Fab")
			(hide yes)
			(effects
				(font
					(size 1.016 1.016)
					(thickness 0.1524)
				)
			)
		)
		(property "Device Type" "R402H14"
			(at 0.064008 -5.517896 0)
			(unlocked yes)
			(layer "F.Fab")
			(hide yes)
			(effects
				(font
					(size 1.016 1.016)
					(thickness 0.1524)
				)
			)
		)
		(duplicate_pad_numbers_are_jumpers no)
		(fp_line
			(start -0.508 -0.9398)
			(end -0.508 0.9398)
			(stroke
				(width 0.1524)
				(type default)
			)
			(layer "F.SilkS")
		)
		(fp_line
			(start 0.508 -0.9398)
			(end -0.508 -0.9398)
			(stroke
				(width 0.1524)
				(type default)
			)
			(layer "F.SilkS")
		)
		(fp_rect
			(start -0.508 0.9398)
			(end 0.508 -0.9398)
			(stroke
				(width 0)
				(type default)
			)
			(fill no)
			(layer "F.CrtYd")
		)
		(fp_rect
			(start -0.508 0.9398)
			(end 0.508 -0.9398)
			(stroke
				(width 0)
				(type default)
			)
			(fill no)
			(layer "F.Fab")
		)
		(pad "1" smd custom
			(at 0 -0.4445)
			(size 0.1397 0.1397)
			(layers "F.Cu" "F.Mask" "F.Paste")
			(net "MB0_CM_SENSE_R1_P")
			(options
				(clearance outline)
				(anchor circle)
			)
			(primitives
				(gr_poly
					(pts
						(arc
							(start -0.1778 -0.2794)
							(mid -0.249642 -0.249642)
							(end -0.2794 -0.1778)
						)
						(arc
							(start -0.2794 0.1778)
							(mid -0.249642 0.249642)
							(end -0.1778 0.2794)
						)
						(arc
							(start 0.1778 0.2794)
							(mid 0.249642 0.249642)
							(end 0.2794 0.1778)
						)
						(arc
							(start 0.2794 -0.1778)
							(mid 0.249642 -0.249642)
							(end 0.1778 -0.2794)
						)
					)
					(width 0)
					(fill yes)
				)
			)
		)
		(pad "2" smd custom
			(at 0 0.4445)
			(size 0.1397 0.1397)
			(layers "F.Cu" "F.Mask" "F.Paste")
			(net "MB0_CM_SENSE_P")
			(options
				(clearance outline)
				(anchor circle)
			)
			(primitives
				(gr_poly
					(pts
						(arc
							(start -0.1778 -0.2794)
							(mid -0.249642 -0.249642)
							(end -0.2794 -0.1778)
						)
						(arc
							(start -0.2794 0.1778)
							(mid -0.249642 0.249642)
							(end -0.1778 0.2794)
						)
						(arc
							(start 0.1778 0.2794)
							(mid 0.249642 0.249642)
							(end 0.2794 0.1778)
						)
						(arc
							(start 0.2794 -0.1778)
							(mid 0.249642 -0.249642)
							(end 0.1778 -0.2794)
						)
					)
					(width 0)
					(fill yes)
				)
			)
		)
	)
	(footprint ""
		(layer "F.Cu")
		(at 60.452 -158.369)
		(property "Reference" "R397"
			(at 0 0 0)
			(layer "F.SilkS")
			(hide yes)
			(effects
				(font
					(size 1.27 1.27)
				)
			)
		)
		(property "Value" "4K7R2F-GP"
			(at 0.064008 -3.993896 0)
			(unlocked yes)
			(layer "F.Fab")
			(hide yes)
			(effects
				(font
					(size 1.016 1.016)
					(thickness 0.1524)
				)
			)
		)
		(property "Device Type" "R402H16"
			(at 0.064008 -5.517896 0)
			(unlocked yes)
			(layer "F.Fab")
			(hide yes)
			(effects
				(font
					(size 1.016 1.016)
					(thickness 0.1524)
				)
			)
		)
		(duplicate_pad_numbers_are_jumpers no)
		(fp_line
			(start -0.508 -0.9398)
			(end -0.508 0.9398)
			(stroke
				(width 0.1524)
				(type default)
			)
			(layer "F.SilkS")
		)
		(fp_line
			(start 0.508 -0.9398)
			(end -0.508 -0.9398)
			(stroke
				(width 0.1524)
				(type default)
			)
			(layer "F.SilkS")
		)
		(fp_rect
			(start -0.508 0.9398)
			(end 0.508 -0.9398)
			(stroke
				(width 0)
				(type default)
			)
			(fill no)
			(layer "F.CrtYd")
		)
		(fp_rect
			(start -0.508 0.9398)
			(end 0.508 -0.9398)
			(stroke
				(width 0)
				(type default)
			)
			(fill no)
			(layer "F.Fab")
		)
		(pad "1" smd custom
			(at 0 -0.4445)
			(size 0.1397 0.1397)
			(layers "F.Cu" "F.Mask" "F.Paste")
			(net "GND")
			(options
				(clearance outline)
				(anchor circle)
			)
			(primitives
				(gr_poly
					(pts
						(arc
							(start -0.1778 -0.2794)
							(mid -0.249642 -0.249642)
							(end -0.2794 -0.1778)
						)
						(arc
							(start -0.2794 0.1778)
							(mid -0.249642 0.249642)
							(end -0.1778 0.2794)
						)
						(arc
							(start 0.1778 0.2794)
							(mid 0.249642 0.249642)
							(end 0.2794 0.1778)
						)
						(arc
							(start 0.2794 -0.1778)
							(mid 0.249642 -0.249642)
							(end 0.1778 -0.2794)
						)
					)
					(width 0)
					(fill yes)
				)
			)
		)
		(pad "2" smd custom
			(at 0 0.4445)
			(size 0.1397 0.1397)
			(layers "F.Cu" "F.Mask" "F.Paste")
			(net "MAC2_TXD1")
			(options
				(clearance outline)
				(anchor circle)
			)
			(primitives
				(gr_poly
					(pts
						(arc
							(start -0.1778 -0.2794)
							(mid -0.249642 -0.249642)
							(end -0.2794 -0.1778)
						)
						(arc
							(start -0.2794 0.1778)
							(mid -0.249642 0.249642)
							(end -0.1778 0.2794)
						)
						(arc
							(start 0.1778 0.2794)
							(mid 0.249642 0.249642)
							(end 0.2794 0.1778)
						)
						(arc
							(start 0.2794 -0.1778)
							(mid 0.249642 -0.249642)
							(end 0.1778 -0.2794)
						)
					)
					(width 0)
					(fill yes)
				)
			)
		)
	)
	(footprint ""
		(layer "F.Cu")
		(at 168.617138 -9.171178)
		(property "Reference" "C216"
			(at 0 0 0)
			(layer "F.SilkS")
			(hide yes)
			(effects
				(font
					(size 1.27 1.27)
				)
			)
		)
		(property "Value" "SC10U6D3V5KX-4GP"
			(at -0.0762 -6.1214 0)
			(unlocked yes)
			(layer "F.Fab")
			(hide yes)
			(effects
				(font
					(size 1.016 1.016)
					(thickness 0.1524)
				)
			)
		)
		(property "Device Type" "C805H58"
			(at -0.0762 -8.1534 0)
			(unlocked yes)
			(layer "F.Fab")
			(hide yes)
			(effects
				(font
					(size 1.016 1.016)
					(thickness 0.1524)
				)
			)
		)
		(duplicate_pad_numbers_are_jumpers no)
		(fp_line
			(start 0.635 0)
			(end -0.635 0)
			(stroke
				(width 0.508)
				(type default)
			)
			(layer "F.SilkS")
		)
		(fp_rect
			(start -0.9652 1.778)
			(end 0.9652 -1.778)
			(stroke
				(width 0)
				(type default)
			)
			(fill no)
			(layer "F.CrtYd")
		)
		(fp_poly
			(pts
				(xy -0.9652 -1.778) (xy 0.9652 -1.778) (xy 0.9652 1.778) (xy -0.9652 1.778)
			)
			(stroke
				(width 0)
				(type default)
			)
			(fill no)
			(layer "F.Fab")
		)
		(pad "1" smd rect
			(at 0 -0.9652)
			(size 1.397 1.143)
			(layers "F.Cu" "F.Mask" "F.Paste")
			(net "P1V8_STBY")
		)
		(pad "2" smd rect
			(at 0 0.9652)
			(size 1.397 1.143)
			(layers "F.Cu" "F.Mask" "F.Paste")
			(net "GND")
		)
	)
	(footprint ""
		(layer "F.Cu")
		(at 80.6704 -154.5844)
		(property "Reference" "C239"
			(at 0 0 0)
			(layer "F.SilkS")
			(hide yes)
			(effects
				(font
					(size 1.27 1.27)
				)
			)
		)
		(property "Value" "SCD1U16V2KX-3GP"
			(at 1.1811 -2.7051 0)
			(unlocked yes)
			(layer "F.Fab")
			(hide yes)
			(effects
				(font
					(size 1.016 1.016)
					(thickness 0.1524)
				)
			)
		)
		(property "Device Type" "C402H22"
			(at 1.1811 -4.2291 0)
			(unlocked yes)
			(layer "F.Fab")
			(hide yes)
			(effects
				(font
					(size 1.016 1.016)
					(thickness 0.1524)
				)
			)
		)
		(duplicate_pad_numbers_are_jumpers no)
		(fp_rect
			(start -0.4318 0.9525)
			(end 0.4318 -0.9525)
			(stroke
				(width 0)
				(type default)
			)
			(fill no)
			(layer "F.CrtYd")
		)
		(fp_rect
			(start -0.4318 0.9525)
			(end 0.4318 -0.9525)
			(stroke
				(width 0)
				(type default)
			)
			(fill no)
			(layer "F.Fab")
		)
		(pad "1" smd custom
			(at 0 -0.4445)
			(size 0.1524 0.1524)
			(layers "F.Cu" "F.Mask" "F.Paste")
			(net "TPS74801_P1V15_STBY_OUT")
			(options
				(clearance outline)
				(anchor circle)
			)
			(primitives
				(gr_poly
					(pts
						(arc
							(start 0.3048 -0.2032)
							(mid 0.275042 -0.275042)
							(end 0.2032 -0.3048)
						)
						(arc
							(start -0.2032 -0.3048)
							(mid -0.275042 -0.275042)
							(end -0.3048 -0.2032)
						)
						(arc
							(start -0.3048 0.2032)
							(mid -0.275042 0.275042)
							(end -0.2032 0.3048)
						)
						(arc
							(start 0.2032 0.3048)
							(mid 0.275042 0.275042)
							(end 0.3048 0.2032)
						)
					)
					(width 0)
					(fill yes)
				)
			)
		)
		(pad "2" smd custom
			(at 0 0.4445)
			(size 0.1524 0.1524)
			(layers "F.Cu" "F.Mask" "F.Paste")
			(net "GND")
			(options
				(clearance outline)
				(anchor circle)
			)
			(primitives
				(gr_poly
					(pts
						(arc
							(start 0.3048 -0.2032)
							(mid 0.275042 -0.275042)
							(end 0.2032 -0.3048)
						)
						(arc
							(start -0.2032 -0.3048)
							(mid -0.275042 -0.275042)
							(end -0.3048 -0.2032)
						)
						(arc
							(start -0.3048 0.2032)
							(mid -0.275042 0.275042)
							(end -0.2032 0.3048)
						)
						(arc
							(start 0.2032 0.3048)
							(mid 0.275042 0.275042)
							(end 0.3048 0.2032)
						)
					)
					(width 0)
					(fill yes)
				)
			)
		)
	)
	(footprint ""
		(layer "F.Cu")
		(at 91.770708 -122.013472 90)
		(property "Reference" "R796"
			(at 0 0 90)
			(layer "F.SilkS")
			(hide yes)
			(effects
				(font
					(size 1.27 1.27)
				)
			)
		)
		(property "Value" "0R2J-2-GP"
			(at 0.064008 -3.993896 90)
			(unlocked yes)
			(layer "F.Fab")
			(hide yes)
			(effects
				(font
					(size 1.016 1.016)
					(thickness 0.1524)
				)
			)
		)
		(property "Device Type" "R402H16"
			(at 0.064008 -5.517896 90)
			(unlocked yes)
			(layer "F.Fab")
			(hide yes)
			(effects
				(font
					(size 1.016 1.016)
					(thickness 0.1524)
				)
			)
		)
		(duplicate_pad_numbers_are_jumpers no)
		(fp_line
			(start 0.508 -0.9398)
			(end -0.508 -0.9398)
			(stroke
				(width 0.1524)
				(type default)
			)
			(layer "F.SilkS")
		)
		(fp_line
			(start -0.508 -0.9398)
			(end -0.508 0.9398)
			(stroke
				(width 0.1524)
				(type default)
			)
			(layer "F.SilkS")
		)
		(fp_rect
			(start -0.508 0.9398)
			(end 0.508 -0.9398)
			(stroke
				(width 0)
				(type default)
			)
			(fill no)
			(layer "F.CrtYd")
		)
		(fp_rect
			(start -0.508 0.9398)
			(end 0.508 -0.9398)
			(stroke
				(width 0)
				(type default)
			)
			(fill no)
			(layer "F.Fab")
		)
		(pad "1" smd custom
			(at 0 -0.4445 90)
			(size 0.1397 0.1397)
			(layers "F.Cu" "F.Mask" "F.Paste")
			(net "UART_COMP_IN_RX")
			(options
				(clearance outline)
				(anchor circle)
			)
			(primitives
				(gr_poly
					(pts
						(arc
							(start -0.1778 -0.2794)
							(mid -0.249642 -0.249642)
							(end -0.2794 -0.1778)
						)
						(arc
							(start -0.2794 0.1778)
							(mid -0.249642 0.249642)
							(end -0.1778 0.2794)
						)
						(arc
							(start 0.1778 0.2794)
							(mid 0.249642 0.249642)
							(end 0.2794 0.1778)
						)
						(arc
							(start 0.2794 -0.1778)
							(mid 0.249642 -0.249642)
							(end 0.1778 -0.2794)
						)
					)
					(width 0)
					(fill yes)
				)
			)
		)
		(pad "2" smd custom
			(at 0 0.4445 90)
			(size 0.1397 0.1397)
			(layers "F.Cu" "F.Mask" "F.Paste")
			(net "UART_COMP_IN_R_RX")
			(options
				(clearance outline)
				(anchor circle)
			)
			(primitives
				(gr_poly
					(pts
						(arc
							(start -0.1778 -0.2794)
							(mid -0.249642 -0.249642)
							(end -0.2794 -0.1778)
						)
						(arc
							(start -0.2794 0.1778)
							(mid -0.249642 0.249642)
							(end -0.1778 0.2794)
						)
						(arc
							(start 0.1778 0.2794)
							(mid 0.249642 0.249642)
							(end 0.2794 0.1778)
						)
						(arc
							(start 0.2794 -0.1778)
							(mid 0.249642 -0.249642)
							(end 0.1778 -0.2794)
						)
					)
					(width 0)
					(fill yes)
				)
			)
		)
	)
	(footprint ""
		(layer "F.Cu")
		(at 219.447872 -53.483256 90)
		(property "Reference" "C161"
			(at 0 0 90)
			(layer "F.SilkS")
			(hide yes)
			(effects
				(font
					(size 1.27 1.27)
				)
			)
		)
		(property "Value" "SC1U16V3KX-5GP"
			(at 0 -2.8194 90)
			(unlocked yes)
			(layer "F.Fab")
			(hide yes)
			(effects
				(font
					(size 1.016 1.016)
					(thickness 0.1524)
				)
			)
		)
		(property "Device Type" "C603H36"
			(at 0 -4.3434 90)
			(unlocked yes)
			(layer "F.Fab")
			(hide yes)
			(effects
				(font
					(size 1.016 1.016)
					(thickness 0.1524)
				)
			)
		)
		(duplicate_pad_numbers_are_jumpers no)
		(fp_line
			(start 0.508 0)
			(end -0.508 0)
			(stroke
				(width 0.2032)
				(type default)
			)
			(layer "F.SilkS")
		)
		(fp_rect
			(start -0.5842 1.3335)
			(end 0.5842 -1.3335)
			(stroke
				(width 0)
				(type default)
			)
			(fill no)
			(layer "F.CrtYd")
		)
		(fp_rect
			(start -0.5842 1.3335)
			(end 0.5842 -1.3335)
			(stroke
				(width 0)
				(type default)
			)
			(fill no)
			(layer "F.Fab")
		)
		(pad "1" smd custom
			(at 0 -0.762 90)
			(size 0.2159 0.2159)
			(layers "F.Cu" "F.Mask" "F.Paste")
			(net "GND")
			(options
				(clearance outline)
				(anchor circle)
			)
			(primitives
				(gr_poly
					(pts
						(arc
							(start -0.3302 -0.4318)
							(mid -0.402042 -0.402042)
							(end -0.4318 -0.3302)
						)
						(arc
							(start -0.4318 0.3302)
							(mid -0.402042 0.402042)
							(end -0.3302 0.4318)
						)
						(arc
							(start 0.3302 0.4318)
							(mid 0.402042 0.402042)
							(end 0.4318 0.3302)
						)
						(arc
							(start 0.4318 -0.3302)
							(mid 0.402042 -0.402042)
							(end 0.3302 -0.4318)
						)
					)
					(width 0)
					(fill yes)
				)
			)
		)
		(pad "2" smd custom
			(at 0 0.762 90)
			(size 0.2159 0.2159)
			(layers "F.Cu" "F.Mask" "F.Paste")
			(net "P5V_STBY_VREG")
			(options
				(clearance outline)
				(anchor circle)
			)
			(primitives
				(gr_poly
					(pts
						(arc
							(start -0.3302 -0.4318)
							(mid -0.402042 -0.402042)
							(end -0.4318 -0.3302)
						)
						(arc
							(start -0.4318 0.3302)
							(mid -0.402042 0.402042)
							(end -0.3302 0.4318)
						)
						(arc
							(start 0.3302 0.4318)
							(mid 0.402042 0.402042)
							(end 0.4318 0.3302)
						)
						(arc
							(start 0.4318 -0.3302)
							(mid 0.402042 -0.402042)
							(end 0.3302 -0.4318)
						)
					)
					(width 0)
					(fill yes)
				)
			)
		)
	)
	(footprint ""
		(layer "F.Cu")
		(at 45.907706 -120.403874 90)
		(property "Reference" "R765"
			(at 0 0 90)
			(layer "F.SilkS")
			(hide yes)
			(effects
				(font
					(size 1.27 1.27)
				)
			)
		)
		(property "Value" "0R2J-2-GP"
			(at 0.064008 -3.993896 90)
			(unlocked yes)
			(layer "F.Fab")
			(hide yes)
			(effects
				(font
					(size 1.016 1.016)
					(thickness 0.1524)
				)
			)
		)
		(property "Device Type" "R402H16"
			(at 0.064008 -5.517896 90)
			(unlocked yes)
			(layer "F.Fab")
			(hide yes)
			(effects
				(font
					(size 1.016 1.016)
					(thickness 0.1524)
				)
			)
		)
		(duplicate_pad_numbers_are_jumpers no)
		(fp_line
			(start 0.508 -0.9398)
			(end -0.508 -0.9398)
			(stroke
				(width 0.1524)
				(type default)
			)
			(layer "F.SilkS")
		)
		(fp_line
			(start -0.508 -0.9398)
			(end -0.508 0.9398)
			(stroke
				(width 0.1524)
				(type default)
			)
			(layer "F.SilkS")
		)
		(fp_rect
			(start -0.508 0.9398)
			(end 0.508 -0.9398)
			(stroke
				(width 0)
				(type default)
			)
			(fill no)
			(layer "F.CrtYd")
		)
		(fp_rect
			(start -0.508 0.9398)
			(end 0.508 -0.9398)
			(stroke
				(width 0)
				(type default)
			)
			(fill no)
			(layer "F.Fab")
		)
		(pad "1" smd custom
			(at 0 -0.4445 90)
			(size 0.1397 0.1397)
			(layers "F.Cu" "F.Mask" "F.Paste")
			(net "FLA0_SPI_RST")
			(options
				(clearance outline)
				(anchor circle)
			)
			(primitives
				(gr_poly
					(pts
						(arc
							(start -0.1778 -0.2794)
							(mid -0.249642 -0.249642)
							(end -0.2794 -0.1778)
						)
						(arc
							(start -0.2794 0.1778)
							(mid -0.249642 0.249642)
							(end -0.1778 0.2794)
						)
						(arc
							(start 0.1778 0.2794)
							(mid 0.249642 0.249642)
							(end 0.2794 0.1778)
						)
						(arc
							(start 0.2794 -0.1778)
							(mid 0.249642 -0.249642)
							(end 0.1778 -0.2794)
						)
					)
					(width 0)
					(fill yes)
				)
			)
		)
		(pad "2" smd custom
			(at 0 0.4445 90)
			(size 0.1397 0.1397)
			(layers "F.Cu" "F.Mask" "F.Paste")
			(net "RST_BMC_EXTRST_N")
			(options
				(clearance outline)
				(anchor circle)
			)
			(primitives
				(gr_poly
					(pts
						(arc
							(start -0.1778 -0.2794)
							(mid -0.249642 -0.249642)
							(end -0.2794 -0.1778)
						)
						(arc
							(start -0.2794 0.1778)
							(mid -0.249642 0.249642)
							(end -0.1778 0.2794)
						)
						(arc
							(start 0.1778 0.2794)
							(mid 0.249642 0.249642)
							(end 0.2794 0.1778)
						)
						(arc
							(start 0.2794 -0.1778)
							(mid 0.249642 -0.249642)
							(end 0.1778 -0.2794)
						)
					)
					(width 0)
					(fill yes)
				)
			)
		)
	)
	(footprint ""
		(layer "F.Cu")
		(at 70.2056 -162.756088 90)
		(property "Reference" "C52"
			(at 0 0 90)
			(layer "F.SilkS")
			(hide yes)
			(effects
				(font
					(size 1.27 1.27)
				)
			)
		)
		(property "Value" "SCD1U16V2KX-3GP"
			(at 1.1811 -2.7051 90)
			(unlocked yes)
			(layer "F.Fab")
			(hide yes)
			(effects
				(font
					(size 1.016 1.016)
					(thickness 0.1524)
				)
			)
		)
		(property "Device Type" "C402H22"
			(at 1.1811 -4.2291 90)
			(unlocked yes)
			(layer "F.Fab")
			(hide yes)
			(effects
				(font
					(size 1.016 1.016)
					(thickness 0.1524)
				)
			)
		)
		(duplicate_pad_numbers_are_jumpers no)
		(fp_rect
			(start -0.4318 0.9525)
			(end 0.4318 -0.9525)
			(stroke
				(width 0)
				(type default)
			)
			(fill no)
			(layer "F.CrtYd")
		)
		(fp_rect
			(start -0.4318 0.9525)
			(end 0.4318 -0.9525)
			(stroke
				(width 0)
				(type default)
			)
			(fill no)
			(layer "F.Fab")
		)
		(pad "1" smd custom
			(at 0 -0.4445 90)
			(size 0.1524 0.1524)
			(layers "F.Cu" "F.Mask" "F.Paste")
			(net "BMC_TPM_RST_N")
			(options
				(clearance outline)
				(anchor circle)
			)
			(primitives
				(gr_poly
					(pts
						(arc
							(start 0.3048 -0.2032)
							(mid 0.275042 -0.275042)
							(end 0.2032 -0.3048)
						)
						(arc
							(start -0.2032 -0.3048)
							(mid -0.275042 -0.275042)
							(end -0.3048 -0.2032)
						)
						(arc
							(start -0.3048 0.2032)
							(mid -0.275042 0.275042)
							(end -0.2032 0.3048)
						)
						(arc
							(start 0.2032 0.3048)
							(mid 0.275042 0.275042)
							(end 0.3048 0.2032)
						)
					)
					(width 0)
					(fill yes)
				)
			)
		)
		(pad "2" smd custom
			(at 0 0.4445 90)
			(size 0.1524 0.1524)
			(layers "F.Cu" "F.Mask" "F.Paste")
			(net "GND")
			(options
				(clearance outline)
				(anchor circle)
			)
			(primitives
				(gr_poly
					(pts
						(arc
							(start 0.3048 -0.2032)
							(mid 0.275042 -0.275042)
							(end 0.2032 -0.3048)
						)
						(arc
							(start -0.2032 -0.3048)
							(mid -0.275042 -0.275042)
							(end -0.3048 -0.2032)
						)
						(arc
							(start -0.3048 0.2032)
							(mid -0.275042 0.275042)
							(end -0.2032 0.3048)
						)
						(arc
							(start 0.2032 0.3048)
							(mid 0.275042 0.275042)
							(end 0.3048 0.2032)
						)
					)
					(width 0)
					(fill yes)
				)
			)
		)
	)
	(footprint ""
		(layer "F.Cu")
		(at 158.124398 -8.312404)
		(property "Reference" "C210"
			(at 0 0 0)
			(layer "F.SilkS")
			(hide yes)
			(effects
				(font
					(size 1.27 1.27)
				)
			)
		)
		(property "Value" "SC2200P50V2KX-2GP"
			(at 1.1811 -2.7051 0)
			(unlocked yes)
			(layer "F.Fab")
			(hide yes)
			(effects
				(font
					(size 1.016 1.016)
					(thickness 0.1524)
				)
			)
		)
		(property "Device Type" "C402H22"
			(at 1.1811 -4.2291 0)
			(unlocked yes)
			(layer "F.Fab")
			(hide yes)
			(effects
				(font
					(size 1.016 1.016)
					(thickness 0.1524)
				)
			)
		)
		(duplicate_pad_numbers_are_jumpers no)
		(fp_rect
			(start -0.4318 0.9525)
			(end 0.4318 -0.9525)
			(stroke
				(width 0)
				(type default)
			)
			(fill no)
			(layer "F.CrtYd")
		)
		(fp_rect
			(start -0.4318 0.9525)
			(end 0.4318 -0.9525)
			(stroke
				(width 0)
				(type default)
			)
			(fill no)
			(layer "F.Fab")
		)
		(pad "1" smd custom
			(at 0 -0.4445)
			(size 0.1524 0.1524)
			(layers "F.Cu" "F.Mask" "F.Paste")
			(net "P1V8_STBY_SW")
			(options
				(clearance outline)
				(anchor circle)
			)
			(primitives
				(gr_poly
					(pts
						(arc
							(start 0.3048 -0.2032)
							(mid 0.275042 -0.275042)
							(end 0.2032 -0.3048)
						)
						(arc
							(start -0.2032 -0.3048)
							(mid -0.275042 -0.275042)
							(end -0.3048 -0.2032)
						)
						(arc
							(start -0.3048 0.2032)
							(mid -0.275042 0.275042)
							(end -0.2032 0.3048)
						)
						(arc
							(start 0.2032 0.3048)
							(mid 0.275042 0.275042)
							(end 0.3048 0.2032)
						)
					)
					(width 0)
					(fill yes)
				)
			)
		)
		(pad "2" smd custom
			(at 0 0.4445)
			(size 0.1524 0.1524)
			(layers "F.Cu" "F.Mask" "F.Paste")
			(net "P1V8_STBY_SNB")
			(options
				(clearance outline)
				(anchor circle)
			)
			(primitives
				(gr_poly
					(pts
						(arc
							(start 0.3048 -0.2032)
							(mid 0.275042 -0.275042)
							(end 0.2032 -0.3048)
						)
						(arc
							(start -0.2032 -0.3048)
							(mid -0.275042 -0.275042)
							(end -0.3048 -0.2032)
						)
						(arc
							(start -0.3048 0.2032)
							(mid -0.275042 0.275042)
							(end -0.2032 0.3048)
						)
						(arc
							(start 0.2032 0.3048)
							(mid 0.275042 0.275042)
							(end 0.3048 0.2032)
						)
					)
					(width 0)
					(fill yes)
				)
			)
		)
	)
	(footprint ""
		(layer "F.Cu")
		(at 69.55028 -181.76748 -90)
		(property "Reference" "C201"
			(at 0 0 270)
			(layer "F.SilkS")
			(hide yes)
			(effects
				(font
					(size 1.27 1.27)
				)
			)
		)
		(property "Value" "SCD1U16V2KX-3GP"
			(at 1.1811 -2.7051 270)
			(unlocked yes)
			(layer "F.Fab")
			(hide yes)
			(effects
				(font
					(size 1.016 1.016)
					(thickness 0.1524)
				)
			)
		)
		(property "Device Type" "C402H22"
			(at 1.1811 -4.2291 270)
			(unlocked yes)
			(layer "F.Fab")
			(hide yes)
			(effects
				(font
					(size 1.016 1.016)
					(thickness 0.1524)
				)
			)
		)
		(duplicate_pad_numbers_are_jumpers no)
		(fp_rect
			(start -0.4318 0.9525)
			(end 0.4318 -0.9525)
			(stroke
				(width 0)
				(type default)
			)
			(fill no)
			(layer "F.CrtYd")
		)
		(fp_rect
			(start -0.4318 0.9525)
			(end 0.4318 -0.9525)
			(stroke
				(width 0)
				(type default)
			)
			(fill no)
			(layer "F.Fab")
		)
		(pad "1" smd custom
			(at 0 -0.4445 270)
			(size 0.1524 0.1524)
			(layers "F.Cu" "F.Mask" "F.Paste")
			(net "TPS74801_P2V5_STBY_EN")
			(options
				(clearance outline)
				(anchor circle)
			)
			(primitives
				(gr_poly
					(pts
						(arc
							(start 0.3048 -0.2032)
							(mid 0.275042 -0.275042)
							(end 0.2032 -0.3048)
						)
						(arc
							(start -0.2032 -0.3048)
							(mid -0.275042 -0.275042)
							(end -0.3048 -0.2032)
						)
						(arc
							(start -0.3048 0.2032)
							(mid -0.275042 0.275042)
							(end -0.2032 0.3048)
						)
						(arc
							(start 0.2032 0.3048)
							(mid 0.275042 0.275042)
							(end 0.3048 0.2032)
						)
					)
					(width 0)
					(fill yes)
				)
			)
		)
		(pad "2" smd custom
			(at 0 0.4445 270)
			(size 0.1524 0.1524)
			(layers "F.Cu" "F.Mask" "F.Paste")
			(net "GND")
			(options
				(clearance outline)
				(anchor circle)
			)
			(primitives
				(gr_poly
					(pts
						(arc
							(start 0.3048 -0.2032)
							(mid 0.275042 -0.275042)
							(end 0.2032 -0.3048)
						)
						(arc
							(start -0.2032 -0.3048)
							(mid -0.275042 -0.275042)
							(end -0.3048 -0.2032)
						)
						(arc
							(start -0.3048 0.2032)
							(mid -0.275042 0.275042)
							(end -0.2032 0.3048)
						)
						(arc
							(start 0.2032 0.3048)
							(mid 0.275042 0.275042)
							(end 0.3048 0.2032)
						)
					)
					(width 0)
					(fill yes)
				)
			)
		)
	)
	(footprint ""
		(layer "F.Cu")
		(at 30.3022 -131.2164)
		(property "Reference" "C79"
			(at 0 0 0)
			(layer "F.SilkS")
			(hide yes)
			(effects
				(font
					(size 1.27 1.27)
				)
			)
		)
		(property "Value" "SCD1U16V2KX-3GP"
			(at 1.1811 -2.7051 0)
			(unlocked yes)
			(layer "F.Fab")
			(hide yes)
			(effects
				(font
					(size 1.016 1.016)
					(thickness 0.1524)
				)
			)
		)
		(property "Device Type" "C402H22"
			(at 1.1811 -4.2291 0)
			(unlocked yes)
			(layer "F.Fab")
			(hide yes)
			(effects
				(font
					(size 1.016 1.016)
					(thickness 0.1524)
				)
			)
		)
		(duplicate_pad_numbers_are_jumpers no)
		(fp_rect
			(start -0.4318 0.9525)
			(end 0.4318 -0.9525)
			(stroke
				(width 0)
				(type default)
			)
			(fill no)
			(layer "F.CrtYd")
		)
		(fp_rect
			(start -0.4318 0.9525)
			(end 0.4318 -0.9525)
			(stroke
				(width 0)
				(type default)
			)
			(fill no)
			(layer "F.Fab")
		)
		(pad "1" smd custom
			(at 0 -0.4445)
			(size 0.1524 0.1524)
			(layers "F.Cu" "F.Mask" "F.Paste")
			(net "P3V3_STBY")
			(options
				(clearance outline)
				(anchor circle)
			)
			(primitives
				(gr_poly
					(pts
						(arc
							(start 0.3048 -0.2032)
							(mid 0.275042 -0.275042)
							(end 0.2032 -0.3048)
						)
						(arc
							(start -0.2032 -0.3048)
							(mid -0.275042 -0.275042)
							(end -0.3048 -0.2032)
						)
						(arc
							(start -0.3048 0.2032)
							(mid -0.275042 0.275042)
							(end -0.2032 0.3048)
						)
						(arc
							(start 0.2032 0.3048)
							(mid 0.275042 0.275042)
							(end 0.3048 0.2032)
						)
					)
					(width 0)
					(fill yes)
				)
			)
		)
		(pad "2" smd custom
			(at 0 0.4445)
			(size 0.1524 0.1524)
			(layers "F.Cu" "F.Mask" "F.Paste")
			(net "GND")
			(options
				(clearance outline)
				(anchor circle)
			)
			(primitives
				(gr_poly
					(pts
						(arc
							(start 0.3048 -0.2032)
							(mid 0.275042 -0.275042)
							(end 0.2032 -0.3048)
						)
						(arc
							(start -0.2032 -0.3048)
							(mid -0.275042 -0.275042)
							(end -0.3048 -0.2032)
						)
						(arc
							(start -0.3048 0.2032)
							(mid -0.275042 0.275042)
							(end -0.2032 0.3048)
						)
						(arc
							(start 0.2032 0.3048)
							(mid 0.275042 0.275042)
							(end 0.3048 0.2032)
						)
					)
					(width 0)
					(fill yes)
				)
			)
		)
	)
	(footprint ""
		(layer "F.Cu")
		(at 66.757042 -159.104584)
		(property "Reference" "R775"
			(at 0 0 0)
			(layer "F.SilkS")
			(hide yes)
			(effects
				(font
					(size 1.27 1.27)
				)
			)
		)
		(property "Value" "1KR2F-3-GP"
			(at 0.064008 -3.993896 0)
			(unlocked yes)
			(layer "F.Fab")
			(hide yes)
			(effects
				(font
					(size 1.016 1.016)
					(thickness 0.1524)
				)
			)
		)
		(property "Device Type" "R402H16"
			(at 0.064008 -5.517896 0)
			(unlocked yes)
			(layer "F.Fab")
			(hide yes)
			(effects
				(font
					(size 1.016 1.016)
					(thickness 0.1524)
				)
			)
		)
		(duplicate_pad_numbers_are_jumpers no)
		(fp_line
			(start -0.508 -0.9398)
			(end -0.508 0.9398)
			(stroke
				(width 0.1524)
				(type default)
			)
			(layer "F.SilkS")
		)
		(fp_line
			(start 0.508 -0.9398)
			(end -0.508 -0.9398)
			(stroke
				(width 0.1524)
				(type default)
			)
			(layer "F.SilkS")
		)
		(fp_rect
			(start -0.508 0.9398)
			(end 0.508 -0.9398)
			(stroke
				(width 0)
				(type default)
			)
			(fill no)
			(layer "F.CrtYd")
		)
		(fp_rect
			(start -0.508 0.9398)
			(end 0.508 -0.9398)
			(stroke
				(width 0)
				(type default)
			)
			(fill no)
			(layer "F.Fab")
		)
		(pad "1" smd custom
			(at 0 -0.4445)
			(size 0.1397 0.1397)
			(layers "F.Cu" "F.Mask" "F.Paste")
			(net "ADC_P1V15_STBY")
			(options
				(clearance outline)
				(anchor circle)
			)
			(primitives
				(gr_poly
					(pts
						(arc
							(start -0.1778 -0.2794)
							(mid -0.249642 -0.249642)
							(end -0.2794 -0.1778)
						)
						(arc
							(start -0.2794 0.1778)
							(mid -0.249642 0.249642)
							(end -0.1778 0.2794)
						)
						(arc
							(start 0.1778 0.2794)
							(mid 0.249642 0.249642)
							(end 0.2794 0.1778)
						)
						(arc
							(start 0.2794 -0.1778)
							(mid 0.249642 -0.249642)
							(end 0.1778 -0.2794)
						)
					)
					(width 0)
					(fill yes)
				)
			)
		)
		(pad "2" smd custom
			(at 0 0.4445)
			(size 0.1397 0.1397)
			(layers "F.Cu" "F.Mask" "F.Paste")
			(net "GND")
			(options
				(clearance outline)
				(anchor circle)
			)
			(primitives
				(gr_poly
					(pts
						(arc
							(start -0.1778 -0.2794)
							(mid -0.249642 -0.249642)
							(end -0.2794 -0.1778)
						)
						(arc
							(start -0.2794 0.1778)
							(mid -0.249642 0.249642)
							(end -0.1778 0.2794)
						)
						(arc
							(start 0.1778 0.2794)
							(mid 0.249642 0.249642)
							(end 0.2794 0.1778)
						)
						(arc
							(start 0.2794 -0.1778)
							(mid 0.249642 -0.249642)
							(end 0.1778 -0.2794)
						)
					)
					(width 0)
					(fill yes)
				)
			)
		)
	)
	(footprint ""
		(layer "F.Cu")
		(at 98.298 -172.6692 -90)
		(property "Reference" "R123"
			(at 0 0 270)
			(layer "F.SilkS")
			(hide yes)
			(effects
				(font
					(size 1.27 1.27)
				)
			)
		)
		(property "Value" "0R2J-2-GP"
			(at 0.064008 -3.993896 270)
			(unlocked yes)
			(layer "F.Fab")
			(hide yes)
			(effects
				(font
					(size 1.016 1.016)
					(thickness 0.1524)
				)
			)
		)
		(property "Device Type" "R402H16"
			(at 0.064008 -5.517896 270)
			(unlocked yes)
			(layer "F.Fab")
			(hide yes)
			(effects
				(font
					(size 1.016 1.016)
					(thickness 0.1524)
				)
			)
		)
		(duplicate_pad_numbers_are_jumpers no)
		(fp_line
			(start -0.508 -0.9398)
			(end -0.508 0.9398)
			(stroke
				(width 0.1524)
				(type default)
			)
			(layer "F.SilkS")
		)
		(fp_line
			(start 0.508 -0.9398)
			(end -0.508 -0.9398)
			(stroke
				(width 0.1524)
				(type default)
			)
			(layer "F.SilkS")
		)
		(fp_rect
			(start -0.508 0.9398)
			(end 0.508 -0.9398)
			(stroke
				(width 0)
				(type default)
			)
			(fill no)
			(layer "F.CrtYd")
		)
		(fp_rect
			(start -0.508 0.9398)
			(end 0.508 -0.9398)
			(stroke
				(width 0)
				(type default)
			)
			(fill no)
			(layer "F.Fab")
		)
		(pad "1" smd custom
			(at 0 -0.4445 270)
			(size 0.1397 0.1397)
			(layers "F.Cu" "F.Mask" "F.Paste")
			(net "I2C_DPB_MISC_SDA")
			(options
				(clearance outline)
				(anchor circle)
			)
			(primitives
				(gr_poly
					(pts
						(arc
							(start -0.1778 -0.2794)
							(mid -0.249642 -0.249642)
							(end -0.2794 -0.1778)
						)
						(arc
							(start -0.2794 0.1778)
							(mid -0.249642 0.249642)
							(end -0.1778 0.2794)
						)
						(arc
							(start 0.1778 0.2794)
							(mid 0.249642 0.249642)
							(end 0.2794 0.1778)
						)
						(arc
							(start 0.2794 -0.1778)
							(mid 0.249642 -0.249642)
							(end 0.1778 -0.2794)
						)
					)
					(width 0)
					(fill yes)
				)
			)
		)
		(pad "2" smd custom
			(at 0 0.4445 270)
			(size 0.1397 0.1397)
			(layers "F.Cu" "F.Mask" "F.Paste")
			(net "I2C_DPB_MISC_SDA_R")
			(options
				(clearance outline)
				(anchor circle)
			)
			(primitives
				(gr_poly
					(pts
						(arc
							(start -0.1778 -0.2794)
							(mid -0.249642 -0.249642)
							(end -0.2794 -0.1778)
						)
						(arc
							(start -0.2794 0.1778)
							(mid -0.249642 0.249642)
							(end -0.1778 0.2794)
						)
						(arc
							(start 0.1778 0.2794)
							(mid 0.249642 0.249642)
							(end 0.2794 0.1778)
						)
						(arc
							(start 0.2794 -0.1778)
							(mid 0.249642 -0.249642)
							(end 0.1778 -0.2794)
						)
					)
					(width 0)
					(fill yes)
				)
			)
		)
	)
	(footprint ""
		(layer "F.Cu")
		(at 60.301886 -133.2738 -90)
		(property "Reference" "R290"
			(at 0 0 270)
			(layer "F.SilkS")
			(hide yes)
			(effects
				(font
					(size 1.27 1.27)
				)
			)
		)
		(property "Value" "0R2J-2-GP"
			(at 0.064008 -3.993896 270)
			(unlocked yes)
			(layer "F.Fab")
			(hide yes)
			(effects
				(font
					(size 1.016 1.016)
					(thickness 0.1524)
				)
			)
		)
		(property "Device Type" "R402H16"
			(at 0.064008 -5.517896 270)
			(unlocked yes)
			(layer "F.Fab")
			(hide yes)
			(effects
				(font
					(size 1.016 1.016)
					(thickness 0.1524)
				)
			)
		)
		(duplicate_pad_numbers_are_jumpers no)
		(fp_line
			(start -0.508 -0.9398)
			(end -0.508 0.9398)
			(stroke
				(width 0.1524)
				(type default)
			)
			(layer "F.SilkS")
		)
		(fp_line
			(start 0.508 -0.9398)
			(end -0.508 -0.9398)
			(stroke
				(width 0.1524)
				(type default)
			)
			(layer "F.SilkS")
		)
		(fp_rect
			(start -0.508 0.9398)
			(end 0.508 -0.9398)
			(stroke
				(width 0)
				(type default)
			)
			(fill no)
			(layer "F.CrtYd")
		)
		(fp_rect
			(start -0.508 0.9398)
			(end 0.508 -0.9398)
			(stroke
				(width 0)
				(type default)
			)
			(fill no)
			(layer "F.Fab")
		)
		(pad "1" smd custom
			(at 0 -0.4445 270)
			(size 0.1397 0.1397)
			(layers "F.Cu" "F.Mask" "F.Paste")
			(net "SCC_STBY_PWR_EN")
			(options
				(clearance outline)
				(anchor circle)
			)
			(primitives
				(gr_poly
					(pts
						(arc
							(start -0.1778 -0.2794)
							(mid -0.249642 -0.249642)
							(end -0.2794 -0.1778)
						)
						(arc
							(start -0.2794 0.1778)
							(mid -0.249642 0.249642)
							(end -0.1778 0.2794)
						)
						(arc
							(start 0.1778 0.2794)
							(mid 0.249642 0.249642)
							(end 0.2794 0.1778)
						)
						(arc
							(start 0.2794 -0.1778)
							(mid 0.249642 -0.249642)
							(end 0.1778 -0.2794)
						)
					)
					(width 0)
					(fill yes)
				)
			)
		)
		(pad "2" smd custom
			(at 0 0.4445 270)
			(size 0.1397 0.1397)
			(layers "F.Cu" "F.Mask" "F.Paste")
			(net "SCC_PWR_EN_R")
			(options
				(clearance outline)
				(anchor circle)
			)
			(primitives
				(gr_poly
					(pts
						(arc
							(start -0.1778 -0.2794)
							(mid -0.249642 -0.249642)
							(end -0.2794 -0.1778)
						)
						(arc
							(start -0.2794 0.1778)
							(mid -0.249642 0.249642)
							(end -0.1778 0.2794)
						)
						(arc
							(start 0.1778 0.2794)
							(mid 0.249642 0.249642)
							(end 0.2794 0.1778)
						)
						(arc
							(start 0.2794 -0.1778)
							(mid 0.249642 -0.249642)
							(end 0.1778 -0.2794)
						)
					)
					(width 0)
					(fill yes)
				)
			)
		)
	)
	(footprint ""
		(layer "F.Cu")
		(at 226.596702 -51.1429 90)
		(property "Reference" "C152"
			(at 0 0 90)
			(layer "F.SilkS")
			(hide yes)
			(effects
				(font
					(size 1.27 1.27)
				)
			)
		)
		(property "Value" "SC10U16V5KX-7-GP-U"
			(at -0.0762 -6.1214 90)
			(unlocked yes)
			(layer "F.Fab")
			(hide yes)
			(effects
				(font
					(size 1.016 1.016)
					(thickness 0.1524)
				)
			)
		)
		(property "Device Type" "C805H58"
			(at -0.0762 -8.1534 90)
			(unlocked yes)
			(layer "F.Fab")
			(hide yes)
			(effects
				(font
					(size 1.016 1.016)
					(thickness 0.1524)
				)
			)
		)
		(duplicate_pad_numbers_are_jumpers no)
		(fp_line
			(start 0.635 0)
			(end -0.635 0)
			(stroke
				(width 0.508)
				(type default)
			)
			(layer "F.SilkS")
		)
		(fp_rect
			(start -0.9652 1.778)
			(end 0.9652 -1.778)
			(stroke
				(width 0)
				(type default)
			)
			(fill no)
			(layer "F.CrtYd")
		)
		(fp_poly
			(pts
				(xy -0.9652 -1.778) (xy 0.9652 -1.778) (xy 0.9652 1.778) (xy -0.9652 1.778)
			)
			(stroke
				(width 0)
				(type default)
			)
			(fill no)
			(layer "F.Fab")
		)
		(pad "1" smd rect
			(at 0 -0.9652 90)
			(size 1.397 1.143)
			(layers "F.Cu" "F.Mask" "F.Paste")
			(net "P12V_STBY_VIN_PU1")
		)
		(pad "2" smd rect
			(at 0 0.9652 90)
			(size 1.397 1.143)
			(layers "F.Cu" "F.Mask" "F.Paste")
			(net "GND")
		)
	)
	(footprint ""
		(layer "F.Cu")
		(at 77.8002 -162.2044 -90)
		(property "Reference" "PU11"
			(at 0 0 270)
			(layer "F.SilkS")
			(hide yes)
			(effects
				(font
					(size 1.27 1.27)
				)
			)
		)
		(property "Value" "TPS74801RGW-GP"
			(at -4.7244 -6.223 270)
			(unlocked yes)
			(layer "F.Fab")
			(hide yes)
			(effects
				(font
					(size 1.016 1.016)
					(thickness 0.1524)
				)
			)
		)
		(property "Device Type" "QFN20-1G3D15H40"
			(at -4.7244 -7.747 270)
			(unlocked yes)
			(layer "F.Fab")
			(hide yes)
			(effects
				(font
					(size 1.016 1.016)
					(thickness 0.1524)
				)
			)
		)
		(duplicate_pad_numbers_are_jumpers no)
		(fp_line
			(start -3.5179 3.5179)
			(end -2.2479 3.5179)
			(stroke
				(width 0.1524)
				(type default)
			)
			(layer "F.SilkS")
		)
		(fp_line
			(start 2.2479 3.5179)
			(end 3.5179 3.5179)
			(stroke
				(width 0.1524)
				(type default)
			)
			(layer "F.SilkS")
		)
		(fp_line
			(start 3.5179 3.5179)
			(end 3.5179 2.2479)
			(stroke
				(width 0.1524)
				(type default)
			)
			(layer "F.SilkS")
		)
		(fp_line
			(start 1.299972 3.160522)
			(end 1.299972 3.668522)
			(stroke
				(width 0.1524)
				(type default)
			)
			(layer "F.SilkS")
		)
		(fp_line
			(start -3.5179 2.2479)
			(end -3.5179 3.5179)
			(stroke
				(width 0.1524)
				(type default)
			)
			(layer "F.SilkS")
		)
		(fp_line
			(start -3.160522 1.299972)
			(end -3.922522 1.299972)
			(stroke
				(width 0.1524)
				(type default)
			)
			(layer "F.SilkS")
		)
		(fp_line
			(start 3.160522 -1.299972)
			(end 3.922522 -1.299972)
			(stroke
				(width 0.1524)
				(type default)
			)
			(layer "F.SilkS")
		)
		(fp_line
			(start -1.299972 -3.160522)
			(end -1.299972 -3.668522)
			(stroke
				(width 0.1524)
				(type default)
			)
			(layer "F.SilkS")
		)
		(fp_line
			(start -3.5179 -3.5179)
			(end -3.5179 -2.2479)
			(stroke
				(width 0.1524)
				(type default)
			)
			(layer "F.SilkS")
		)
		(fp_line
			(start -2.2479 -3.5179)
			(end -3.5179 -3.5179)
			(stroke
				(width 0.1524)
				(type default)
			)
			(layer "F.SilkS")
		)
		(fp_poly
			(pts
				(xy 3.5179 -3.5179) (xy 2.2479 -3.5179) (xy 3.5179 -2.2479)
			)
			(stroke
				(width 0)
				(type default)
			)
			(fill yes)
			(layer "F.SilkS")
		)
		(fp_rect
			(start -2.5019 2.5019)
			(end 2.5019 -2.5019)
			(stroke
				(width 0)
				(type default)
			)
			(fill no)
			(layer "F.CrtYd")
		)
		(fp_poly
			(pts
				(xy -3.5179 3.5179) (xy -3.5179 -3.5179) (xy 3.5179 -3.5179) (xy 3.5179 -2.5019) (xy -2.5019 -2.5019)
				(xy -2.5019 2.5019) (xy 2.5019 2.5019) (xy 2.5019 -2.49682) (xy 3.5179 -2.49682) (xy 3.5179 3.5179)
			)
			(stroke
				(width 0)
				(type default)
			)
			(fill no)
			(layer "F.CrtYd")
		)
		(fp_rect
			(start -3.5179 3.5179)
			(end 3.5179 -3.5179)
			(stroke
				(width 0)
				(type default)
			)
			(fill no)
			(layer "F.Fab")
		)
		(pad "1" smd rect
			(at 1.299972 -2.474722 270)
			(size 0.3556 1.0668)
			(layers "F.Cu" "F.Mask" "F.Paste")
			(net "TPS74801_P1V15_STBY_OUT")
		)
		(pad "2" smd rect
			(at 0.649986 -2.474722 270)
			(size 0.3556 1.0668)
			(layers "F.Cu" "F.Mask" "F.Paste")
			(net "GND")
		)
		(pad "3" smd rect
			(at 0 -2.474722 270)
			(size 0.3556 1.0668)
			(layers "F.Cu" "F.Mask" "F.Paste")
			(net "GND")
		)
		(pad "4" smd rect
			(at -0.649986 -2.474722 270)
			(size 0.3556 1.0668)
			(layers "F.Cu" "F.Mask" "F.Paste")
			(net "GND")
		)
		(pad "5" smd rect
			(at -1.299972 -2.474722 270)
			(size 0.3556 1.0668)
			(layers "F.Cu" "F.Mask" "F.Paste")
			(net "P1V8_STBY")
		)
		(pad "6" smd rect
			(at -2.474722 -1.299972 270)
			(size 1.0668 0.3556)
			(layers "F.Cu" "F.Mask" "F.Paste")
			(net "P1V8_STBY")
		)
		(pad "7" smd rect
			(at -2.474722 -0.649986 270)
			(size 1.0668 0.3556)
			(layers "F.Cu" "F.Mask" "F.Paste")
			(net "P1V8_STBY")
		)
		(pad "8" smd rect
			(at -2.474722 0 270)
			(size 1.0668 0.3556)
			(layers "F.Cu" "F.Mask" "F.Paste")
			(net "P1V8_STBY")
		)
		(pad "9" smd rect
			(at -2.474722 0.649986 270)
			(size 1.0668 0.3556)
			(layers "F.Cu" "F.Mask" "F.Paste")
			(net "P1V15_STBY_PG")
		)
		(pad "10" smd rect
			(at -2.474722 1.299972 270)
			(size 1.0668 0.3556)
			(layers "F.Cu" "F.Mask" "F.Paste")
			(net "TPS74801_P1V15_STBY_BIAS")
		)
		(pad "11" smd rect
			(at -1.299972 2.474722 270)
			(size 0.3556 1.0668)
			(layers "F.Cu" "F.Mask" "F.Paste")
			(net "TPS74801_P1V15_STBY_EN")
		)
		(pad "12" smd rect
			(at -0.649986 2.474722 270)
			(size 0.3556 1.0668)
			(layers "F.Cu" "F.Mask" "F.Paste")
			(net "GND")
		)
		(pad "13" smd rect
			(at 0 2.474722 270)
			(size 0.3556 1.0668)
			(layers "F.Cu" "F.Mask" "F.Paste")
			(net "GND")
		)
		(pad "14" smd rect
			(at 0.649986 2.474722 270)
			(size 0.3556 1.0668)
			(layers "F.Cu" "F.Mask" "F.Paste")
			(net "GND")
		)
		(pad "15" smd rect
			(at 1.299972 2.474722 270)
			(size 0.3556 1.0668)
			(layers "F.Cu" "F.Mask" "F.Paste")
			(net "TPS74801_P1V15_STBY_SS")
		)
		(pad "16" smd rect
			(at 2.474722 1.299972 270)
			(size 1.0668 0.3556)
			(layers "F.Cu" "F.Mask" "F.Paste")
			(net "TPS74801_P1V15_STBY_FB")
		)
		(pad "17" smd rect
			(at 2.474722 0.649986 270)
			(size 1.0668 0.3556)
			(layers "F.Cu" "F.Mask" "F.Paste")
			(net "GND")
		)
		(pad "18" smd rect
			(at 2.474722 0 270)
			(size 1.0668 0.3556)
			(layers "F.Cu" "F.Mask" "F.Paste")
			(net "TPS74801_P1V15_STBY_OUT")
		)
		(pad "19" smd rect
			(at 2.474722 -0.649986 270)
			(size 1.0668 0.3556)
			(layers "F.Cu" "F.Mask" "F.Paste")
			(net "TPS74801_P1V15_STBY_OUT")
		)
		(pad "20" smd rect
			(at 2.474722 -1.299972 270)
			(size 1.0668 0.3556)
			(layers "F.Cu" "F.Mask" "F.Paste")
			(net "TPS74801_P1V15_STBY_OUT")
		)
		(pad "21" smd rect
			(at 0 0 270)
			(size 3.2512 3.2512)
			(layers "F.Cu" "F.Mask" "F.Paste")
			(net "GND")
		)
	)
	(footprint ""
		(layer "F.Cu")
		(at 77.407262 -157.6197 90)
		(property "Reference" "R538"
			(at 0 0 90)
			(layer "F.SilkS")
			(hide yes)
			(effects
				(font
					(size 1.27 1.27)
				)
			)
		)
		(property "Value" "4K64R2F-GP"
			(at 0.064008 -3.993896 90)
			(unlocked yes)
			(layer "F.Fab")
			(hide yes)
			(effects
				(font
					(size 1.016 1.016)
					(thickness 0.1524)
				)
			)
		)
		(property "Device Type" "R402H16"
			(at 0.064008 -5.517896 90)
			(unlocked yes)
			(layer "F.Fab")
			(hide yes)
			(effects
				(font
					(size 1.016 1.016)
					(thickness 0.1524)
				)
			)
		)
		(duplicate_pad_numbers_are_jumpers no)
		(fp_line
			(start 0.508 -0.9398)
			(end -0.508 -0.9398)
			(stroke
				(width 0.1524)
				(type default)
			)
			(layer "F.SilkS")
		)
		(fp_line
			(start -0.508 -0.9398)
			(end -0.508 0.9398)
			(stroke
				(width 0.1524)
				(type default)
			)
			(layer "F.SilkS")
		)
		(fp_rect
			(start -0.508 0.9398)
			(end 0.508 -0.9398)
			(stroke
				(width 0)
				(type default)
			)
			(fill no)
			(layer "F.CrtYd")
		)
		(fp_rect
			(start -0.508 0.9398)
			(end 0.508 -0.9398)
			(stroke
				(width 0)
				(type default)
			)
			(fill no)
			(layer "F.Fab")
		)
		(pad "1" smd custom
			(at 0 -0.4445 90)
			(size 0.1397 0.1397)
			(layers "F.Cu" "F.Mask" "F.Paste")
			(net "TPS74801_P1V15_STBY_FB")
			(options
				(clearance outline)
				(anchor circle)
			)
			(primitives
				(gr_poly
					(pts
						(arc
							(start -0.1778 -0.2794)
							(mid -0.249642 -0.249642)
							(end -0.2794 -0.1778)
						)
						(arc
							(start -0.2794 0.1778)
							(mid -0.249642 0.249642)
							(end -0.1778 0.2794)
						)
						(arc
							(start 0.1778 0.2794)
							(mid 0.249642 0.249642)
							(end 0.2794 0.1778)
						)
						(arc
							(start 0.2794 -0.1778)
							(mid 0.249642 -0.249642)
							(end 0.1778 -0.2794)
						)
					)
					(width 0)
					(fill yes)
				)
			)
		)
		(pad "2" smd custom
			(at 0 0.4445 90)
			(size 0.1397 0.1397)
			(layers "F.Cu" "F.Mask" "F.Paste")
			(net "GND")
			(options
				(clearance outline)
				(anchor circle)
			)
			(primitives
				(gr_poly
					(pts
						(arc
							(start -0.1778 -0.2794)
							(mid -0.249642 -0.249642)
							(end -0.2794 -0.1778)
						)
						(arc
							(start -0.2794 0.1778)
							(mid -0.249642 0.249642)
							(end -0.1778 0.2794)
						)
						(arc
							(start 0.1778 0.2794)
							(mid 0.249642 0.249642)
							(end 0.2794 0.1778)
						)
						(arc
							(start 0.2794 -0.1778)
							(mid 0.249642 -0.249642)
							(end 0.1778 -0.2794)
						)
					)
					(width 0)
					(fill yes)
				)
			)
		)
	)
	(footprint ""
		(layer "F.Cu")
		(at 55.6768 -162.687 180)
		(property "Reference" "R405"
			(at 0 0 180)
			(layer "F.SilkS")
			(hide yes)
			(effects
				(font
					(size 1.27 1.27)
				)
			)
		)
		(property "Value" "1KR2F-3-GP"
			(at 0.064008 -3.993896 180)
			(unlocked yes)
			(layer "F.Fab")
			(hide yes)
			(effects
				(font
					(size 1.016 1.016)
					(thickness 0.1524)
				)
			)
		)
		(property "Device Type" "R402H16"
			(at 0.064008 -5.517896 180)
			(unlocked yes)
			(layer "F.Fab")
			(hide yes)
			(effects
				(font
					(size 1.016 1.016)
					(thickness 0.1524)
				)
			)
		)
		(duplicate_pad_numbers_are_jumpers no)
		(fp_line
			(start 0.508 -0.9398)
			(end -0.508 -0.9398)
			(stroke
				(width 0.1524)
				(type default)
			)
			(layer "F.SilkS")
		)
		(fp_line
			(start -0.508 -0.9398)
			(end -0.508 0.9398)
			(stroke
				(width 0.1524)
				(type default)
			)
			(layer "F.SilkS")
		)
		(fp_rect
			(start -0.508 0.9398)
			(end 0.508 -0.9398)
			(stroke
				(width 0)
				(type default)
			)
			(fill no)
			(layer "F.CrtYd")
		)
		(fp_rect
			(start -0.508 0.9398)
			(end 0.508 -0.9398)
			(stroke
				(width 0)
				(type default)
			)
			(fill no)
			(layer "F.Fab")
		)
		(pad "1" smd custom
			(at 0 -0.4445 180)
			(size 0.1397 0.1397)
			(layers "F.Cu" "F.Mask" "F.Paste")
			(net "ADC_P1V8_STBY")
			(options
				(clearance outline)
				(anchor circle)
			)
			(primitives
				(gr_poly
					(pts
						(arc
							(start -0.1778 -0.2794)
							(mid -0.249642 -0.249642)
							(end -0.2794 -0.1778)
						)
						(arc
							(start -0.2794 0.1778)
							(mid -0.249642 0.249642)
							(end -0.1778 0.2794)
						)
						(arc
							(start 0.1778 0.2794)
							(mid 0.249642 0.249642)
							(end 0.2794 0.1778)
						)
						(arc
							(start 0.2794 -0.1778)
							(mid 0.249642 -0.249642)
							(end 0.1778 -0.2794)
						)
					)
					(width 0)
					(fill yes)
				)
			)
		)
		(pad "2" smd custom
			(at 0 0.4445 180)
			(size 0.1397 0.1397)
			(layers "F.Cu" "F.Mask" "F.Paste")
			(net "GND")
			(options
				(clearance outline)
				(anchor circle)
			)
			(primitives
				(gr_poly
					(pts
						(arc
							(start -0.1778 -0.2794)
							(mid -0.249642 -0.249642)
							(end -0.2794 -0.1778)
						)
						(arc
							(start -0.2794 0.1778)
							(mid -0.249642 0.249642)
							(end -0.1778 0.2794)
						)
						(arc
							(start 0.1778 0.2794)
							(mid 0.249642 0.249642)
							(end 0.2794 0.1778)
						)
						(arc
							(start 0.2794 -0.1778)
							(mid 0.249642 -0.249642)
							(end 0.1778 -0.2794)
						)
					)
					(width 0)
					(fill yes)
				)
			)
		)
	)
	(footprint ""
		(layer "F.Cu")
		(at 205.2574 -110.7694)
		(property "Reference" "R549"
			(at 0 0 0)
			(layer "F.SilkS")
			(hide yes)
			(effects
				(font
					(size 1.27 1.27)
				)
			)
		)
		(property "Value" "4K7R2F-GP"
			(at 0.064008 -3.993896 0)
			(unlocked yes)
			(layer "F.Fab")
			(hide yes)
			(effects
				(font
					(size 1.016 1.016)
					(thickness 0.1524)
				)
			)
		)
		(property "Device Type" "R402H16"
			(at 0.064008 -5.517896 0)
			(unlocked yes)
			(layer "F.Fab")
			(hide yes)
			(effects
				(font
					(size 1.016 1.016)
					(thickness 0.1524)
				)
			)
		)
		(duplicate_pad_numbers_are_jumpers no)
		(fp_line
			(start -0.508 -0.9398)
			(end -0.508 0.9398)
			(stroke
				(width 0.1524)
				(type default)
			)
			(layer "F.SilkS")
		)
		(fp_line
			(start 0.508 -0.9398)
			(end -0.508 -0.9398)
			(stroke
				(width 0.1524)
				(type default)
			)
			(layer "F.SilkS")
		)
		(fp_rect
			(start -0.508 0.9398)
			(end 0.508 -0.9398)
			(stroke
				(width 0)
				(type default)
			)
			(fill no)
			(layer "F.CrtYd")
		)
		(fp_rect
			(start -0.508 0.9398)
			(end 0.508 -0.9398)
			(stroke
				(width 0)
				(type default)
			)
			(fill no)
			(layer "F.Fab")
		)
		(pad "1" smd custom
			(at 0 -0.4445)
			(size 0.1397 0.1397)
			(layers "F.Cu" "F.Mask" "F.Paste")
			(net "P3V3_STBY")
			(options
				(clearance outline)
				(anchor circle)
			)
			(primitives
				(gr_poly
					(pts
						(arc
							(start -0.1778 -0.2794)
							(mid -0.249642 -0.249642)
							(end -0.2794 -0.1778)
						)
						(arc
							(start -0.2794 0.1778)
							(mid -0.249642 0.249642)
							(end -0.1778 0.2794)
						)
						(arc
							(start 0.1778 0.2794)
							(mid 0.249642 0.249642)
							(end 0.2794 0.1778)
						)
						(arc
							(start 0.2794 -0.1778)
							(mid 0.249642 -0.249642)
							(end 0.1778 -0.2794)
						)
					)
					(width 0)
					(fill yes)
				)
			)
		)
		(pad "2" smd custom
			(at 0 0.4445)
			(size 0.1397 0.1397)
			(layers "F.Cu" "F.Mask" "F.Paste")
			(net "TEMP_2_A1")
			(options
				(clearance outline)
				(anchor circle)
			)
			(primitives
				(gr_poly
					(pts
						(arc
							(start -0.1778 -0.2794)
							(mid -0.249642 -0.249642)
							(end -0.2794 -0.1778)
						)
						(arc
							(start -0.2794 0.1778)
							(mid -0.249642 0.249642)
							(end -0.1778 0.2794)
						)
						(arc
							(start 0.1778 0.2794)
							(mid 0.249642 0.249642)
							(end 0.2794 0.1778)
						)
						(arc
							(start 0.2794 -0.1778)
							(mid 0.249642 -0.249642)
							(end 0.1778 -0.2794)
						)
					)
					(width 0)
					(fill yes)
				)
			)
		)
	)
	(footprint ""
		(layer "F.Cu")
		(at 58.928 -162.7886 180)
		(property "Reference" "R410"
			(at 0 0 180)
			(layer "F.SilkS")
			(hide yes)
			(effects
				(font
					(size 1.27 1.27)
				)
			)
		)
		(property "Value" "1KR2F-3-GP"
			(at 0.064008 -3.993896 180)
			(unlocked yes)
			(layer "F.Fab")
			(hide yes)
			(effects
				(font
					(size 1.016 1.016)
					(thickness 0.1524)
				)
			)
		)
		(property "Device Type" "R402H16"
			(at 0.064008 -5.517896 180)
			(unlocked yes)
			(layer "F.Fab")
			(hide yes)
			(effects
				(font
					(size 1.016 1.016)
					(thickness 0.1524)
				)
			)
		)
		(duplicate_pad_numbers_are_jumpers no)
		(fp_line
			(start 0.508 -0.9398)
			(end -0.508 -0.9398)
			(stroke
				(width 0.1524)
				(type default)
			)
			(layer "F.SilkS")
		)
		(fp_line
			(start -0.508 -0.9398)
			(end -0.508 0.9398)
			(stroke
				(width 0.1524)
				(type default)
			)
			(layer "F.SilkS")
		)
		(fp_rect
			(start -0.508 0.9398)
			(end 0.508 -0.9398)
			(stroke
				(width 0)
				(type default)
			)
			(fill no)
			(layer "F.CrtYd")
		)
		(fp_rect
			(start -0.508 0.9398)
			(end 0.508 -0.9398)
			(stroke
				(width 0)
				(type default)
			)
			(fill no)
			(layer "F.Fab")
		)
		(pad "1" smd custom
			(at 0 -0.4445 180)
			(size 0.1397 0.1397)
			(layers "F.Cu" "F.Mask" "F.Paste")
			(net "ADC_P3V3_STBY")
			(options
				(clearance outline)
				(anchor circle)
			)
			(primitives
				(gr_poly
					(pts
						(arc
							(start -0.1778 -0.2794)
							(mid -0.249642 -0.249642)
							(end -0.2794 -0.1778)
						)
						(arc
							(start -0.2794 0.1778)
							(mid -0.249642 0.249642)
							(end -0.1778 0.2794)
						)
						(arc
							(start 0.1778 0.2794)
							(mid 0.249642 0.249642)
							(end 0.2794 0.1778)
						)
						(arc
							(start 0.2794 -0.1778)
							(mid 0.249642 -0.249642)
							(end 0.1778 -0.2794)
						)
					)
					(width 0)
					(fill yes)
				)
			)
		)
		(pad "2" smd custom
			(at 0 0.4445 180)
			(size 0.1397 0.1397)
			(layers "F.Cu" "F.Mask" "F.Paste")
			(net "GND")
			(options
				(clearance outline)
				(anchor circle)
			)
			(primitives
				(gr_poly
					(pts
						(arc
							(start -0.1778 -0.2794)
							(mid -0.249642 -0.249642)
							(end -0.2794 -0.1778)
						)
						(arc
							(start -0.2794 0.1778)
							(mid -0.249642 0.249642)
							(end -0.1778 0.2794)
						)
						(arc
							(start 0.1778 0.2794)
							(mid 0.249642 0.249642)
							(end 0.2794 0.1778)
						)
						(arc
							(start 0.2794 -0.1778)
							(mid 0.249642 -0.249642)
							(end 0.1778 -0.2794)
						)
					)
					(width 0)
					(fill yes)
				)
			)
		)
	)
	(footprint ""
		(layer "F.Cu")
		(at 37.9476 -158.7246)
		(property "Reference" "R317"
			(at 0 0 0)
			(layer "F.SilkS")
			(hide yes)
			(effects
				(font
					(size 1.27 1.27)
				)
			)
		)
		(property "Value" "0R2J-2-GP"
			(at 0.064008 -3.993896 0)
			(unlocked yes)
			(layer "F.Fab")
			(hide yes)
			(effects
				(font
					(size 1.016 1.016)
					(thickness 0.1524)
				)
			)
		)
		(property "Device Type" "R402H16"
			(at 0.064008 -5.517896 0)
			(unlocked yes)
			(layer "F.Fab")
			(hide yes)
			(effects
				(font
					(size 1.016 1.016)
					(thickness 0.1524)
				)
			)
		)
		(duplicate_pad_numbers_are_jumpers no)
		(fp_line
			(start -0.508 -0.9398)
			(end -0.508 0.9398)
			(stroke
				(width 0.1524)
				(type default)
			)
			(layer "F.SilkS")
		)
		(fp_line
			(start 0.508 -0.9398)
			(end -0.508 -0.9398)
			(stroke
				(width 0.1524)
				(type default)
			)
			(layer "F.SilkS")
		)
		(fp_rect
			(start -0.508 0.9398)
			(end 0.508 -0.9398)
			(stroke
				(width 0)
				(type default)
			)
			(fill no)
			(layer "F.CrtYd")
		)
		(fp_rect
			(start -0.508 0.9398)
			(end 0.508 -0.9398)
			(stroke
				(width 0)
				(type default)
			)
			(fill no)
			(layer "F.Fab")
		)
		(pad "1" smd custom
			(at 0 -0.4445)
			(size 0.1397 0.1397)
			(layers "F.Cu" "F.Mask" "F.Paste")
			(net "PWM_OUT_ZONE_C")
			(options
				(clearance outline)
				(anchor circle)
			)
			(primitives
				(gr_poly
					(pts
						(arc
							(start -0.1778 -0.2794)
							(mid -0.249642 -0.249642)
							(end -0.2794 -0.1778)
						)
						(arc
							(start -0.2794 0.1778)
							(mid -0.249642 0.249642)
							(end -0.1778 0.2794)
						)
						(arc
							(start 0.1778 0.2794)
							(mid 0.249642 0.249642)
							(end 0.2794 0.1778)
						)
						(arc
							(start 0.2794 -0.1778)
							(mid 0.249642 -0.249642)
							(end 0.1778 -0.2794)
						)
					)
					(width 0)
					(fill yes)
				)
			)
		)
		(pad "2" smd custom
			(at 0 0.4445)
			(size 0.1397 0.1397)
			(layers "F.Cu" "F.Mask" "F.Paste")
			(net "FAN_PWM0_BMC")
			(options
				(clearance outline)
				(anchor circle)
			)
			(primitives
				(gr_poly
					(pts
						(arc
							(start -0.1778 -0.2794)
							(mid -0.249642 -0.249642)
							(end -0.2794 -0.1778)
						)
						(arc
							(start -0.2794 0.1778)
							(mid -0.249642 0.249642)
							(end -0.1778 0.2794)
						)
						(arc
							(start 0.1778 0.2794)
							(mid 0.249642 0.249642)
							(end 0.2794 0.1778)
						)
						(arc
							(start 0.2794 -0.1778)
							(mid 0.249642 -0.249642)
							(end 0.1778 -0.2794)
						)
					)
					(width 0)
					(fill yes)
				)
			)
		)
	)
	(footprint ""
		(layer "F.Cu")
		(at 85.451442 -172.077888 -90)
		(property "Reference" "R723"
			(at 0 0 270)
			(layer "F.SilkS")
			(hide yes)
			(effects
				(font
					(size 1.27 1.27)
				)
			)
		)
		(property "Value" "4K7R2F-GP"
			(at 0.064008 -3.993896 270)
			(unlocked yes)
			(layer "F.Fab")
			(hide yes)
			(effects
				(font
					(size 1.016 1.016)
					(thickness 0.1524)
				)
			)
		)
		(property "Device Type" "R402H16"
			(at 0.064008 -5.517896 270)
			(unlocked yes)
			(layer "F.Fab")
			(hide yes)
			(effects
				(font
					(size 1.016 1.016)
					(thickness 0.1524)
				)
			)
		)
		(duplicate_pad_numbers_are_jumpers no)
		(fp_line
			(start -0.508 -0.9398)
			(end -0.508 0.9398)
			(stroke
				(width 0.1524)
				(type default)
			)
			(layer "F.SilkS")
		)
		(fp_line
			(start 0.508 -0.9398)
			(end -0.508 -0.9398)
			(stroke
				(width 0.1524)
				(type default)
			)
			(layer "F.SilkS")
		)
		(fp_rect
			(start -0.508 0.9398)
			(end 0.508 -0.9398)
			(stroke
				(width 0)
				(type default)
			)
			(fill no)
			(layer "F.CrtYd")
		)
		(fp_rect
			(start -0.508 0.9398)
			(end 0.508 -0.9398)
			(stroke
				(width 0)
				(type default)
			)
			(fill no)
			(layer "F.Fab")
		)
		(pad "1" smd custom
			(at 0 -0.4445 270)
			(size 0.1397 0.1397)
			(layers "F.Cu" "F.Mask" "F.Paste")
			(net "P5V_STBY")
			(options
				(clearance outline)
				(anchor circle)
			)
			(primitives
				(gr_poly
					(pts
						(arc
							(start -0.1778 -0.2794)
							(mid -0.249642 -0.249642)
							(end -0.2794 -0.1778)
						)
						(arc
							(start -0.2794 0.1778)
							(mid -0.249642 0.249642)
							(end -0.1778 0.2794)
						)
						(arc
							(start 0.1778 0.2794)
							(mid 0.249642 0.249642)
							(end 0.2794 0.1778)
						)
						(arc
							(start 0.2794 -0.1778)
							(mid 0.249642 -0.249642)
							(end 0.1778 -0.2794)
						)
					)
					(width 0)
					(fill yes)
				)
			)
		)
		(pad "2" smd custom
			(at 0 0.4445 270)
			(size 0.1397 0.1397)
			(layers "F.Cu" "F.Mask" "F.Paste")
			(net "P1V15_STBY_PG_G")
			(options
				(clearance outline)
				(anchor circle)
			)
			(primitives
				(gr_poly
					(pts
						(arc
							(start -0.1778 -0.2794)
							(mid -0.249642 -0.249642)
							(end -0.2794 -0.1778)
						)
						(arc
							(start -0.2794 0.1778)
							(mid -0.249642 0.249642)
							(end -0.1778 0.2794)
						)
						(arc
							(start 0.1778 0.2794)
							(mid 0.249642 0.249642)
							(end 0.2794 0.1778)
						)
						(arc
							(start 0.2794 -0.1778)
							(mid 0.249642 -0.249642)
							(end 0.1778 -0.2794)
						)
					)
					(width 0)
					(fill yes)
				)
			)
		)
	)
	(footprint ""
		(layer "F.Cu")
		(at 20.809712 -175.650906)
		(property "Reference" "R533"
			(at 0 0 0)
			(layer "F.SilkS")
			(hide yes)
			(effects
				(font
					(size 1.27 1.27)
				)
			)
		)
		(property "Value" "0R2J-2-GP"
			(at 0.064008 -3.993896 0)
			(unlocked yes)
			(layer "F.Fab")
			(hide yes)
			(effects
				(font
					(size 1.016 1.016)
					(thickness 0.1524)
				)
			)
		)
		(property "Device Type" "R402H16"
			(at 0.064008 -5.517896 0)
			(unlocked yes)
			(layer "F.Fab")
			(hide yes)
			(effects
				(font
					(size 1.016 1.016)
					(thickness 0.1524)
				)
			)
		)
		(duplicate_pad_numbers_are_jumpers no)
		(fp_line
			(start -0.508 -0.9398)
			(end -0.508 0.9398)
			(stroke
				(width 0.1524)
				(type default)
			)
			(layer "F.SilkS")
		)
		(fp_line
			(start 0.508 -0.9398)
			(end -0.508 -0.9398)
			(stroke
				(width 0.1524)
				(type default)
			)
			(layer "F.SilkS")
		)
		(fp_rect
			(start -0.508 0.9398)
			(end 0.508 -0.9398)
			(stroke
				(width 0)
				(type default)
			)
			(fill no)
			(layer "F.CrtYd")
		)
		(fp_rect
			(start -0.508 0.9398)
			(end 0.508 -0.9398)
			(stroke
				(width 0)
				(type default)
			)
			(fill no)
			(layer "F.Fab")
		)
		(pad "1" smd custom
			(at 0 -0.4445)
			(size 0.1397 0.1397)
			(layers "F.Cu" "F.Mask" "F.Paste")
			(net "P5V_STBY")
			(options
				(clearance outline)
				(anchor circle)
			)
			(primitives
				(gr_poly
					(pts
						(arc
							(start -0.1778 -0.2794)
							(mid -0.249642 -0.249642)
							(end -0.2794 -0.1778)
						)
						(arc
							(start -0.2794 0.1778)
							(mid -0.249642 0.249642)
							(end -0.1778 0.2794)
						)
						(arc
							(start 0.1778 0.2794)
							(mid 0.249642 0.249642)
							(end 0.2794 0.1778)
						)
						(arc
							(start 0.2794 -0.1778)
							(mid 0.249642 -0.249642)
							(end 0.1778 -0.2794)
						)
					)
					(width 0)
					(fill yes)
				)
			)
		)
		(pad "2" smd custom
			(at 0 0.4445)
			(size 0.1397 0.1397)
			(layers "F.Cu" "F.Mask" "F.Paste")
			(net "TPS74801_P1V2_STBY_BIAS")
			(options
				(clearance outline)
				(anchor circle)
			)
			(primitives
				(gr_poly
					(pts
						(arc
							(start -0.1778 -0.2794)
							(mid -0.249642 -0.249642)
							(end -0.2794 -0.1778)
						)
						(arc
							(start -0.2794 0.1778)
							(mid -0.249642 0.249642)
							(end -0.1778 0.2794)
						)
						(arc
							(start 0.1778 0.2794)
							(mid 0.249642 0.249642)
							(end 0.2794 0.1778)
						)
						(arc
							(start 0.2794 -0.1778)
							(mid 0.249642 -0.249642)
							(end 0.1778 -0.2794)
						)
					)
					(width 0)
					(fill yes)
				)
			)
		)
	)
	(footprint ""
		(layer "F.Cu")
		(at 8.88111 -135.290052 -90)
		(property "Reference" "R239"
			(at 0 0 270)
			(layer "F.SilkS")
			(hide yes)
			(effects
				(font
					(size 1.27 1.27)
				)
			)
		)
		(property "Value" "0R2J-2-GP"
			(at 0.064008 -3.993896 270)
			(unlocked yes)
			(layer "F.Fab")
			(hide yes)
			(effects
				(font
					(size 1.016 1.016)
					(thickness 0.1524)
				)
			)
		)
		(property "Device Type" "R402H16"
			(at 0.064008 -5.517896 270)
			(unlocked yes)
			(layer "F.Fab")
			(hide yes)
			(effects
				(font
					(size 1.016 1.016)
					(thickness 0.1524)
				)
			)
		)
		(duplicate_pad_numbers_are_jumpers no)
		(fp_line
			(start -0.508 -0.9398)
			(end -0.508 0.9398)
			(stroke
				(width 0.1524)
				(type default)
			)
			(layer "F.SilkS")
		)
		(fp_line
			(start 0.508 -0.9398)
			(end -0.508 -0.9398)
			(stroke
				(width 0.1524)
				(type default)
			)
			(layer "F.SilkS")
		)
		(fp_rect
			(start -0.508 0.9398)
			(end 0.508 -0.9398)
			(stroke
				(width 0)
				(type default)
			)
			(fill no)
			(layer "F.CrtYd")
		)
		(fp_rect
			(start -0.508 0.9398)
			(end 0.508 -0.9398)
			(stroke
				(width 0)
				(type default)
			)
			(fill no)
			(layer "F.Fab")
		)
		(pad "1" smd custom
			(at 0 -0.4445 270)
			(size 0.1397 0.1397)
			(layers "F.Cu" "F.Mask" "F.Paste")
			(net "MEM_PAR")
			(options
				(clearance outline)
				(anchor circle)
			)
			(primitives
				(gr_poly
					(pts
						(arc
							(start -0.1778 -0.2794)
							(mid -0.249642 -0.249642)
							(end -0.2794 -0.1778)
						)
						(arc
							(start -0.2794 0.1778)
							(mid -0.249642 0.249642)
							(end -0.1778 0.2794)
						)
						(arc
							(start 0.1778 0.2794)
							(mid 0.249642 0.249642)
							(end 0.2794 0.1778)
						)
						(arc
							(start 0.2794 -0.1778)
							(mid 0.249642 -0.249642)
							(end 0.1778 -0.2794)
						)
					)
					(width 0)
					(fill yes)
				)
			)
		)
		(pad "2" smd custom
			(at 0 0.4445 270)
			(size 0.1397 0.1397)
			(layers "F.Cu" "F.Mask" "F.Paste")
			(net "GND")
			(options
				(clearance outline)
				(anchor circle)
			)
			(primitives
				(gr_poly
					(pts
						(arc
							(start -0.1778 -0.2794)
							(mid -0.249642 -0.249642)
							(end -0.2794 -0.1778)
						)
						(arc
							(start -0.2794 0.1778)
							(mid -0.249642 0.249642)
							(end -0.1778 0.2794)
						)
						(arc
							(start 0.1778 0.2794)
							(mid 0.249642 0.249642)
							(end 0.2794 0.1778)
						)
						(arc
							(start 0.2794 -0.1778)
							(mid 0.249642 -0.249642)
							(end 0.1778 -0.2794)
						)
					)
					(width 0)
					(fill yes)
				)
			)
		)
	)
	(footprint ""
		(layer "F.Cu")
		(at 53.3273 -161.0614 -90)
		(property "Reference" "C84"
			(at 0 0 270)
			(layer "F.SilkS")
			(hide yes)
			(effects
				(font
					(size 1.27 1.27)
				)
			)
		)
		(property "Value" "SCD1U16V2KX-3GP"
			(at 1.1811 -2.7051 270)
			(unlocked yes)
			(layer "F.Fab")
			(hide yes)
			(effects
				(font
					(size 1.016 1.016)
					(thickness 0.1524)
				)
			)
		)
		(property "Device Type" "C402H22"
			(at 1.1811 -4.2291 270)
			(unlocked yes)
			(layer "F.Fab")
			(hide yes)
			(effects
				(font
					(size 1.016 1.016)
					(thickness 0.1524)
				)
			)
		)
		(duplicate_pad_numbers_are_jumpers no)
		(fp_rect
			(start -0.4318 0.9525)
			(end 0.4318 -0.9525)
			(stroke
				(width 0)
				(type default)
			)
			(fill no)
			(layer "F.CrtYd")
		)
		(fp_rect
			(start -0.4318 0.9525)
			(end 0.4318 -0.9525)
			(stroke
				(width 0)
				(type default)
			)
			(fill no)
			(layer "F.Fab")
		)
		(pad "1" smd custom
			(at 0 -0.4445 270)
			(size 0.1524 0.1524)
			(layers "F.Cu" "F.Mask" "F.Paste")
			(net "ADCAV33")
			(options
				(clearance outline)
				(anchor circle)
			)
			(primitives
				(gr_poly
					(pts
						(arc
							(start 0.3048 -0.2032)
							(mid 0.275042 -0.275042)
							(end 0.2032 -0.3048)
						)
						(arc
							(start -0.2032 -0.3048)
							(mid -0.275042 -0.275042)
							(end -0.3048 -0.2032)
						)
						(arc
							(start -0.3048 0.2032)
							(mid -0.275042 0.275042)
							(end -0.2032 0.3048)
						)
						(arc
							(start 0.2032 0.3048)
							(mid 0.275042 0.275042)
							(end 0.3048 0.2032)
						)
					)
					(width 0)
					(fill yes)
				)
			)
		)
		(pad "2" smd custom
			(at 0 0.4445 270)
			(size 0.1524 0.1524)
			(layers "F.Cu" "F.Mask" "F.Paste")
			(net "ADCVREFFP")
			(options
				(clearance outline)
				(anchor circle)
			)
			(primitives
				(gr_poly
					(pts
						(arc
							(start 0.3048 -0.2032)
							(mid 0.275042 -0.275042)
							(end 0.2032 -0.3048)
						)
						(arc
							(start -0.2032 -0.3048)
							(mid -0.275042 -0.275042)
							(end -0.3048 -0.2032)
						)
						(arc
							(start -0.3048 0.2032)
							(mid -0.275042 0.275042)
							(end -0.2032 0.3048)
						)
						(arc
							(start 0.2032 0.3048)
							(mid 0.275042 0.275042)
							(end 0.3048 0.2032)
						)
					)
					(width 0)
					(fill yes)
				)
			)
		)
	)
	(footprint ""
		(layer "F.Cu")
		(at 29.367226 -180.33873 180)
		(property "Reference" "C182"
			(at 0 0 180)
			(layer "F.SilkS")
			(hide yes)
			(effects
				(font
					(size 1.27 1.27)
				)
			)
		)
		(property "Value" "SC1U16V3KX-5GP"
			(at 0 -2.8194 180)
			(unlocked yes)
			(layer "F.Fab")
			(hide yes)
			(effects
				(font
					(size 1.016 1.016)
					(thickness 0.1524)
				)
			)
		)
		(property "Device Type" "C603H36"
			(at 0 -4.3434 180)
			(unlocked yes)
			(layer "F.Fab")
			(hide yes)
			(effects
				(font
					(size 1.016 1.016)
					(thickness 0.1524)
				)
			)
		)
		(duplicate_pad_numbers_are_jumpers no)
		(fp_line
			(start 0.508 0)
			(end -0.508 0)
			(stroke
				(width 0.2032)
				(type default)
			)
			(layer "F.SilkS")
		)
		(fp_rect
			(start -0.5842 1.3335)
			(end 0.5842 -1.3335)
			(stroke
				(width 0)
				(type default)
			)
			(fill no)
			(layer "F.CrtYd")
		)
		(fp_rect
			(start -0.5842 1.3335)
			(end 0.5842 -1.3335)
			(stroke
				(width 0)
				(type default)
			)
			(fill no)
			(layer "F.Fab")
		)
		(pad "1" smd custom
			(at 0 -0.762 180)
			(size 0.2159 0.2159)
			(layers "F.Cu" "F.Mask" "F.Paste")
			(net "GND")
			(options
				(clearance outline)
				(anchor circle)
			)
			(primitives
				(gr_poly
					(pts
						(arc
							(start -0.3302 -0.4318)
							(mid -0.402042 -0.402042)
							(end -0.4318 -0.3302)
						)
						(arc
							(start -0.4318 0.3302)
							(mid -0.402042 0.402042)
							(end -0.3302 0.4318)
						)
						(arc
							(start 0.3302 0.4318)
							(mid 0.402042 0.402042)
							(end 0.4318 0.3302)
						)
						(arc
							(start 0.4318 -0.3302)
							(mid 0.402042 -0.402042)
							(end 0.3302 -0.4318)
						)
					)
					(width 0)
					(fill yes)
				)
			)
		)
		(pad "2" smd custom
			(at 0 0.762 180)
			(size 0.2159 0.2159)
			(layers "F.Cu" "F.Mask" "F.Paste")
			(net "P3V3_STBY_VREG")
			(options
				(clearance outline)
				(anchor circle)
			)
			(primitives
				(gr_poly
					(pts
						(arc
							(start -0.3302 -0.4318)
							(mid -0.402042 -0.402042)
							(end -0.4318 -0.3302)
						)
						(arc
							(start -0.4318 0.3302)
							(mid -0.402042 0.402042)
							(end -0.3302 0.4318)
						)
						(arc
							(start 0.3302 0.4318)
							(mid 0.402042 0.402042)
							(end 0.4318 0.3302)
						)
						(arc
							(start 0.4318 -0.3302)
							(mid 0.402042 -0.402042)
							(end 0.3302 -0.4318)
						)
					)
					(width 0)
					(fill yes)
				)
			)
		)
	)
	(footprint ""
		(layer "F.Cu")
		(at 149.632416 -10.532618)
		(property "Reference" "C208"
			(at 0 0 0)
			(layer "F.SilkS")
			(hide yes)
			(effects
				(font
					(size 1.27 1.27)
				)
			)
		)
		(property "Value" "SC3300P50V2KX-1GP"
			(at 1.1811 -2.7051 0)
			(unlocked yes)
			(layer "F.Fab")
			(hide yes)
			(effects
				(font
					(size 1.016 1.016)
					(thickness 0.1524)
				)
			)
		)
		(property "Device Type" "C402H22"
			(at 1.1811 -4.2291 0)
			(unlocked yes)
			(layer "F.Fab")
			(hide yes)
			(effects
				(font
					(size 1.016 1.016)
					(thickness 0.1524)
				)
			)
		)
		(duplicate_pad_numbers_are_jumpers no)
		(fp_rect
			(start -0.4318 0.9525)
			(end 0.4318 -0.9525)
			(stroke
				(width 0)
				(type default)
			)
			(fill no)
			(layer "F.CrtYd")
		)
		(fp_rect
			(start -0.4318 0.9525)
			(end 0.4318 -0.9525)
			(stroke
				(width 0)
				(type default)
			)
			(fill no)
			(layer "F.Fab")
		)
		(pad "1" smd custom
			(at 0 -0.4445)
			(size 0.1524 0.1524)
			(layers "F.Cu" "F.Mask" "F.Paste")
			(net "P1V8_STBY_SS")
			(options
				(clearance outline)
				(anchor circle)
			)
			(primitives
				(gr_poly
					(pts
						(arc
							(start 0.3048 -0.2032)
							(mid 0.275042 -0.275042)
							(end 0.2032 -0.3048)
						)
						(arc
							(start -0.2032 -0.3048)
							(mid -0.275042 -0.275042)
							(end -0.3048 -0.2032)
						)
						(arc
							(start -0.3048 0.2032)
							(mid -0.275042 0.275042)
							(end -0.2032 0.3048)
						)
						(arc
							(start 0.2032 0.3048)
							(mid 0.275042 0.275042)
							(end 0.3048 0.2032)
						)
					)
					(width 0)
					(fill yes)
				)
			)
		)
		(pad "2" smd custom
			(at 0 0.4445)
			(size 0.1524 0.1524)
			(layers "F.Cu" "F.Mask" "F.Paste")
			(net "AGND_P1V8_STBY")
			(options
				(clearance outline)
				(anchor circle)
			)
			(primitives
				(gr_poly
					(pts
						(arc
							(start 0.3048 -0.2032)
							(mid 0.275042 -0.275042)
							(end 0.2032 -0.3048)
						)
						(arc
							(start -0.2032 -0.3048)
							(mid -0.275042 -0.275042)
							(end -0.3048 -0.2032)
						)
						(arc
							(start -0.3048 0.2032)
							(mid -0.275042 0.275042)
							(end -0.2032 0.3048)
						)
						(arc
							(start 0.2032 0.3048)
							(mid 0.275042 0.275042)
							(end 0.3048 0.2032)
						)
					)
					(width 0)
					(fill yes)
				)
			)
		)
	)
	(footprint ""
		(layer "F.Cu")
		(at 69.140324 -166.048182 -90)
		(property "Reference" "Q2"
			(at 0 0 270)
			(layer "F.SilkS")
			(hide yes)
			(effects
				(font
					(size 1.27 1.27)
				)
			)
		)
		(property "Value" "MMBT3904-3-GP"
			(at 0.10287 -10.29843 270)
			(unlocked yes)
			(layer "F.Fab")
			(hide yes)
			(effects
				(font
					(size 1.016 1.016)
					(thickness 0.1524)
				)
			)
		)
		(property "Device Type" "SOT23CBE2D4H44"
			(at 0.10287 -12.20343 270)
			(unlocked yes)
			(layer "F.Fab")
			(hide yes)
			(effects
				(font
					(size 1.016 1.016)
					(thickness 0.1524)
				)
			)
		)
		(duplicate_pad_numbers_are_jumpers no)
		(fp_line
			(start -1.651 1.778)
			(end 1.651 1.778)
			(stroke
				(width 0.1524)
				(type default)
			)
			(layer "F.SilkS")
		)
		(fp_line
			(start 1.651 1.778)
			(end 1.651 -1.778)
			(stroke
				(width 0.1524)
				(type default)
			)
			(layer "F.SilkS")
		)
		(fp_line
			(start -1.651 -1.778)
			(end -1.651 1.778)
			(stroke
				(width 0.1524)
				(type default)
			)
			(layer "F.SilkS")
		)
		(fp_line
			(start 1.651 -1.778)
			(end -1.651 -1.778)
			(stroke
				(width 0.1524)
				(type default)
			)
			(layer "F.SilkS")
		)
		(fp_poly
			(pts
				(xy -1.778 1.8796) (xy -1.778 -1.8796) (xy 1.778 -1.8796) (xy 1.778 1.8796)
			)
			(stroke
				(width 0)
				(type default)
			)
			(fill no)
			(layer "F.CrtYd")
		)
		(fp_poly
			(pts
				(xy -1.778 1.8796) (xy -1.778 -1.8796) (xy 1.778 -1.8796) (xy 1.778 1.8796)
			)
			(stroke
				(width 0)
				(type default)
			)
			(fill no)
			(layer "F.Fab")
		)
		(pad "B" smd custom
			(at -0.98425 0.9525 270)
			(size 0.1905 0.1905)
			(layers "F.Cu" "F.Mask" "F.Paste")
			(net "FM_TPM_PRSNT_RST")
			(options
				(clearance outline)
				(anchor circle)
			)
			(primitives
				(gr_poly
					(pts
						(arc
							(start -0.1778 0.5715)
							(mid -0.321484 0.511984)
							(end -0.381 0.3683)
						)
						(arc
							(start -0.381 -0.3683)
							(mid -0.321484 -0.511984)
							(end -0.1778 -0.5715)
						)
						(arc
							(start 0.1778 -0.5715)
							(mid 0.321484 -0.511984)
							(end 0.381 -0.3683)
						)
						(arc
							(start 0.381 0.3683)
							(mid 0.321484 0.511984)
							(end 0.1778 0.5715)
						)
					)
					(width 0)
					(fill yes)
				)
			)
		)
		(pad "C" smd custom
			(at 0 -0.9525 270)
			(size 0.1905 0.1905)
			(layers "F.Cu" "F.Mask" "F.Paste")
			(net "BMC_TPM_RST_N")
			(options
				(clearance outline)
				(anchor circle)
			)
			(primitives
				(gr_poly
					(pts
						(arc
							(start -0.1778 0.5715)
							(mid -0.321484 0.511984)
							(end -0.381 0.3683)
						)
						(arc
							(start -0.381 -0.3683)
							(mid -0.321484 -0.511984)
							(end -0.1778 -0.5715)
						)
						(arc
							(start 0.1778 -0.5715)
							(mid 0.321484 -0.511984)
							(end 0.381 -0.3683)
						)
						(arc
							(start 0.381 0.3683)
							(mid 0.321484 0.511984)
							(end 0.1778 0.5715)
						)
					)
					(width 0)
					(fill yes)
				)
			)
		)
		(pad "E" smd custom
			(at 0.98425 0.9525 270)
			(size 0.1905 0.1905)
			(layers "F.Cu" "F.Mask" "F.Paste")
			(net "GND")
			(options
				(clearance outline)
				(anchor circle)
			)
			(primitives
				(gr_poly
					(pts
						(arc
							(start -0.1778 0.5715)
							(mid -0.321484 0.511984)
							(end -0.381 0.3683)
						)
						(arc
							(start -0.381 -0.3683)
							(mid -0.321484 -0.511984)
							(end -0.1778 -0.5715)
						)
						(arc
							(start 0.1778 -0.5715)
							(mid 0.321484 -0.511984)
							(end 0.381 -0.3683)
						)
						(arc
							(start 0.381 0.3683)
							(mid 0.321484 0.511984)
							(end 0.1778 0.5715)
						)
					)
					(width 0)
					(fill yes)
				)
			)
		)
	)
	(footprint ""
		(layer "F.Cu")
		(at 110.758478 -10.791952 -90)
		(property "Reference" "C148"
			(at 0 0 270)
			(layer "F.SilkS")
			(hide yes)
			(effects
				(font
					(size 1.27 1.27)
				)
			)
		)
		(property "Value" "SCD1U50V3KX-GP"
			(at 0 -2.8194 270)
			(unlocked yes)
			(layer "F.Fab")
			(hide yes)
			(effects
				(font
					(size 1.016 1.016)
					(thickness 0.1524)
				)
			)
		)
		(property "Device Type" "C603H36"
			(at 0 -4.3434 270)
			(unlocked yes)
			(layer "F.Fab")
			(hide yes)
			(effects
				(font
					(size 1.016 1.016)
					(thickness 0.1524)
				)
			)
		)
		(duplicate_pad_numbers_are_jumpers no)
		(fp_line
			(start 0.508 0)
			(end -0.508 0)
			(stroke
				(width 0.2032)
				(type default)
			)
			(layer "F.SilkS")
		)
		(fp_rect
			(start -0.5842 1.3335)
			(end 0.5842 -1.3335)
			(stroke
				(width 0)
				(type default)
			)
			(fill no)
			(layer "F.CrtYd")
		)
		(fp_rect
			(start -0.5842 1.3335)
			(end 0.5842 -1.3335)
			(stroke
				(width 0)
				(type default)
			)
			(fill no)
			(layer "F.Fab")
		)
		(pad "1" smd custom
			(at 0 -0.762 270)
			(size 0.2159 0.2159)
			(layers "F.Cu" "F.Mask" "F.Paste")
			(net "MB0_ISET_R")
			(options
				(clearance outline)
				(anchor circle)
			)
			(primitives
				(gr_poly
					(pts
						(arc
							(start -0.3302 -0.4318)
							(mid -0.402042 -0.402042)
							(end -0.4318 -0.3302)
						)
						(arc
							(start -0.4318 0.3302)
							(mid -0.402042 0.402042)
							(end -0.3302 0.4318)
						)
						(arc
							(start 0.3302 0.4318)
							(mid 0.402042 0.402042)
							(end 0.4318 0.3302)
						)
						(arc
							(start 0.4318 -0.3302)
							(mid 0.402042 -0.402042)
							(end 0.3302 -0.4318)
						)
					)
					(width 0)
					(fill yes)
				)
			)
		)
		(pad "2" smd custom
			(at 0 0.762 270)
			(size 0.2159 0.2159)
			(layers "F.Cu" "F.Mask" "F.Paste")
			(net "AGND_CURRENT_MON")
			(options
				(clearance outline)
				(anchor circle)
			)
			(primitives
				(gr_poly
					(pts
						(arc
							(start -0.3302 -0.4318)
							(mid -0.402042 -0.402042)
							(end -0.4318 -0.3302)
						)
						(arc
							(start -0.4318 0.3302)
							(mid -0.402042 0.402042)
							(end -0.3302 0.4318)
						)
						(arc
							(start 0.3302 0.4318)
							(mid 0.402042 0.402042)
							(end 0.4318 0.3302)
						)
						(arc
							(start 0.4318 -0.3302)
							(mid 0.402042 -0.402042)
							(end 0.3302 -0.4318)
						)
					)
					(width 0)
					(fill yes)
				)
			)
		)
	)
	(footprint ""
		(layer "F.Cu")
		(at 55.152036 -132.360162)
		(property "Reference" "TP11"
			(at 0 0 0)
			(layer "F.SilkS")
			(hide yes)
			(effects
				(font
					(size 1.27 1.27)
				)
			)
		)
		(property "Value" "TPAD28-2-GP"
			(at -0.0127 -1.6637 0)
			(unlocked yes)
			(layer "F.Fab")
			(hide yes)
			(effects
				(font
					(size 1.016 1.016)
					(thickness 0.1524)
				)
			)
		)
		(property "Device Type" "TPAD28"
			(at -0.0127 -3.1877 0)
			(unlocked yes)
			(layer "F.Fab")
			(hide yes)
			(effects
				(font
					(size 1.016 1.016)
					(thickness 0.1524)
				)
			)
		)
		(duplicate_pad_numbers_are_jumpers no)
		(fp_poly
			(pts
				(arc
					(start 0.3556 0)
					(mid -0.3556 0)
					(end 0.3556 0)
				)
			)
			(stroke
				(width 0)
				(type default)
			)
			(fill no)
			(layer "F.CrtYd")
		)
		(fp_poly
			(pts
				(arc
					(start 0.6096 0)
					(mid -0.6096 0)
					(end 0.6096 0)
				)
			)
			(stroke
				(width 0)
				(type default)
			)
			(fill no)
			(layer "F.Fab")
		)
		(pad "1" smd circle
			(at 0 0)
			(size 0.7112 0.7112)
			(layers "F.Cu" "F.Mask" "F.Paste")
			(net "TP_BMC0_LPC_LAD2")
		)
	)
	(footprint ""
		(layer "F.Cu")
		(at 46.392592 -128.207516)
		(property "Reference" "R274"
			(at 0 0 0)
			(layer "F.SilkS")
			(hide yes)
			(effects
				(font
					(size 1.27 1.27)
				)
			)
		)
		(property "Value" "2K2R2F-GP"
			(at 0.064008 -3.993896 0)
			(unlocked yes)
			(layer "F.Fab")
			(hide yes)
			(effects
				(font
					(size 1.016 1.016)
					(thickness 0.1524)
				)
			)
		)
		(property "Device Type" "R402H16"
			(at 0.064008 -5.517896 0)
			(unlocked yes)
			(layer "F.Fab")
			(hide yes)
			(effects
				(font
					(size 1.016 1.016)
					(thickness 0.1524)
				)
			)
		)
		(duplicate_pad_numbers_are_jumpers no)
		(fp_line
			(start -0.508 -0.9398)
			(end -0.508 0.9398)
			(stroke
				(width 0.1524)
				(type default)
			)
			(layer "F.SilkS")
		)
		(fp_line
			(start 0.508 -0.9398)
			(end -0.508 -0.9398)
			(stroke
				(width 0.1524)
				(type default)
			)
			(layer "F.SilkS")
		)
		(fp_rect
			(start -0.508 0.9398)
			(end 0.508 -0.9398)
			(stroke
				(width 0)
				(type default)
			)
			(fill no)
			(layer "F.CrtYd")
		)
		(fp_rect
			(start -0.508 0.9398)
			(end 0.508 -0.9398)
			(stroke
				(width 0)
				(type default)
			)
			(fill no)
			(layer "F.Fab")
		)
		(pad "1" smd custom
			(at 0 -0.4445)
			(size 0.1397 0.1397)
			(layers "F.Cu" "F.Mask" "F.Paste")
			(net "BMC_SMB2_DAT")
			(options
				(clearance outline)
				(anchor circle)
			)
			(primitives
				(gr_poly
					(pts
						(arc
							(start -0.1778 -0.2794)
							(mid -0.249642 -0.249642)
							(end -0.2794 -0.1778)
						)
						(arc
							(start -0.2794 0.1778)
							(mid -0.249642 0.249642)
							(end -0.1778 0.2794)
						)
						(arc
							(start 0.1778 0.2794)
							(mid 0.249642 0.249642)
							(end 0.2794 0.1778)
						)
						(arc
							(start 0.2794 -0.1778)
							(mid 0.249642 -0.249642)
							(end 0.1778 -0.2794)
						)
					)
					(width 0)
					(fill yes)
				)
			)
		)
		(pad "2" smd custom
			(at 0 0.4445)
			(size 0.1397 0.1397)
			(layers "F.Cu" "F.Mask" "F.Paste")
			(net "P3V3_STBY")
			(options
				(clearance outline)
				(anchor circle)
			)
			(primitives
				(gr_poly
					(pts
						(arc
							(start -0.1778 -0.2794)
							(mid -0.249642 -0.249642)
							(end -0.2794 -0.1778)
						)
						(arc
							(start -0.2794 0.1778)
							(mid -0.249642 0.249642)
							(end -0.1778 0.2794)
						)
						(arc
							(start 0.1778 0.2794)
							(mid 0.249642 0.249642)
							(end 0.2794 0.1778)
						)
						(arc
							(start 0.2794 -0.1778)
							(mid 0.249642 -0.249642)
							(end 0.1778 -0.2794)
						)
					)
					(width 0)
					(fill yes)
				)
			)
		)
	)
	(footprint ""
		(layer "F.Cu")
		(at 48.05299 -158.5976)
		(property "Reference" "R170"
			(at 0 0 0)
			(layer "F.SilkS")
			(hide yes)
			(effects
				(font
					(size 1.27 1.27)
				)
			)
		)
		(property "Value" "0R2J-2-GP"
			(at 0.064008 -3.993896 0)
			(unlocked yes)
			(layer "F.Fab")
			(hide yes)
			(effects
				(font
					(size 1.016 1.016)
					(thickness 0.1524)
				)
			)
		)
		(property "Device Type" "R402H16"
			(at 0.064008 -5.517896 0)
			(unlocked yes)
			(layer "F.Fab")
			(hide yes)
			(effects
				(font
					(size 1.016 1.016)
					(thickness 0.1524)
				)
			)
		)
		(duplicate_pad_numbers_are_jumpers no)
		(fp_line
			(start -0.508 -0.9398)
			(end -0.508 0.9398)
			(stroke
				(width 0.1524)
				(type default)
			)
			(layer "F.SilkS")
		)
		(fp_line
			(start 0.508 -0.9398)
			(end -0.508 -0.9398)
			(stroke
				(width 0.1524)
				(type default)
			)
			(layer "F.SilkS")
		)
		(fp_rect
			(start -0.508 0.9398)
			(end 0.508 -0.9398)
			(stroke
				(width 0)
				(type default)
			)
			(fill no)
			(layer "F.CrtYd")
		)
		(fp_rect
			(start -0.508 0.9398)
			(end 0.508 -0.9398)
			(stroke
				(width 0)
				(type default)
			)
			(fill no)
			(layer "F.Fab")
		)
		(pad "1" smd custom
			(at 0 -0.4445)
			(size 0.1397 0.1397)
			(layers "F.Cu" "F.Mask" "F.Paste")
			(net "I2C_DPB_MISC_SDA_OUT")
			(options
				(clearance outline)
				(anchor circle)
			)
			(primitives
				(gr_poly
					(pts
						(arc
							(start -0.1778 -0.2794)
							(mid -0.249642 -0.249642)
							(end -0.2794 -0.1778)
						)
						(arc
							(start -0.2794 0.1778)
							(mid -0.249642 0.249642)
							(end -0.1778 0.2794)
						)
						(arc
							(start 0.1778 0.2794)
							(mid 0.249642 0.249642)
							(end 0.2794 0.1778)
						)
						(arc
							(start 0.2794 -0.1778)
							(mid 0.249642 -0.249642)
							(end 0.1778 -0.2794)
						)
					)
					(width 0)
					(fill yes)
				)
			)
		)
		(pad "2" smd custom
			(at 0 0.4445)
			(size 0.1397 0.1397)
			(layers "F.Cu" "F.Mask" "F.Paste")
			(net "BMC_SMB6_DAT")
			(options
				(clearance outline)
				(anchor circle)
			)
			(primitives
				(gr_poly
					(pts
						(arc
							(start -0.1778 -0.2794)
							(mid -0.249642 -0.249642)
							(end -0.2794 -0.1778)
						)
						(arc
							(start -0.2794 0.1778)
							(mid -0.249642 0.249642)
							(end -0.1778 0.2794)
						)
						(arc
							(start 0.1778 0.2794)
							(mid 0.249642 0.249642)
							(end 0.2794 0.1778)
						)
						(arc
							(start 0.2794 -0.1778)
							(mid 0.249642 -0.249642)
							(end 0.1778 -0.2794)
						)
					)
					(width 0)
					(fill yes)
				)
			)
		)
	)
	(footprint ""
		(layer "F.Cu")
		(at 97.6122 -177.292 90)
		(property "Reference" "C141"
			(at 0 0 90)
			(layer "F.SilkS")
			(hide yes)
			(effects
				(font
					(size 1.27 1.27)
				)
			)
		)
		(property "Value" "SCD1U16V2KX-3GP"
			(at 1.1811 -2.7051 90)
			(unlocked yes)
			(layer "F.Fab")
			(hide yes)
			(effects
				(font
					(size 1.016 1.016)
					(thickness 0.1524)
				)
			)
		)
		(property "Device Type" "C402H22"
			(at 1.1811 -4.2291 90)
			(unlocked yes)
			(layer "F.Fab")
			(hide yes)
			(effects
				(font
					(size 1.016 1.016)
					(thickness 0.1524)
				)
			)
		)
		(duplicate_pad_numbers_are_jumpers no)
		(fp_rect
			(start -0.4318 0.9525)
			(end 0.4318 -0.9525)
			(stroke
				(width 0)
				(type default)
			)
			(fill no)
			(layer "F.CrtYd")
		)
		(fp_rect
			(start -0.4318 0.9525)
			(end 0.4318 -0.9525)
			(stroke
				(width 0)
				(type default)
			)
			(fill no)
			(layer "F.Fab")
		)
		(pad "1" smd custom
			(at 0 -0.4445 90)
			(size 0.1524 0.1524)
			(layers "F.Cu" "F.Mask" "F.Paste")
			(net "P3V3_STBY")
			(options
				(clearance outline)
				(anchor circle)
			)
			(primitives
				(gr_poly
					(pts
						(arc
							(start 0.3048 -0.2032)
							(mid 0.275042 -0.275042)
							(end 0.2032 -0.3048)
						)
						(arc
							(start -0.2032 -0.3048)
							(mid -0.275042 -0.275042)
							(end -0.3048 -0.2032)
						)
						(arc
							(start -0.3048 0.2032)
							(mid -0.275042 0.275042)
							(end -0.2032 0.3048)
						)
						(arc
							(start 0.2032 0.3048)
							(mid 0.275042 0.275042)
							(end 0.3048 0.2032)
						)
					)
					(width 0)
					(fill yes)
				)
			)
		)
		(pad "2" smd custom
			(at 0 0.4445 90)
			(size 0.1524 0.1524)
			(layers "F.Cu" "F.Mask" "F.Paste")
			(net "GND")
			(options
				(clearance outline)
				(anchor circle)
			)
			(primitives
				(gr_poly
					(pts
						(arc
							(start 0.3048 -0.2032)
							(mid 0.275042 -0.275042)
							(end 0.2032 -0.3048)
						)
						(arc
							(start -0.2032 -0.3048)
							(mid -0.275042 -0.275042)
							(end -0.3048 -0.2032)
						)
						(arc
							(start -0.3048 0.2032)
							(mid -0.275042 0.275042)
							(end -0.2032 0.3048)
						)
						(arc
							(start 0.2032 0.3048)
							(mid 0.275042 0.275042)
							(end 0.3048 0.2032)
						)
					)
					(width 0)
					(fill yes)
				)
			)
		)
	)
	(footprint ""
		(layer "F.Cu")
		(at 34.544 -159.2834)
		(property "Reference" "C91"
			(at 0 0 0)
			(layer "F.SilkS")
			(hide yes)
			(effects
				(font
					(size 1.27 1.27)
				)
			)
		)
		(property "Value" "SC100P50V2JN-3GP"
			(at 1.1811 -2.7051 0)
			(unlocked yes)
			(layer "F.Fab")
			(hide yes)
			(effects
				(font
					(size 1.016 1.016)
					(thickness 0.1524)
				)
			)
		)
		(property "Device Type" "C402H22"
			(at 1.1811 -4.2291 0)
			(unlocked yes)
			(layer "F.Fab")
			(hide yes)
			(effects
				(font
					(size 1.016 1.016)
					(thickness 0.1524)
				)
			)
		)
		(duplicate_pad_numbers_are_jumpers no)
		(fp_rect
			(start -0.4318 0.9525)
			(end 0.4318 -0.9525)
			(stroke
				(width 0)
				(type default)
			)
			(fill no)
			(layer "F.CrtYd")
		)
		(fp_rect
			(start -0.4318 0.9525)
			(end 0.4318 -0.9525)
			(stroke
				(width 0)
				(type default)
			)
			(fill no)
			(layer "F.Fab")
		)
		(pad "1" smd custom
			(at 0 -0.4445)
			(size 0.1524 0.1524)
			(layers "F.Cu" "F.Mask" "F.Paste")
			(net "DACAV33")
			(options
				(clearance outline)
				(anchor circle)
			)
			(primitives
				(gr_poly
					(pts
						(arc
							(start 0.3048 -0.2032)
							(mid 0.275042 -0.275042)
							(end 0.2032 -0.3048)
						)
						(arc
							(start -0.2032 -0.3048)
							(mid -0.275042 -0.275042)
							(end -0.3048 -0.2032)
						)
						(arc
							(start -0.3048 0.2032)
							(mid -0.275042 0.275042)
							(end -0.2032 0.3048)
						)
						(arc
							(start 0.2032 0.3048)
							(mid 0.275042 0.275042)
							(end 0.3048 0.2032)
						)
					)
					(width 0)
					(fill yes)
				)
			)
		)
		(pad "2" smd custom
			(at 0 0.4445)
			(size 0.1524 0.1524)
			(layers "F.Cu" "F.Mask" "F.Paste")
			(net "GND")
			(options
				(clearance outline)
				(anchor circle)
			)
			(primitives
				(gr_poly
					(pts
						(arc
							(start 0.3048 -0.2032)
							(mid 0.275042 -0.275042)
							(end 0.2032 -0.3048)
						)
						(arc
							(start -0.2032 -0.3048)
							(mid -0.275042 -0.275042)
							(end -0.3048 -0.2032)
						)
						(arc
							(start -0.3048 0.2032)
							(mid -0.275042 0.275042)
							(end -0.2032 0.3048)
						)
						(arc
							(start 0.2032 0.3048)
							(mid 0.275042 0.275042)
							(end 0.3048 0.2032)
						)
					)
					(width 0)
					(fill yes)
				)
			)
		)
	)
	(footprint ""
		(layer "F.Cu")
		(at 216.67724 -103.123492 180)
		(property "Reference" "R841"
			(at 0 0 180)
			(layer "F.SilkS")
			(hide yes)
			(effects
				(font
					(size 1.27 1.27)
				)
			)
		)
		(property "Value" "39K2R2F-L-GP"
			(at 0.064008 -3.993896 180)
			(unlocked yes)
			(layer "F.Fab")
			(hide yes)
			(effects
				(font
					(size 1.016 1.016)
					(thickness 0.1524)
				)
			)
		)
		(property "Device Type" "R402H16"
			(at 0.064008 -5.517896 180)
			(unlocked yes)
			(layer "F.Fab")
			(hide yes)
			(effects
				(font
					(size 1.016 1.016)
					(thickness 0.1524)
				)
			)
		)
		(duplicate_pad_numbers_are_jumpers no)
		(fp_line
			(start 0.508 -0.9398)
			(end -0.508 -0.9398)
			(stroke
				(width 0.1524)
				(type default)
			)
			(layer "F.SilkS")
		)
		(fp_line
			(start -0.508 -0.9398)
			(end -0.508 0.9398)
			(stroke
				(width 0.1524)
				(type default)
			)
			(layer "F.SilkS")
		)
		(fp_rect
			(start -0.508 0.9398)
			(end 0.508 -0.9398)
			(stroke
				(width 0)
				(type default)
			)
			(fill no)
			(layer "F.CrtYd")
		)
		(fp_rect
			(start -0.508 0.9398)
			(end 0.508 -0.9398)
			(stroke
				(width 0)
				(type default)
			)
			(fill no)
			(layer "F.Fab")
		)
		(pad "1" smd custom
			(at 0 -0.4445 180)
			(size 0.1397 0.1397)
			(layers "F.Cu" "F.Mask" "F.Paste")
			(net "P3V3_M2_MODE")
			(options
				(clearance outline)
				(anchor circle)
			)
			(primitives
				(gr_poly
					(pts
						(arc
							(start -0.1778 -0.2794)
							(mid -0.249642 -0.249642)
							(end -0.2794 -0.1778)
						)
						(arc
							(start -0.2794 0.1778)
							(mid -0.249642 0.249642)
							(end -0.1778 0.2794)
						)
						(arc
							(start 0.1778 0.2794)
							(mid 0.249642 0.249642)
							(end 0.2794 0.1778)
						)
						(arc
							(start 0.2794 -0.1778)
							(mid 0.249642 -0.249642)
							(end 0.1778 -0.2794)
						)
					)
					(width 0)
					(fill yes)
				)
			)
		)
		(pad "2" smd custom
			(at 0 0.4445 180)
			(size 0.1397 0.1397)
			(layers "F.Cu" "F.Mask" "F.Paste")
			(net "IOM_FULL_PGOOD")
			(options
				(clearance outline)
				(anchor circle)
			)
			(primitives
				(gr_poly
					(pts
						(arc
							(start -0.1778 -0.2794)
							(mid -0.249642 -0.249642)
							(end -0.2794 -0.1778)
						)
						(arc
							(start -0.2794 0.1778)
							(mid -0.249642 0.249642)
							(end -0.1778 0.2794)
						)
						(arc
							(start 0.1778 0.2794)
							(mid 0.249642 0.249642)
							(end 0.2794 0.1778)
						)
						(arc
							(start 0.2794 -0.1778)
							(mid 0.249642 -0.249642)
							(end 0.1778 -0.2794)
						)
					)
					(width 0)
					(fill yes)
				)
			)
		)
	)
	(footprint ""
		(layer "F.Cu")
		(at 77.372718 -150.261574)
		(property "Reference" "R408"
			(at 0 0 0)
			(layer "F.SilkS")
			(hide yes)
			(effects
				(font
					(size 1.27 1.27)
				)
			)
		)
		(property "Value" "4K7R2F-GP"
			(at 0.064008 -3.993896 0)
			(unlocked yes)
			(layer "F.Fab")
			(hide yes)
			(effects
				(font
					(size 1.016 1.016)
					(thickness 0.1524)
				)
			)
		)
		(property "Device Type" "R402H16"
			(at 0.064008 -5.517896 0)
			(unlocked yes)
			(layer "F.Fab")
			(hide yes)
			(effects
				(font
					(size 1.016 1.016)
					(thickness 0.1524)
				)
			)
		)
		(duplicate_pad_numbers_are_jumpers no)
		(fp_line
			(start -0.508 -0.9398)
			(end -0.508 0.9398)
			(stroke
				(width 0.1524)
				(type default)
			)
			(layer "F.SilkS")
		)
		(fp_line
			(start 0.508 -0.9398)
			(end -0.508 -0.9398)
			(stroke
				(width 0.1524)
				(type default)
			)
			(layer "F.SilkS")
		)
		(fp_rect
			(start -0.508 0.9398)
			(end 0.508 -0.9398)
			(stroke
				(width 0)
				(type default)
			)
			(fill no)
			(layer "F.CrtYd")
		)
		(fp_rect
			(start -0.508 0.9398)
			(end 0.508 -0.9398)
			(stroke
				(width 0)
				(type default)
			)
			(fill no)
			(layer "F.Fab")
		)
		(pad "1" smd custom
			(at 0 -0.4445)
			(size 0.1397 0.1397)
			(layers "F.Cu" "F.Mask" "F.Paste")
			(net "COMP_TO_BMC_RESET_R")
			(options
				(clearance outline)
				(anchor circle)
			)
			(primitives
				(gr_poly
					(pts
						(arc
							(start -0.1778 -0.2794)
							(mid -0.249642 -0.249642)
							(end -0.2794 -0.1778)
						)
						(arc
							(start -0.2794 0.1778)
							(mid -0.249642 0.249642)
							(end -0.1778 0.2794)
						)
						(arc
							(start 0.1778 0.2794)
							(mid 0.249642 0.249642)
							(end 0.2794 0.1778)
						)
						(arc
							(start 0.2794 -0.1778)
							(mid 0.249642 -0.249642)
							(end 0.1778 -0.2794)
						)
					)
					(width 0)
					(fill yes)
				)
			)
		)
		(pad "2" smd custom
			(at 0 0.4445)
			(size 0.1397 0.1397)
			(layers "F.Cu" "F.Mask" "F.Paste")
			(net "GND")
			(options
				(clearance outline)
				(anchor circle)
			)
			(primitives
				(gr_poly
					(pts
						(arc
							(start -0.1778 -0.2794)
							(mid -0.249642 -0.249642)
							(end -0.2794 -0.1778)
						)
						(arc
							(start -0.2794 0.1778)
							(mid -0.249642 0.249642)
							(end -0.1778 0.2794)
						)
						(arc
							(start 0.1778 0.2794)
							(mid 0.249642 0.249642)
							(end 0.2794 0.1778)
						)
						(arc
							(start 0.2794 -0.1778)
							(mid 0.249642 -0.249642)
							(end 0.1778 -0.2794)
						)
					)
					(width 0)
					(fill yes)
				)
			)
		)
	)
	(footprint ""
		(layer "F.Cu")
		(at 85.470746 -145.471134 -90)
		(property "Reference" "R130"
			(at 0 0 270)
			(layer "F.SilkS")
			(hide yes)
			(effects
				(font
					(size 1.27 1.27)
				)
			)
		)
		(property "Value" "0R2J-2-GP"
			(at 0.064008 -3.993896 270)
			(unlocked yes)
			(layer "F.Fab")
			(hide yes)
			(effects
				(font
					(size 1.016 1.016)
					(thickness 0.1524)
				)
			)
		)
		(property "Device Type" "R402H16"
			(at 0.064008 -5.517896 270)
			(unlocked yes)
			(layer "F.Fab")
			(hide yes)
			(effects
				(font
					(size 1.016 1.016)
					(thickness 0.1524)
				)
			)
		)
		(duplicate_pad_numbers_are_jumpers no)
		(fp_line
			(start -0.508 -0.9398)
			(end -0.508 0.9398)
			(stroke
				(width 0.1524)
				(type default)
			)
			(layer "F.SilkS")
		)
		(fp_line
			(start 0.508 -0.9398)
			(end -0.508 -0.9398)
			(stroke
				(width 0.1524)
				(type default)
			)
			(layer "F.SilkS")
		)
		(fp_rect
			(start -0.508 0.9398)
			(end 0.508 -0.9398)
			(stroke
				(width 0)
				(type default)
			)
			(fill no)
			(layer "F.CrtYd")
		)
		(fp_rect
			(start -0.508 0.9398)
			(end 0.508 -0.9398)
			(stroke
				(width 0)
				(type default)
			)
			(fill no)
			(layer "F.Fab")
		)
		(pad "1" smd custom
			(at 0 -0.4445 270)
			(size 0.1397 0.1397)
			(layers "F.Cu" "F.Mask" "F.Paste")
			(net "I2C_EXP_RMT_SDA")
			(options
				(clearance outline)
				(anchor circle)
			)
			(primitives
				(gr_poly
					(pts
						(arc
							(start -0.1778 -0.2794)
							(mid -0.249642 -0.249642)
							(end -0.2794 -0.1778)
						)
						(arc
							(start -0.2794 0.1778)
							(mid -0.249642 0.249642)
							(end -0.1778 0.2794)
						)
						(arc
							(start 0.1778 0.2794)
							(mid 0.249642 0.249642)
							(end 0.2794 0.1778)
						)
						(arc
							(start 0.2794 -0.1778)
							(mid 0.249642 -0.249642)
							(end 0.1778 -0.2794)
						)
					)
					(width 0)
					(fill yes)
				)
			)
		)
		(pad "2" smd custom
			(at 0 0.4445 270)
			(size 0.1397 0.1397)
			(layers "F.Cu" "F.Mask" "F.Paste")
			(net "I2C_EXP_RMT_SDA_R")
			(options
				(clearance outline)
				(anchor circle)
			)
			(primitives
				(gr_poly
					(pts
						(arc
							(start -0.1778 -0.2794)
							(mid -0.249642 -0.249642)
							(end -0.2794 -0.1778)
						)
						(arc
							(start -0.2794 0.1778)
							(mid -0.249642 0.249642)
							(end -0.1778 0.2794)
						)
						(arc
							(start 0.1778 0.2794)
							(mid 0.249642 0.249642)
							(end 0.2794 0.1778)
						)
						(arc
							(start 0.2794 -0.1778)
							(mid 0.249642 -0.249642)
							(end 0.1778 -0.2794)
						)
					)
					(width 0)
					(fill yes)
				)
			)
		)
	)
	(footprint ""
		(layer "F.Cu")
		(at 59.8678 -138.303)
		(property "Reference" "TP71"
			(at 0 0 0)
			(layer "F.SilkS")
			(hide yes)
			(effects
				(font
					(size 1.27 1.27)
				)
			)
		)
		(property "Value" "TPAD28-2-GP"
			(at -0.0127 -1.6637 0)
			(unlocked yes)
			(layer "F.Fab")
			(hide yes)
			(effects
				(font
					(size 1.016 1.016)
					(thickness 0.1524)
				)
			)
		)
		(property "Device Type" "TPAD28"
			(at -0.0127 -3.1877 0)
			(unlocked yes)
			(layer "F.Fab")
			(hide yes)
			(effects
				(font
					(size 1.016 1.016)
					(thickness 0.1524)
				)
			)
		)
		(duplicate_pad_numbers_are_jumpers no)
		(fp_poly
			(pts
				(arc
					(start 0.3556 0)
					(mid -0.3556 0)
					(end 0.3556 0)
				)
			)
			(stroke
				(width 0)
				(type default)
			)
			(fill no)
			(layer "F.CrtYd")
		)
		(fp_poly
			(pts
				(arc
					(start 0.6096 0)
					(mid -0.6096 0)
					(end 0.6096 0)
				)
			)
			(stroke
				(width 0)
				(type default)
			)
			(fill no)
			(layer "F.Fab")
		)
		(pad "1" smd circle
			(at 0 0)
			(size 0.7112 0.7112)
			(layers "F.Cu" "F.Mask" "F.Paste")
			(net "TP_BMC_GPIOI4")
		)
	)
	(footprint ""
		(layer "F.Cu")
		(at 94.98838 -21.9202 90)
		(property "Reference" "D17"
			(at 0 0 90)
			(layer "F.SilkS")
			(hide yes)
			(effects
				(font
					(size 1.27 1.27)
				)
			)
		)
		(property "Value" "PESD5V0S1BL-1-GP"
			(at 1.8923 -1.5621 90)
			(unlocked yes)
			(layer "F.Fab")
			(hide yes)
			(effects
				(font
					(size 1.016 1.016)
					(thickness 0.1524)
				)
			)
		)
		(property "Device Type" "SOD882-10D6-1H20"
			(at 1.8923 -3.0861 90)
			(unlocked yes)
			(layer "F.Fab")
			(hide yes)
			(effects
				(font
					(size 1.016 1.016)
					(thickness 0.1524)
				)
			)
		)
		(duplicate_pad_numbers_are_jumpers no)
		(fp_line
			(start -0.3048 -0.9271)
			(end 0.3048 -0.9271)
			(stroke
				(width 0.254)
				(type default)
			)
			(layer "F.SilkS")
		)
		(fp_rect
			(start -0.2921 0.4953)
			(end 0.2921 -0.4953)
			(stroke
				(width 0)
				(type default)
			)
			(fill no)
			(layer "F.CrtYd")
		)
		(fp_poly
			(pts
				(xy -0.4318 0.8001) (xy -0.4318 -0.266192) (xy -0.2921 -0.266192) (xy -0.2921 0.4953) (xy 0.2921 0.4953)
				(xy 0.2921 -0.4953) (xy -0.2921 -0.4953) (xy -0.2921 -0.2667) (xy -0.4318 -0.2667) (xy -0.4318 -0.8001)
				(xy 0.4318 -0.8001) (xy 0.4318 0.8001)
			)
			(stroke
				(width 0)
				(type default)
			)
			(fill no)
			(layer "F.CrtYd")
		)
		(fp_rect
			(start -0.4318 0.8001)
			(end 0.4318 -0.8001)
			(stroke
				(width 0)
				(type default)
			)
			(fill no)
			(layer "F.Fab")
		)
		(pad "1" smd custom
			(at 0 -0.4445 90)
			(size 0.1143 0.1143)
			(layers "F.Cu" "F.Mask" "F.Paste")
			(net "UART_IOM_RX")
			(options
				(clearance outline)
				(anchor circle)
			)
			(primitives
				(gr_poly
					(pts
						(arc
							(start -0.2032 0.2286)
							(mid -0.275042 0.198842)
							(end -0.3048 0.127)
						)
						(arc
							(start -0.3048 -0.127)
							(mid -0.275042 -0.198842)
							(end -0.2032 -0.2286)
						)
						(arc
							(start 0.2032 -0.2286)
							(mid 0.275042 -0.198842)
							(end 0.3048 -0.127)
						)
						(arc
							(start 0.3048 0.127)
							(mid 0.275042 0.198842)
							(end 0.2032 0.2286)
						)
					)
					(width 0)
					(fill yes)
				)
			)
		)
		(pad "2" smd custom
			(at 0 0.4445 90)
			(size 0.1143 0.1143)
			(layers "F.Cu" "F.Mask" "F.Paste")
			(net "GND")
			(options
				(clearance outline)
				(anchor circle)
			)
			(primitives
				(gr_poly
					(pts
						(arc
							(start 0.2032 -0.2286)
							(mid 0.275042 -0.198842)
							(end 0.3048 -0.127)
						)
						(arc
							(start 0.3048 0.127)
							(mid 0.275042 0.198842)
							(end 0.2032 0.2286)
						)
						(arc
							(start -0.2032 0.2286)
							(mid -0.275042 0.198842)
							(end -0.3048 0.127)
						)
						(arc
							(start -0.3048 -0.127)
							(mid -0.275042 -0.198842)
							(end -0.2032 -0.2286)
						)
					)
					(width 0)
					(fill yes)
				)
			)
		)
	)
	(footprint ""
		(layer "F.Cu")
		(at 93.72092 -61.292232 90)
		(property "Reference" "R719"
			(at 0 0 90)
			(layer "F.SilkS")
			(hide yes)
			(effects
				(font
					(size 1.27 1.27)
				)
			)
		)
		(property "Value" "100KR2J-4-GP"
			(at 0.064008 -3.993896 90)
			(unlocked yes)
			(layer "F.Fab")
			(hide yes)
			(effects
				(font
					(size 1.016 1.016)
					(thickness 0.1524)
				)
			)
		)
		(property "Device Type" "R402H15"
			(at 0.064008 -5.517896 90)
			(unlocked yes)
			(layer "F.Fab")
			(hide yes)
			(effects
				(font
					(size 1.016 1.016)
					(thickness 0.1524)
				)
			)
		)
		(duplicate_pad_numbers_are_jumpers no)
		(fp_line
			(start 0.508 -0.9398)
			(end -0.508 -0.9398)
			(stroke
				(width 0.1524)
				(type default)
			)
			(layer "F.SilkS")
		)
		(fp_line
			(start -0.508 -0.9398)
			(end -0.508 0.9398)
			(stroke
				(width 0.1524)
				(type default)
			)
			(layer "F.SilkS")
		)
		(fp_rect
			(start -0.508 0.9398)
			(end 0.508 -0.9398)
			(stroke
				(width 0)
				(type default)
			)
			(fill no)
			(layer "F.CrtYd")
		)
		(fp_rect
			(start -0.508 0.9398)
			(end 0.508 -0.9398)
			(stroke
				(width 0)
				(type default)
			)
			(fill no)
			(layer "F.Fab")
		)
		(pad "1" smd custom
			(at 0 -0.4445 90)
			(size 0.1397 0.1397)
			(layers "F.Cu" "F.Mask" "F.Paste")
			(net "GND")
			(options
				(clearance outline)
				(anchor circle)
			)
			(primitives
				(gr_poly
					(pts
						(arc
							(start -0.1778 -0.2794)
							(mid -0.249642 -0.249642)
							(end -0.2794 -0.1778)
						)
						(arc
							(start -0.2794 0.1778)
							(mid -0.249642 0.249642)
							(end -0.1778 0.2794)
						)
						(arc
							(start 0.1778 0.2794)
							(mid 0.249642 0.249642)
							(end 0.2794 0.1778)
						)
						(arc
							(start 0.2794 -0.1778)
							(mid 0.249642 -0.249642)
							(end 0.1778 -0.2794)
						)
					)
					(width 0)
					(fill yes)
				)
			)
		)
		(pad "2" smd custom
			(at 0 0.4445 90)
			(size 0.1397 0.1397)
			(layers "F.Cu" "F.Mask" "F.Paste")
			(net "IOM_FULL_PWR_EN")
			(options
				(clearance outline)
				(anchor circle)
			)
			(primitives
				(gr_poly
					(pts
						(arc
							(start -0.1778 -0.2794)
							(mid -0.249642 -0.249642)
							(end -0.2794 -0.1778)
						)
						(arc
							(start -0.2794 0.1778)
							(mid -0.249642 0.249642)
							(end -0.1778 0.2794)
						)
						(arc
							(start 0.1778 0.2794)
							(mid 0.249642 0.249642)
							(end 0.2794 0.1778)
						)
						(arc
							(start 0.2794 -0.1778)
							(mid 0.249642 -0.249642)
							(end 0.1778 -0.2794)
						)
					)
					(width 0)
					(fill yes)
				)
			)
		)
	)
	(footprint ""
		(layer "F.Cu")
		(at 99.373944 -148.61032 -90)
		(property "Reference" "R35"
			(at 0 0 270)
			(layer "F.SilkS")
			(hide yes)
			(effects
				(font
					(size 1.27 1.27)
				)
			)
		)
		(property "Value" "4K7R2F-GP"
			(at 0.064008 -3.993896 270)
			(unlocked yes)
			(layer "F.Fab")
			(hide yes)
			(effects
				(font
					(size 1.016 1.016)
					(thickness 0.1524)
				)
			)
		)
		(property "Device Type" "R402H16"
			(at 0.064008 -5.517896 270)
			(unlocked yes)
			(layer "F.Fab")
			(hide yes)
			(effects
				(font
					(size 1.016 1.016)
					(thickness 0.1524)
				)
			)
		)
		(duplicate_pad_numbers_are_jumpers no)
		(fp_line
			(start -0.508 -0.9398)
			(end -0.508 0.9398)
			(stroke
				(width 0.1524)
				(type default)
			)
			(layer "F.SilkS")
		)
		(fp_line
			(start 0.508 -0.9398)
			(end -0.508 -0.9398)
			(stroke
				(width 0.1524)
				(type default)
			)
			(layer "F.SilkS")
		)
		(fp_rect
			(start -0.508 0.9398)
			(end 0.508 -0.9398)
			(stroke
				(width 0)
				(type default)
			)
			(fill no)
			(layer "F.CrtYd")
		)
		(fp_rect
			(start -0.508 0.9398)
			(end 0.508 -0.9398)
			(stroke
				(width 0)
				(type default)
			)
			(fill no)
			(layer "F.Fab")
		)
		(pad "1" smd custom
			(at 0 -0.4445 270)
			(size 0.1397 0.1397)
			(layers "F.Cu" "F.Mask" "F.Paste")
			(net "P3V3_STBY")
			(options
				(clearance outline)
				(anchor circle)
			)
			(primitives
				(gr_poly
					(pts
						(arc
							(start -0.1778 -0.2794)
							(mid -0.249642 -0.249642)
							(end -0.2794 -0.1778)
						)
						(arc
							(start -0.2794 0.1778)
							(mid -0.249642 0.249642)
							(end -0.1778 0.2794)
						)
						(arc
							(start 0.1778 0.2794)
							(mid 0.249642 0.249642)
							(end 0.2794 0.1778)
						)
						(arc
							(start 0.2794 -0.1778)
							(mid 0.249642 -0.249642)
							(end 0.1778 -0.2794)
						)
					)
					(width 0)
					(fill yes)
				)
			)
		)
		(pad "2" smd custom
			(at 0 0.4445 270)
			(size 0.1397 0.1397)
			(layers "F.Cu" "F.Mask" "F.Paste")
			(net "USB_EN_3")
			(options
				(clearance outline)
				(anchor circle)
			)
			(primitives
				(gr_poly
					(pts
						(arc
							(start -0.1778 -0.2794)
							(mid -0.249642 -0.249642)
							(end -0.2794 -0.1778)
						)
						(arc
							(start -0.2794 0.1778)
							(mid -0.249642 0.249642)
							(end -0.1778 0.2794)
						)
						(arc
							(start 0.1778 0.2794)
							(mid 0.249642 0.249642)
							(end 0.2794 0.1778)
						)
						(arc
							(start 0.2794 -0.1778)
							(mid 0.249642 -0.249642)
							(end 0.1778 -0.2794)
						)
					)
					(width 0)
					(fill yes)
				)
			)
		)
	)
	(footprint ""
		(layer "F.Cu")
		(at 39.0398 -158.623 180)
		(property "Reference" "R328"
			(at 0 0 180)
			(layer "F.SilkS")
			(hide yes)
			(effects
				(font
					(size 1.27 1.27)
				)
			)
		)
		(property "Value" "0R2J-2-GP"
			(at 0.064008 -3.993896 180)
			(unlocked yes)
			(layer "F.Fab")
			(hide yes)
			(effects
				(font
					(size 1.016 1.016)
					(thickness 0.1524)
				)
			)
		)
		(property "Device Type" "R402H16"
			(at 0.064008 -5.517896 180)
			(unlocked yes)
			(layer "F.Fab")
			(hide yes)
			(effects
				(font
					(size 1.016 1.016)
					(thickness 0.1524)
				)
			)
		)
		(duplicate_pad_numbers_are_jumpers no)
		(fp_line
			(start 0.508 -0.9398)
			(end -0.508 -0.9398)
			(stroke
				(width 0.1524)
				(type default)
			)
			(layer "F.SilkS")
		)
		(fp_line
			(start -0.508 -0.9398)
			(end -0.508 0.9398)
			(stroke
				(width 0.1524)
				(type default)
			)
			(layer "F.SilkS")
		)
		(fp_rect
			(start -0.508 0.9398)
			(end 0.508 -0.9398)
			(stroke
				(width 0)
				(type default)
			)
			(fill no)
			(layer "F.CrtYd")
		)
		(fp_rect
			(start -0.508 0.9398)
			(end 0.508 -0.9398)
			(stroke
				(width 0)
				(type default)
			)
			(fill no)
			(layer "F.Fab")
		)
		(pad "1" smd custom
			(at 0 -0.4445 180)
			(size 0.1397 0.1397)
			(layers "F.Cu" "F.Mask" "F.Paste")
			(net "UART_COMP_OUT_TX_R")
			(options
				(clearance outline)
				(anchor circle)
			)
			(primitives
				(gr_poly
					(pts
						(arc
							(start -0.1778 -0.2794)
							(mid -0.249642 -0.249642)
							(end -0.2794 -0.1778)
						)
						(arc
							(start -0.2794 0.1778)
							(mid -0.249642 0.249642)
							(end -0.1778 0.2794)
						)
						(arc
							(start 0.1778 0.2794)
							(mid 0.249642 0.249642)
							(end 0.2794 0.1778)
						)
						(arc
							(start 0.2794 -0.1778)
							(mid 0.249642 -0.249642)
							(end 0.1778 -0.2794)
						)
					)
					(width 0)
					(fill yes)
				)
			)
		)
		(pad "2" smd custom
			(at 0 0.4445 180)
			(size 0.1397 0.1397)
			(layers "F.Cu" "F.Mask" "F.Paste")
			(net "UART_COMP_OUT_TX")
			(options
				(clearance outline)
				(anchor circle)
			)
			(primitives
				(gr_poly
					(pts
						(arc
							(start -0.1778 -0.2794)
							(mid -0.249642 -0.249642)
							(end -0.2794 -0.1778)
						)
						(arc
							(start -0.2794 0.1778)
							(mid -0.249642 0.249642)
							(end -0.1778 0.2794)
						)
						(arc
							(start 0.1778 0.2794)
							(mid 0.249642 0.249642)
							(end 0.2794 0.1778)
						)
						(arc
							(start 0.2794 -0.1778)
							(mid 0.249642 -0.249642)
							(end 0.1778 -0.2794)
						)
					)
					(width 0)
					(fill yes)
				)
			)
		)
	)
	(footprint ""
		(layer "F.Cu")
		(at 72.822562 -156.644594 180)
		(property "Reference" "R305"
			(at 0 0 180)
			(layer "F.SilkS")
			(hide yes)
			(effects
				(font
					(size 1.27 1.27)
				)
			)
		)
		(property "Value" "10KR2F-2-GP"
			(at 0.064008 -3.993896 180)
			(unlocked yes)
			(layer "F.Fab")
			(hide yes)
			(effects
				(font
					(size 1.016 1.016)
					(thickness 0.1524)
				)
			)
		)
		(property "Device Type" "R402H16"
			(at 0.064008 -5.517896 180)
			(unlocked yes)
			(layer "F.Fab")
			(hide yes)
			(effects
				(font
					(size 1.016 1.016)
					(thickness 0.1524)
				)
			)
		)
		(duplicate_pad_numbers_are_jumpers no)
		(fp_line
			(start 0.508 -0.9398)
			(end -0.508 -0.9398)
			(stroke
				(width 0.1524)
				(type default)
			)
			(layer "F.SilkS")
		)
		(fp_line
			(start -0.508 -0.9398)
			(end -0.508 0.9398)
			(stroke
				(width 0.1524)
				(type default)
			)
			(layer "F.SilkS")
		)
		(fp_rect
			(start -0.508 0.9398)
			(end 0.508 -0.9398)
			(stroke
				(width 0)
				(type default)
			)
			(fill no)
			(layer "F.CrtYd")
		)
		(fp_rect
			(start -0.508 0.9398)
			(end 0.508 -0.9398)
			(stroke
				(width 0)
				(type default)
			)
			(fill no)
			(layer "F.Fab")
		)
		(pad "1" smd custom
			(at 0 -0.4445 180)
			(size 0.1397 0.1397)
			(layers "F.Cu" "F.Mask" "F.Paste")
			(net "P3V3_STBY")
			(options
				(clearance outline)
				(anchor circle)
			)
			(primitives
				(gr_poly
					(pts
						(arc
							(start -0.1778 -0.2794)
							(mid -0.249642 -0.249642)
							(end -0.2794 -0.1778)
						)
						(arc
							(start -0.2794 0.1778)
							(mid -0.249642 0.249642)
							(end -0.1778 0.2794)
						)
						(arc
							(start 0.1778 0.2794)
							(mid 0.249642 0.249642)
							(end 0.2794 0.1778)
						)
						(arc
							(start 0.2794 -0.1778)
							(mid 0.249642 -0.249642)
							(end 0.1778 -0.2794)
						)
					)
					(width 0)
					(fill yes)
				)
			)
		)
		(pad "2" smd custom
			(at 0 0.4445 180)
			(size 0.1397 0.1397)
			(layers "F.Cu" "F.Mask" "F.Paste")
			(net "FM_OSC_50M_EN")
			(options
				(clearance outline)
				(anchor circle)
			)
			(primitives
				(gr_poly
					(pts
						(arc
							(start -0.1778 -0.2794)
							(mid -0.249642 -0.249642)
							(end -0.2794 -0.1778)
						)
						(arc
							(start -0.2794 0.1778)
							(mid -0.249642 0.249642)
							(end -0.1778 0.2794)
						)
						(arc
							(start 0.1778 0.2794)
							(mid 0.249642 0.249642)
							(end 0.2794 0.1778)
						)
						(arc
							(start 0.2794 -0.1778)
							(mid 0.249642 -0.249642)
							(end 0.1778 -0.2794)
						)
					)
					(width 0)
					(fill yes)
				)
			)
		)
	)
	(footprint ""
		(layer "F.Cu")
		(at 181.4322 -6.8326 -90)
		(property "Reference" "Q28"
			(at 0 0 270)
			(layer "F.SilkS")
			(hide yes)
			(effects
				(font
					(size 1.27 1.27)
				)
			)
		)
		(property "Value" "2N7002K-1-GP"
			(at 0.127 -8.9662 270)
			(unlocked yes)
			(layer "F.Fab")
			(hide yes)
			(effects
				(font
					(size 1.016 1.016)
					(thickness 0.1524)
				)
			)
		)
		(property "Device Type" "SOT23DGS2D4H44"
			(at 0.127 -10.4902 270)
			(unlocked yes)
			(layer "F.Fab")
			(hide yes)
			(effects
				(font
					(size 1.016 1.016)
					(thickness 0.1524)
				)
			)
		)
		(duplicate_pad_numbers_are_jumpers no)
		(fp_line
			(start -1.651 1.778)
			(end 1.651 1.778)
			(stroke
				(width 0.1524)
				(type default)
			)
			(layer "F.SilkS")
		)
		(fp_line
			(start 1.651 1.778)
			(end 1.651 -1.778)
			(stroke
				(width 0.1524)
				(type default)
			)
			(layer "F.SilkS")
		)
		(fp_line
			(start -1.651 -1.778)
			(end -1.651 1.778)
			(stroke
				(width 0.1524)
				(type default)
			)
			(layer "F.SilkS")
		)
		(fp_line
			(start 1.651 -1.778)
			(end -1.651 -1.778)
			(stroke
				(width 0.1524)
				(type default)
			)
			(layer "F.SilkS")
		)
		(fp_poly
			(pts
				(xy -1.778 1.8796) (xy -1.778 -1.8796) (xy 1.778 -1.8796) (xy 1.778 1.8796)
			)
			(stroke
				(width 0)
				(type default)
			)
			(fill no)
			(layer "F.CrtYd")
		)
		(fp_poly
			(pts
				(xy -1.778 1.8796) (xy -1.778 -1.8796) (xy 1.778 -1.8796) (xy 1.778 1.8796)
			)
			(stroke
				(width 0)
				(type default)
			)
			(fill no)
			(layer "F.Fab")
		)
		(pad "D" smd custom
			(at 0 -0.9525 270)
			(size 0.1905 0.1905)
			(layers "F.Cu" "F.Mask" "F.Paste")
			(net "BMC_ML_PWR_BLUE_LED_L")
			(options
				(clearance outline)
				(anchor circle)
			)
			(primitives
				(gr_poly
					(pts
						(arc
							(start -0.1778 0.5715)
							(mid -0.321484 0.511984)
							(end -0.381 0.3683)
						)
						(arc
							(start -0.381 -0.3683)
							(mid -0.321484 -0.511984)
							(end -0.1778 -0.5715)
						)
						(arc
							(start 0.1778 -0.5715)
							(mid 0.321484 -0.511984)
							(end 0.381 -0.3683)
						)
						(arc
							(start 0.381 0.3683)
							(mid 0.321484 0.511984)
							(end 0.1778 0.5715)
						)
					)
					(width 0)
					(fill yes)
				)
			)
		)
		(pad "G" smd custom
			(at -0.98425 0.9525 270)
			(size 0.1905 0.1905)
			(layers "F.Cu" "F.Mask" "F.Paste")
			(net "BMC_ML_PWR_BLUE_LED_R")
			(options
				(clearance outline)
				(anchor circle)
			)
			(primitives
				(gr_poly
					(pts
						(arc
							(start -0.1778 0.5715)
							(mid -0.321484 0.511984)
							(end -0.381 0.3683)
						)
						(arc
							(start -0.381 -0.3683)
							(mid -0.321484 -0.511984)
							(end -0.1778 -0.5715)
						)
						(arc
							(start 0.1778 -0.5715)
							(mid 0.321484 -0.511984)
							(end 0.381 -0.3683)
						)
						(arc
							(start 0.381 0.3683)
							(mid 0.321484 0.511984)
							(end 0.1778 0.5715)
						)
					)
					(width 0)
					(fill yes)
				)
			)
		)
		(pad "S" smd custom
			(at 0.98425 0.9525 270)
			(size 0.1905 0.1905)
			(layers "F.Cu" "F.Mask" "F.Paste")
			(net "GND")
			(options
				(clearance outline)
				(anchor circle)
			)
			(primitives
				(gr_poly
					(pts
						(arc
							(start -0.1778 0.5715)
							(mid -0.321484 0.511984)
							(end -0.381 0.3683)
						)
						(arc
							(start -0.381 -0.3683)
							(mid -0.321484 -0.511984)
							(end -0.1778 -0.5715)
						)
						(arc
							(start 0.1778 -0.5715)
							(mid 0.321484 -0.511984)
							(end 0.381 -0.3683)
						)
						(arc
							(start 0.381 0.3683)
							(mid 0.321484 0.511984)
							(end 0.1778 0.5715)
						)
					)
					(width 0)
					(fill yes)
				)
			)
		)
	)
	(footprint ""
		(layer "F.Cu")
		(at 88.0872 -138.1252 90)
		(property "Reference" "R136"
			(at 0 0 90)
			(layer "F.SilkS")
			(hide yes)
			(effects
				(font
					(size 1.27 1.27)
				)
			)
		)
		(property "Value" "8K2R2J-3-GP"
			(at 0.064008 -3.993896 90)
			(unlocked yes)
			(layer "F.Fab")
			(hide yes)
			(effects
				(font
					(size 1.016 1.016)
					(thickness 0.1524)
				)
			)
		)
		(property "Device Type" "R402H16"
			(at 0.064008 -5.517896 90)
			(unlocked yes)
			(layer "F.Fab")
			(hide yes)
			(effects
				(font
					(size 1.016 1.016)
					(thickness 0.1524)
				)
			)
		)
		(duplicate_pad_numbers_are_jumpers no)
		(fp_line
			(start 0.508 -0.9398)
			(end -0.508 -0.9398)
			(stroke
				(width 0.1524)
				(type default)
			)
			(layer "F.SilkS")
		)
		(fp_line
			(start -0.508 -0.9398)
			(end -0.508 0.9398)
			(stroke
				(width 0.1524)
				(type default)
			)
			(layer "F.SilkS")
		)
		(fp_rect
			(start -0.508 0.9398)
			(end 0.508 -0.9398)
			(stroke
				(width 0)
				(type default)
			)
			(fill no)
			(layer "F.CrtYd")
		)
		(fp_rect
			(start -0.508 0.9398)
			(end 0.508 -0.9398)
			(stroke
				(width 0)
				(type default)
			)
			(fill no)
			(layer "F.Fab")
		)
		(pad "1" smd custom
			(at 0 -0.4445 90)
			(size 0.1397 0.1397)
			(layers "F.Cu" "F.Mask" "F.Paste")
			(net "EEPROM_A0")
			(options
				(clearance outline)
				(anchor circle)
			)
			(primitives
				(gr_poly
					(pts
						(arc
							(start -0.1778 -0.2794)
							(mid -0.249642 -0.249642)
							(end -0.2794 -0.1778)
						)
						(arc
							(start -0.2794 0.1778)
							(mid -0.249642 0.249642)
							(end -0.1778 0.2794)
						)
						(arc
							(start 0.1778 0.2794)
							(mid 0.249642 0.249642)
							(end 0.2794 0.1778)
						)
						(arc
							(start 0.2794 -0.1778)
							(mid 0.249642 -0.249642)
							(end 0.1778 -0.2794)
						)
					)
					(width 0)
					(fill yes)
				)
			)
		)
		(pad "2" smd custom
			(at 0 0.4445 90)
			(size 0.1397 0.1397)
			(layers "F.Cu" "F.Mask" "F.Paste")
			(net "GND")
			(options
				(clearance outline)
				(anchor circle)
			)
			(primitives
				(gr_poly
					(pts
						(arc
							(start -0.1778 -0.2794)
							(mid -0.249642 -0.249642)
							(end -0.2794 -0.1778)
						)
						(arc
							(start -0.2794 0.1778)
							(mid -0.249642 0.249642)
							(end -0.1778 0.2794)
						)
						(arc
							(start 0.1778 0.2794)
							(mid 0.249642 0.249642)
							(end 0.2794 0.1778)
						)
						(arc
							(start 0.2794 -0.1778)
							(mid 0.249642 -0.249642)
							(end 0.1778 -0.2794)
						)
					)
					(width 0)
					(fill yes)
				)
			)
		)
	)
	(footprint ""
		(layer "F.Cu")
		(at 80.7212 -133.6294 90)
		(property "Reference" "C32"
			(at 0 0 90)
			(layer "F.SilkS")
			(hide yes)
			(effects
				(font
					(size 1.27 1.27)
				)
			)
		)
		(property "Value" "SCD1U16V2KX-3GP"
			(at 1.1811 -2.7051 90)
			(unlocked yes)
			(layer "F.Fab")
			(hide yes)
			(effects
				(font
					(size 1.016 1.016)
					(thickness 0.1524)
				)
			)
		)
		(property "Device Type" "C402H22"
			(at 1.1811 -4.2291 90)
			(unlocked yes)
			(layer "F.Fab")
			(hide yes)
			(effects
				(font
					(size 1.016 1.016)
					(thickness 0.1524)
				)
			)
		)
		(duplicate_pad_numbers_are_jumpers no)
		(fp_rect
			(start -0.4318 0.9525)
			(end 0.4318 -0.9525)
			(stroke
				(width 0)
				(type default)
			)
			(fill no)
			(layer "F.CrtYd")
		)
		(fp_rect
			(start -0.4318 0.9525)
			(end 0.4318 -0.9525)
			(stroke
				(width 0)
				(type default)
			)
			(fill no)
			(layer "F.Fab")
		)
		(pad "1" smd custom
			(at 0 -0.4445 90)
			(size 0.1524 0.1524)
			(layers "F.Cu" "F.Mask" "F.Paste")
			(net "DEBUG_HDR_UART_SEL")
			(options
				(clearance outline)
				(anchor circle)
			)
			(primitives
				(gr_poly
					(pts
						(arc
							(start 0.3048 -0.2032)
							(mid 0.275042 -0.275042)
							(end 0.2032 -0.3048)
						)
						(arc
							(start -0.2032 -0.3048)
							(mid -0.275042 -0.275042)
							(end -0.3048 -0.2032)
						)
						(arc
							(start -0.3048 0.2032)
							(mid -0.275042 0.275042)
							(end -0.2032 0.3048)
						)
						(arc
							(start 0.2032 0.3048)
							(mid 0.275042 0.275042)
							(end 0.3048 0.2032)
						)
					)
					(width 0)
					(fill yes)
				)
			)
		)
		(pad "2" smd custom
			(at 0 0.4445 90)
			(size 0.1524 0.1524)
			(layers "F.Cu" "F.Mask" "F.Paste")
			(net "GND")
			(options
				(clearance outline)
				(anchor circle)
			)
			(primitives
				(gr_poly
					(pts
						(arc
							(start 0.3048 -0.2032)
							(mid 0.275042 -0.275042)
							(end 0.2032 -0.3048)
						)
						(arc
							(start -0.2032 -0.3048)
							(mid -0.275042 -0.275042)
							(end -0.3048 -0.2032)
						)
						(arc
							(start -0.3048 0.2032)
							(mid -0.275042 0.275042)
							(end -0.2032 0.3048)
						)
						(arc
							(start 0.2032 0.3048)
							(mid 0.275042 0.275042)
							(end 0.3048 0.2032)
						)
					)
					(width 0)
					(fill yes)
				)
			)
		)
	)
	(footprint ""
		(layer "F.Cu")
		(at 51.5112 -129.5654)
		(property "Reference" "TP9"
			(at 0 0 0)
			(layer "F.SilkS")
			(hide yes)
			(effects
				(font
					(size 1.27 1.27)
				)
			)
		)
		(property "Value" "TPAD28-2-GP"
			(at -0.0127 -1.6637 0)
			(unlocked yes)
			(layer "F.Fab")
			(hide yes)
			(effects
				(font
					(size 1.016 1.016)
					(thickness 0.1524)
				)
			)
		)
		(property "Device Type" "TPAD28"
			(at -0.0127 -3.1877 0)
			(unlocked yes)
			(layer "F.Fab")
			(hide yes)
			(effects
				(font
					(size 1.016 1.016)
					(thickness 0.1524)
				)
			)
		)
		(duplicate_pad_numbers_are_jumpers no)
		(fp_poly
			(pts
				(arc
					(start 0.3556 0)
					(mid -0.3556 0)
					(end 0.3556 0)
				)
			)
			(stroke
				(width 0)
				(type default)
			)
			(fill no)
			(layer "F.CrtYd")
		)
		(fp_poly
			(pts
				(arc
					(start 0.6096 0)
					(mid -0.6096 0)
					(end 0.6096 0)
				)
			)
			(stroke
				(width 0)
				(type default)
			)
			(fill no)
			(layer "F.Fab")
		)
		(pad "1" smd circle
			(at 0 0)
			(size 0.7112 0.7112)
			(layers "F.Cu" "F.Mask" "F.Paste")
			(net "TP_BMC0_LPC_LAD0")
		)
	)
	(footprint ""
		(layer "F.Cu")
		(at 50.27168 -184.020714)
		(property "Reference" "C175"
			(at 0 0 0)
			(layer "F.SilkS")
			(hide yes)
			(effects
				(font
					(size 1.27 1.27)
				)
			)
		)
		(property "Value" "ST150U6D3VDM-28-GP"
			(at 0 -9.6012 0)
			(unlocked yes)
			(layer "F.Fab")
			(hide yes)
			(effects
				(font
					(size 1.016 1.016)
					(thickness 0.1524)
				)
			)
		)
		(property "Device Type" "CT7343H83"
			(at 0 -11.1252 0)
			(unlocked yes)
			(layer "F.Fab")
			(hide yes)
			(effects
				(font
					(size 1.016 1.016)
					(thickness 0.1524)
				)
			)
		)
		(duplicate_pad_numbers_are_jumpers no)
		(fp_line
			(start -2.286 -4.8768)
			(end -2.286 -2.032)
			(stroke
				(width 0.1524)
				(type default)
			)
			(layer "F.SilkS")
		)
		(fp_line
			(start -2.286 4.8768)
			(end -2.286 2.032)
			(stroke
				(width 0.1524)
				(type default)
			)
			(layer "F.SilkS")
		)
		(fp_line
			(start 2.1082 -4.699)
			(end -2.1082 -4.699)
			(stroke
				(width 0.508)
				(type default)
			)
			(layer "F.SilkS")
		)
		(fp_line
			(start 2.286 -4.8768)
			(end -2.286 -4.8768)
			(stroke
				(width 0.1524)
				(type default)
			)
			(layer "F.SilkS")
		)
		(fp_line
			(start 2.286 -2.032)
			(end 2.286 -4.8768)
			(stroke
				(width 0.1524)
				(type default)
			)
			(layer "F.SilkS")
		)
		(fp_line
			(start 2.286 2.032)
			(end 2.286 4.8768)
			(stroke
				(width 0.1524)
				(type default)
			)
			(layer "F.SilkS")
		)
		(fp_line
			(start 2.286 4.8768)
			(end -2.286 4.8768)
			(stroke
				(width 0.1524)
				(type default)
			)
			(layer "F.SilkS")
		)
		(fp_rect
			(start -2.1463 3.6449)
			(end 2.1463 -3.6449)
			(stroke
				(width 0)
				(type default)
			)
			(fill no)
			(layer "F.CrtYd")
		)
		(fp_poly
			(pts
				(xy -2.54 4.953) (xy -2.54 4.2926) (xy -3.81 4.2926) (xy -3.81 -4.2926) (xy -2.54 -4.2926) (xy -2.54 -4.953)
				(xy 2.54 -4.953) (xy 2.54 -4.2926) (xy 3.81 -4.2926) (xy 3.81 -1.6256) (xy 2.1463 -1.6256) (xy 2.1463 -3.6449)
				(xy -2.1463 -3.6449) (xy -2.1463 3.6449) (xy 2.1463 3.6449) (xy 2.1463 -1.6129) (xy 3.81 -1.6129)
				(xy 3.81 4.2926) (xy 2.54 4.2926) (xy 2.54 4.953)
			)
			(stroke
				(width 0)
				(type default)
			)
			(fill no)
			(layer "F.CrtYd")
		)
		(fp_rect
			(start -3.81 4.2926)
			(end -2.54 -4.2926)
			(stroke
				(width 0)
				(type default)
			)
			(fill no)
			(layer "F.Fab")
		)
		(fp_rect
			(start -2.54 4.953)
			(end 2.54 -4.953)
			(stroke
				(width 0)
				(type default)
			)
			(fill no)
			(layer "F.Fab")
		)
		(fp_rect
			(start 2.54 4.2926)
			(end 3.81 -4.2926)
			(stroke
				(width 0)
				(type default)
			)
			(fill no)
			(layer "F.Fab")
		)
		(pad "1" smd rect
			(at 0 -3.1496)
			(size 2.413 2.286)
			(layers "F.Cu" "F.Mask" "F.Paste")
			(net "P3V3_STBY_OUT")
		)
		(pad "2" smd rect
			(at 0 3.1496)
			(size 2.413 2.286)
			(layers "F.Cu" "F.Mask" "F.Paste")
			(net "GND")
		)
		(zone
			(layer "F.Cu")
			(hatch none 0.5)
			(connect_pads
				(clearance 0)
			)
			(min_thickness 0.25)
			(keepout
				(tracks allowed)
				(vias not_allowed)
				(pads allowed)
				(copperpour not_allowed)
				(footprints allowed)
			)
			(placement
				(enabled no)
				(sheetname "")
			)
			(fill
				(thermal_gap 0.5)
				(thermal_bridge_width 0.5)
				(island_removal_mode 0)
			)
			(polygon
				(pts
					(xy 48.76038 -179.423314) (xy 51.78298 -179.423314) (xy 51.78298 -182.318914) (xy 51.78298 -182.649114)
					(xy 48.76038 -182.649114) (xy 48.76038 -182.318914)
				)
			)
		)
		(zone
			(layer "F.Cu")
			(hatch none 0.5)
			(connect_pads
				(clearance 0)
			)
			(min_thickness 0.25)
			(keepout
				(tracks allowed)
				(vias not_allowed)
				(pads allowed)
				(copperpour not_allowed)
				(footprints allowed)
			)
			(placement
				(enabled no)
				(sheetname "")
			)
			(fill
				(thermal_gap 0.5)
				(thermal_bridge_width 0.5)
				(island_removal_mode 0)
			)
			(polygon
				(pts
					(xy 51.78298 -185.709814) (xy 51.78298 -188.618114) (xy 48.76038 -188.618114) (xy 48.76038 -185.722514)
					(xy 48.76038 -185.392314) (xy 51.78298 -185.392314)
				)
			)
		)
	)
	(footprint ""
		(layer "F.Cu")
		(at 88.092026 -132.68325)
		(property "Reference" "R138"
			(at 0 0 0)
			(layer "F.SilkS")
			(hide yes)
			(effects
				(font
					(size 1.27 1.27)
				)
			)
		)
		(property "Value" "8K2R2J-3-GP"
			(at 0.064008 -3.993896 0)
			(unlocked yes)
			(layer "F.Fab")
			(hide yes)
			(effects
				(font
					(size 1.016 1.016)
					(thickness 0.1524)
				)
			)
		)
		(property "Device Type" "R402H16"
			(at 0.064008 -5.517896 0)
			(unlocked yes)
			(layer "F.Fab")
			(hide yes)
			(effects
				(font
					(size 1.016 1.016)
					(thickness 0.1524)
				)
			)
		)
		(duplicate_pad_numbers_are_jumpers no)
		(fp_line
			(start -0.508 -0.9398)
			(end -0.508 0.9398)
			(stroke
				(width 0.1524)
				(type default)
			)
			(layer "F.SilkS")
		)
		(fp_line
			(start 0.508 -0.9398)
			(end -0.508 -0.9398)
			(stroke
				(width 0.1524)
				(type default)
			)
			(layer "F.SilkS")
		)
		(fp_rect
			(start -0.508 0.9398)
			(end 0.508 -0.9398)
			(stroke
				(width 0)
				(type default)
			)
			(fill no)
			(layer "F.CrtYd")
		)
		(fp_rect
			(start -0.508 0.9398)
			(end 0.508 -0.9398)
			(stroke
				(width 0)
				(type default)
			)
			(fill no)
			(layer "F.Fab")
		)
		(pad "1" smd custom
			(at 0 -0.4445)
			(size 0.1397 0.1397)
			(layers "F.Cu" "F.Mask" "F.Paste")
			(net "EEPROM_A2")
			(options
				(clearance outline)
				(anchor circle)
			)
			(primitives
				(gr_poly
					(pts
						(arc
							(start -0.1778 -0.2794)
							(mid -0.249642 -0.249642)
							(end -0.2794 -0.1778)
						)
						(arc
							(start -0.2794 0.1778)
							(mid -0.249642 0.249642)
							(end -0.1778 0.2794)
						)
						(arc
							(start 0.1778 0.2794)
							(mid 0.249642 0.249642)
							(end 0.2794 0.1778)
						)
						(arc
							(start 0.2794 -0.1778)
							(mid 0.249642 -0.249642)
							(end 0.1778 -0.2794)
						)
					)
					(width 0)
					(fill yes)
				)
			)
		)
		(pad "2" smd custom
			(at 0 0.4445)
			(size 0.1397 0.1397)
			(layers "F.Cu" "F.Mask" "F.Paste")
			(net "GND")
			(options
				(clearance outline)
				(anchor circle)
			)
			(primitives
				(gr_poly
					(pts
						(arc
							(start -0.1778 -0.2794)
							(mid -0.249642 -0.249642)
							(end -0.2794 -0.1778)
						)
						(arc
							(start -0.2794 0.1778)
							(mid -0.249642 0.249642)
							(end -0.1778 0.2794)
						)
						(arc
							(start 0.1778 0.2794)
							(mid 0.249642 0.249642)
							(end 0.2794 0.1778)
						)
						(arc
							(start 0.2794 -0.1778)
							(mid 0.249642 -0.249642)
							(end 0.1778 -0.2794)
						)
					)
					(width 0)
					(fill yes)
				)
			)
		)
	)
	(footprint ""
		(layer "F.Cu")
		(at 151.004016 -14.977618 180)
		(property "Reference" "R516"
			(at 0 0 180)
			(layer "F.SilkS")
			(hide yes)
			(effects
				(font
					(size 1.27 1.27)
				)
			)
		)
		(property "Value" "0R2J-2-GP"
			(at 0.064008 -3.993896 180)
			(unlocked yes)
			(layer "F.Fab")
			(hide yes)
			(effects
				(font
					(size 1.016 1.016)
					(thickness 0.1524)
				)
			)
		)
		(property "Device Type" "R402H16"
			(at 0.064008 -5.517896 180)
			(unlocked yes)
			(layer "F.Fab")
			(hide yes)
			(effects
				(font
					(size 1.016 1.016)
					(thickness 0.1524)
				)
			)
		)
		(duplicate_pad_numbers_are_jumpers no)
		(fp_line
			(start 0.508 -0.9398)
			(end -0.508 -0.9398)
			(stroke
				(width 0.1524)
				(type default)
			)
			(layer "F.SilkS")
		)
		(fp_line
			(start -0.508 -0.9398)
			(end -0.508 0.9398)
			(stroke
				(width 0.1524)
				(type default)
			)
			(layer "F.SilkS")
		)
		(fp_rect
			(start -0.508 0.9398)
			(end 0.508 -0.9398)
			(stroke
				(width 0)
				(type default)
			)
			(fill no)
			(layer "F.CrtYd")
		)
		(fp_rect
			(start -0.508 0.9398)
			(end 0.508 -0.9398)
			(stroke
				(width 0)
				(type default)
			)
			(fill no)
			(layer "F.Fab")
		)
		(pad "1" smd custom
			(at 0 -0.4445 180)
			(size 0.1397 0.1397)
			(layers "F.Cu" "F.Mask" "F.Paste")
			(net "P1V8_STBY_VO")
			(options
				(clearance outline)
				(anchor circle)
			)
			(primitives
				(gr_poly
					(pts
						(arc
							(start -0.1778 -0.2794)
							(mid -0.249642 -0.249642)
							(end -0.2794 -0.1778)
						)
						(arc
							(start -0.2794 0.1778)
							(mid -0.249642 0.249642)
							(end -0.1778 0.2794)
						)
						(arc
							(start 0.1778 0.2794)
							(mid 0.249642 0.249642)
							(end 0.2794 0.1778)
						)
						(arc
							(start 0.2794 -0.1778)
							(mid 0.249642 -0.249642)
							(end 0.1778 -0.2794)
						)
					)
					(width 0)
					(fill yes)
				)
			)
		)
		(pad "2" smd custom
			(at 0 0.4445 180)
			(size 0.1397 0.1397)
			(layers "F.Cu" "F.Mask" "F.Paste")
			(net "P1V8_STBY_CC_R")
			(options
				(clearance outline)
				(anchor circle)
			)
			(primitives
				(gr_poly
					(pts
						(arc
							(start -0.1778 -0.2794)
							(mid -0.249642 -0.249642)
							(end -0.2794 -0.1778)
						)
						(arc
							(start -0.2794 0.1778)
							(mid -0.249642 0.249642)
							(end -0.1778 0.2794)
						)
						(arc
							(start 0.1778 0.2794)
							(mid 0.249642 0.249642)
							(end 0.2794 0.1778)
						)
						(arc
							(start 0.2794 -0.1778)
							(mid 0.249642 -0.249642)
							(end 0.1778 -0.2794)
						)
					)
					(width 0)
					(fill yes)
				)
			)
		)
	)
	(footprint ""
		(layer "F.Cu")
		(at 95.9358 -180.4416 90)
		(property "Reference" "C136"
			(at 0 0 90)
			(layer "F.SilkS")
			(hide yes)
			(effects
				(font
					(size 1.27 1.27)
				)
			)
		)
		(property "Value" "SCD1U16V2KX-3GP"
			(at 1.1811 -2.7051 90)
			(unlocked yes)
			(layer "F.Fab")
			(hide yes)
			(effects
				(font
					(size 1.016 1.016)
					(thickness 0.1524)
				)
			)
		)
		(property "Device Type" "C402H22"
			(at 1.1811 -4.2291 90)
			(unlocked yes)
			(layer "F.Fab")
			(hide yes)
			(effects
				(font
					(size 1.016 1.016)
					(thickness 0.1524)
				)
			)
		)
		(duplicate_pad_numbers_are_jumpers no)
		(fp_rect
			(start -0.4318 0.9525)
			(end 0.4318 -0.9525)
			(stroke
				(width 0)
				(type default)
			)
			(fill no)
			(layer "F.CrtYd")
		)
		(fp_rect
			(start -0.4318 0.9525)
			(end 0.4318 -0.9525)
			(stroke
				(width 0)
				(type default)
			)
			(fill no)
			(layer "F.Fab")
		)
		(pad "1" smd custom
			(at 0 -0.4445 90)
			(size 0.1524 0.1524)
			(layers "F.Cu" "F.Mask" "F.Paste")
			(net "P3V3_STBY")
			(options
				(clearance outline)
				(anchor circle)
			)
			(primitives
				(gr_poly
					(pts
						(arc
							(start 0.3048 -0.2032)
							(mid 0.275042 -0.275042)
							(end 0.2032 -0.3048)
						)
						(arc
							(start -0.2032 -0.3048)
							(mid -0.275042 -0.275042)
							(end -0.3048 -0.2032)
						)
						(arc
							(start -0.3048 0.2032)
							(mid -0.275042 0.275042)
							(end -0.2032 0.3048)
						)
						(arc
							(start 0.2032 0.3048)
							(mid 0.275042 0.275042)
							(end 0.3048 0.2032)
						)
					)
					(width 0)
					(fill yes)
				)
			)
		)
		(pad "2" smd custom
			(at 0 0.4445 90)
			(size 0.1524 0.1524)
			(layers "F.Cu" "F.Mask" "F.Paste")
			(net "GND")
			(options
				(clearance outline)
				(anchor circle)
			)
			(primitives
				(gr_poly
					(pts
						(arc
							(start 0.3048 -0.2032)
							(mid 0.275042 -0.275042)
							(end 0.2032 -0.3048)
						)
						(arc
							(start -0.2032 -0.3048)
							(mid -0.275042 -0.275042)
							(end -0.3048 -0.2032)
						)
						(arc
							(start -0.3048 0.2032)
							(mid -0.275042 0.275042)
							(end -0.2032 0.3048)
						)
						(arc
							(start 0.2032 0.3048)
							(mid 0.275042 0.275042)
							(end 0.3048 0.2032)
						)
					)
					(width 0)
					(fill yes)
				)
			)
		)
	)
	(footprint ""
		(layer "F.Cu")
		(at 86.880192 -57.916318 -90)
		(property "Reference" "R3"
			(at 0 0 270)
			(layer "F.SilkS")
			(hide yes)
			(effects
				(font
					(size 1.27 1.27)
				)
			)
		)
		(property "Value" "4K7R2F-GP"
			(at 0.064008 -3.993896 270)
			(unlocked yes)
			(layer "F.Fab")
			(hide yes)
			(effects
				(font
					(size 1.016 1.016)
					(thickness 0.1524)
				)
			)
		)
		(property "Device Type" "R402H16"
			(at 0.064008 -5.517896 270)
			(unlocked yes)
			(layer "F.Fab")
			(hide yes)
			(effects
				(font
					(size 1.016 1.016)
					(thickness 0.1524)
				)
			)
		)
		(duplicate_pad_numbers_are_jumpers no)
		(fp_line
			(start -0.508 -0.9398)
			(end -0.508 0.9398)
			(stroke
				(width 0.1524)
				(type default)
			)
			(layer "F.SilkS")
		)
		(fp_line
			(start 0.508 -0.9398)
			(end -0.508 -0.9398)
			(stroke
				(width 0.1524)
				(type default)
			)
			(layer "F.SilkS")
		)
		(fp_rect
			(start -0.508 0.9398)
			(end 0.508 -0.9398)
			(stroke
				(width 0)
				(type default)
			)
			(fill no)
			(layer "F.CrtYd")
		)
		(fp_rect
			(start -0.508 0.9398)
			(end 0.508 -0.9398)
			(stroke
				(width 0)
				(type default)
			)
			(fill no)
			(layer "F.Fab")
		)
		(pad "1" smd custom
			(at 0 -0.4445 270)
			(size 0.1397 0.1397)
			(layers "F.Cu" "F.Mask" "F.Paste")
			(net "I2C_MEZZ_ALERT_N")
			(options
				(clearance outline)
				(anchor circle)
			)
			(primitives
				(gr_poly
					(pts
						(arc
							(start -0.1778 -0.2794)
							(mid -0.249642 -0.249642)
							(end -0.2794 -0.1778)
						)
						(arc
							(start -0.2794 0.1778)
							(mid -0.249642 0.249642)
							(end -0.1778 0.2794)
						)
						(arc
							(start 0.1778 0.2794)
							(mid 0.249642 0.249642)
							(end 0.2794 0.1778)
						)
						(arc
							(start 0.2794 -0.1778)
							(mid 0.249642 -0.249642)
							(end 0.1778 -0.2794)
						)
					)
					(width 0)
					(fill yes)
				)
			)
		)
		(pad "2" smd custom
			(at 0 0.4445 270)
			(size 0.1397 0.1397)
			(layers "F.Cu" "F.Mask" "F.Paste")
			(net "P3V3_STBY")
			(options
				(clearance outline)
				(anchor circle)
			)
			(primitives
				(gr_poly
					(pts
						(arc
							(start -0.1778 -0.2794)
							(mid -0.249642 -0.249642)
							(end -0.2794 -0.1778)
						)
						(arc
							(start -0.2794 0.1778)
							(mid -0.249642 0.249642)
							(end -0.1778 0.2794)
						)
						(arc
							(start 0.1778 0.2794)
							(mid 0.249642 0.249642)
							(end 0.2794 0.1778)
						)
						(arc
							(start 0.2794 -0.1778)
							(mid 0.249642 -0.249642)
							(end 0.1778 -0.2794)
						)
					)
					(width 0)
					(fill yes)
				)
			)
		)
	)
	(footprint ""
		(layer "F.Cu")
		(at 37.299646 -174.67961 90)
		(property "Reference" "C184"
			(at 0 0 90)
			(layer "F.SilkS")
			(hide yes)
			(effects
				(font
					(size 1.27 1.27)
				)
			)
		)
		(property "Value" "SC68P50V2JN-2-GP"
			(at 1.1811 -2.7051 90)
			(unlocked yes)
			(layer "F.Fab")
			(hide yes)
			(effects
				(font
					(size 1.016 1.016)
					(thickness 0.1524)
				)
			)
		)
		(property "Device Type" "C402H22"
			(at 1.1811 -4.2291 90)
			(unlocked yes)
			(layer "F.Fab")
			(hide yes)
			(effects
				(font
					(size 1.016 1.016)
					(thickness 0.1524)
				)
			)
		)
		(duplicate_pad_numbers_are_jumpers no)
		(fp_rect
			(start -0.4318 0.9525)
			(end 0.4318 -0.9525)
			(stroke
				(width 0)
				(type default)
			)
			(fill no)
			(layer "F.CrtYd")
		)
		(fp_rect
			(start -0.4318 0.9525)
			(end 0.4318 -0.9525)
			(stroke
				(width 0)
				(type default)
			)
			(fill no)
			(layer "F.Fab")
		)
		(pad "1" smd custom
			(at 0 -0.4445 90)
			(size 0.1524 0.1524)
			(layers "F.Cu" "F.Mask" "F.Paste")
			(net "P3V3_STBY_VFB")
			(options
				(clearance outline)
				(anchor circle)
			)
			(primitives
				(gr_poly
					(pts
						(arc
							(start 0.3048 -0.2032)
							(mid 0.275042 -0.275042)
							(end 0.2032 -0.3048)
						)
						(arc
							(start -0.2032 -0.3048)
							(mid -0.275042 -0.275042)
							(end -0.3048 -0.2032)
						)
						(arc
							(start -0.3048 0.2032)
							(mid -0.275042 0.275042)
							(end -0.2032 0.3048)
						)
						(arc
							(start 0.2032 0.3048)
							(mid 0.275042 0.275042)
							(end 0.3048 0.2032)
						)
					)
					(width 0)
					(fill yes)
				)
			)
		)
		(pad "2" smd custom
			(at 0 0.4445 90)
			(size 0.1524 0.1524)
			(layers "F.Cu" "F.Mask" "F.Paste")
			(net "P3V3_STBY_VFB_R")
			(options
				(clearance outline)
				(anchor circle)
			)
			(primitives
				(gr_poly
					(pts
						(arc
							(start 0.3048 -0.2032)
							(mid 0.275042 -0.275042)
							(end 0.2032 -0.3048)
						)
						(arc
							(start -0.2032 -0.3048)
							(mid -0.275042 -0.275042)
							(end -0.3048 -0.2032)
						)
						(arc
							(start -0.3048 0.2032)
							(mid -0.275042 0.275042)
							(end -0.2032 0.3048)
						)
						(arc
							(start 0.2032 0.3048)
							(mid 0.275042 0.275042)
							(end 0.3048 0.2032)
						)
					)
					(width 0)
					(fill yes)
				)
			)
		)
	)
	(footprint ""
		(layer "F.Cu")
		(at 88.31072 -162.042856 180)
		(property "Reference" "R28"
			(at 0 0 180)
			(layer "F.SilkS")
			(hide yes)
			(effects
				(font
					(size 1.27 1.27)
				)
			)
		)
		(property "Value" "12KR2J-L-GP"
			(at 0.064008 -3.993896 180)
			(unlocked yes)
			(layer "F.Fab")
			(hide yes)
			(effects
				(font
					(size 1.016 1.016)
					(thickness 0.1524)
				)
			)
		)
		(property "Device Type" "R402H16"
			(at 0.064008 -5.517896 180)
			(unlocked yes)
			(layer "F.Fab")
			(hide yes)
			(effects
				(font
					(size 1.016 1.016)
					(thickness 0.1524)
				)
			)
		)
		(duplicate_pad_numbers_are_jumpers no)
		(fp_line
			(start 0.508 -0.9398)
			(end -0.508 -0.9398)
			(stroke
				(width 0.1524)
				(type default)
			)
			(layer "F.SilkS")
		)
		(fp_line
			(start -0.508 -0.9398)
			(end -0.508 0.9398)
			(stroke
				(width 0.1524)
				(type default)
			)
			(layer "F.SilkS")
		)
		(fp_rect
			(start -0.508 0.9398)
			(end 0.508 -0.9398)
			(stroke
				(width 0)
				(type default)
			)
			(fill no)
			(layer "F.CrtYd")
		)
		(fp_rect
			(start -0.508 0.9398)
			(end 0.508 -0.9398)
			(stroke
				(width 0)
				(type default)
			)
			(fill no)
			(layer "F.Fab")
		)
		(pad "1" smd custom
			(at 0 -0.4445 180)
			(size 0.1397 0.1397)
			(layers "F.Cu" "F.Mask" "F.Paste")
			(net "RBIAS")
			(options
				(clearance outline)
				(anchor circle)
			)
			(primitives
				(gr_poly
					(pts
						(arc
							(start -0.1778 -0.2794)
							(mid -0.249642 -0.249642)
							(end -0.2794 -0.1778)
						)
						(arc
							(start -0.2794 0.1778)
							(mid -0.249642 0.249642)
							(end -0.1778 0.2794)
						)
						(arc
							(start 0.1778 0.2794)
							(mid 0.249642 0.249642)
							(end 0.2794 0.1778)
						)
						(arc
							(start 0.2794 -0.1778)
							(mid 0.249642 -0.249642)
							(end 0.1778 -0.2794)
						)
					)
					(width 0)
					(fill yes)
				)
			)
		)
		(pad "2" smd custom
			(at 0 0.4445 180)
			(size 0.1397 0.1397)
			(layers "F.Cu" "F.Mask" "F.Paste")
			(net "GND")
			(options
				(clearance outline)
				(anchor circle)
			)
			(primitives
				(gr_poly
					(pts
						(arc
							(start -0.1778 -0.2794)
							(mid -0.249642 -0.249642)
							(end -0.2794 -0.1778)
						)
						(arc
							(start -0.2794 0.1778)
							(mid -0.249642 0.249642)
							(end -0.1778 0.2794)
						)
						(arc
							(start 0.1778 0.2794)
							(mid 0.249642 0.249642)
							(end 0.2794 0.1778)
						)
						(arc
							(start 0.2794 -0.1778)
							(mid 0.249642 -0.249642)
							(end 0.1778 -0.2794)
						)
					)
					(width 0)
					(fill yes)
				)
			)
		)
	)
	(footprint ""
		(layer "F.Cu")
		(at 84.986622 -78.951836 90)
		(property "Reference" "VIA11"
			(at 0 0 90)
			(layer "F.SilkS")
			(hide yes)
			(effects
				(font
					(size 1.27 1.27)
				)
			)
		)
		(property "Value" "85OHM-8L-1D6MM-L16L18-GP"
			(at 4.064 0.6096 90)
			(unlocked yes)
			(layer "F.Fab")
			(hide yes)
			(effects
				(font
					(size 1.016 1.016)
					(thickness 0.1524)
				)
			)
		)
		(property "Device Type" "VIA-PCIE-4P-368076"
			(at 4.064 -0.9144 90)
			(unlocked yes)
			(layer "F.Fab")
			(hide yes)
			(effects
				(font
					(size 1.016 1.016)
					(thickness 0.1524)
				)
			)
		)
		(duplicate_pad_numbers_are_jumpers no)
		(fp_rect
			(start -1.8415 0.381)
			(end 1.8415 -0.381)
			(stroke
				(width 0)
				(type default)
			)
			(fill no)
			(layer "F.CrtYd")
		)
		(fp_rect
			(start -1.8415 0.381)
			(end 1.8415 -0.381)
			(stroke
				(width 0)
				(type default)
			)
			(fill no)
			(layer "F.Fab")
		)
		(pad "1" thru_hole circle
			(at -1.4605 0 90)
			(size 0.508 0.508)
			(drill 0.254)
			(layers "*.Cu" "*.Mask")
			(remove_unused_layers no)
			(net "GND")
			(clearance 0.127)
			(thermal_gap 0.127)
		)
		(pad "2" thru_hole circle
			(at -0.4445 0 90)
			(size 0.508 0.508)
			(drill 0.254)
			(layers "*.Cu" "*.Mask")
			(remove_unused_layers no)
			(net "PCIE_IOM_TO_COMP_18_DP")
			(clearance 0.127)
			(thermal_gap 0.127)
		)
		(pad "3" thru_hole circle
			(at 0.4445 0 90)
			(size 0.508 0.508)
			(drill 0.254)
			(layers "*.Cu" "*.Mask")
			(remove_unused_layers no)
			(net "PCIE_IOM_TO_COMP_18_DN")
			(clearance 0.127)
			(thermal_gap 0.127)
		)
		(pad "4" thru_hole circle
			(at 1.4605 0 90)
			(size 0.508 0.508)
			(drill 0.254)
			(layers "*.Cu" "*.Mask")
			(remove_unused_layers no)
			(net "GND")
			(clearance 0.127)
			(thermal_gap 0.127)
		)
	)
	(footprint ""
		(layer "F.Cu")
		(at 179.399946 -129.599944)
		(property "Reference" "M2"
			(at 0 0 0)
			(layer "F.SilkS")
			(hide yes)
			(effects
				(font
					(size 1.27 1.27)
				)
			)
		)
		(property "Value" "SKT-MINI75P-11-GP"
			(at 12.6619 2.2733 0)
			(unlocked yes)
			(layer "F.Fab")
			(hide yes)
			(effects
				(font
					(size 1.016 1.016)
					(thickness 0.1524)
				)
			)
		)
		(property "Device Type" "MDT580M01001"
			(at 12.6619 0.7493 0)
			(unlocked yes)
			(layer "F.Fab")
			(hide yes)
			(effects
				(font
					(size 1.016 1.016)
					(thickness 0.1524)
				)
			)
		)
		(duplicate_pad_numbers_are_jumpers no)
		(fp_line
			(start -11.2522 -6.2992)
			(end 11.2522 -6.2992)
			(stroke
				(width 0.1524)
				(type default)
			)
			(layer "F.SilkS")
		)
		(fp_line
			(start -11.2522 3.302)
			(end -11.2522 -6.2992)
			(stroke
				(width 0.1524)
				(type default)
			)
			(layer "F.SilkS")
		)
		(fp_line
			(start -9.525 -6.3881)
			(end -9.017 -6.3881)
			(stroke
				(width 0.3302)
				(type default)
			)
			(layer "F.SilkS")
		)
		(fp_line
			(start 11.2522 -6.2992)
			(end 11.2522 3.302)
			(stroke
				(width 0.1524)
				(type default)
			)
			(layer "F.SilkS")
		)
		(fp_line
			(start 11.2522 3.302)
			(end -11.2522 3.302)
			(stroke
				(width 0.1524)
				(type default)
			)
			(layer "F.SilkS")
		)
		(fp_poly
			(pts
				(xy -9.273794 -6.315202) (xy -8.841994 -6.747002) (xy -9.705594 -6.747002)
			)
			(stroke
				(width 0)
				(type default)
			)
			(fill yes)
			(layer "F.SilkS")
		)
		(fp_rect
			(start -10.9982 2.8448)
			(end 10.9982 -5.6896)
			(stroke
				(width 0)
				(type default)
			)
			(fill no)
			(layer "F.CrtYd")
		)
		(fp_poly
			(pts
				(xy -11.5062 3.556) (xy -11.5062 -6.5532) (xy 11.5062 -6.5532) (xy 11.5062 -0.00635) (xy 10.9982 -0.00635)
				(xy 10.9982 -5.6896) (xy -10.9982 -5.6896) (xy -10.9982 2.8448) (xy 10.9982 2.8448) (xy 10.9982 0.00635)
				(xy 11.5062 0.00635) (xy 11.5062 3.556)
			)
			(stroke
				(width 0)
				(type default)
			)
			(fill no)
			(layer "F.CrtYd")
		)
		(fp_rect
			(start -11.5062 3.556)
			(end 11.5062 -6.5532)
			(stroke
				(width 0)
				(type default)
			)
			(fill no)
			(layer "F.Fab")
		)
		(pad "" np_thru_hole circle
			(at -9.99998 0)
			(size 0.254 0.254)
			(drill 1.1176)
			(layers "*.Cu" "*.Mask")
			(clearance 0.7874)
			(thermal_gap 0.7874)
		)
		(pad "" np_thru_hole circle
			(at 9.99998 0)
			(size 0.254 0.254)
			(drill 1.6002)
			(layers "*.Cu" "*.Mask")
			(clearance 1.0287)
			(thermal_gap 1.0287)
		)
		(pad "1" smd rect
			(at -9.249918 -5.275072)
			(size 0.3048 1.5494)
			(layers "F.Cu" "F.Mask" "F.Paste")
			(net "M2_2_PRESENT_N_R")
		)
		(pad "2" smd rect
			(at -8.999982 2.275078)
			(size 0.3048 1.5494)
			(layers "F.Cu" "F.Mask" "F.Paste")
			(net "P3V3_M2")
		)
		(pad "3" smd rect
			(at -8.750046 -5.275072)
			(size 0.3048 1.5494)
			(layers "F.Cu" "F.Mask" "F.Paste")
			(net "GND")
		)
		(pad "4" smd rect
			(at -8.50011 2.275078)
			(size 0.3048 1.5494)
			(layers "F.Cu" "F.Mask" "F.Paste")
			(net "P3V3_M2")
		)
		(pad "5" smd rect
			(at -8.24992 -5.275072)
			(size 0.3048 1.5494)
			(layers "F.Cu" "F.Mask" "F.Paste")
			(net "PCIE_IOM_TO_COMP_15_DN")
		)
		(pad "6" smd rect
			(at -7.999984 2.275078)
			(size 0.3048 1.5494)
			(layers "F.Cu" "F.Mask" "F.Paste")
			(net "Net_603")
		)
		(pad "7" smd rect
			(at -7.750048 -5.275072)
			(size 0.3048 1.5494)
			(layers "F.Cu" "F.Mask" "F.Paste")
			(net "PCIE_IOM_TO_COMP_15_DP")
		)
		(pad "8" smd rect
			(at -7.500112 2.275078)
			(size 0.3048 1.5494)
			(layers "F.Cu" "F.Mask" "F.Paste")
			(net "Net_604")
		)
		(pad "9" smd rect
			(at -7.249922 -5.275072)
			(size 0.3048 1.5494)
			(layers "F.Cu" "F.Mask" "F.Paste")
			(net "GND")
		)
		(pad "10" smd rect
			(at -6.999986 2.275078)
			(size 0.3048 1.5494)
			(layers "F.Cu" "F.Mask" "F.Paste")
			(net "M2_2_ACTIVE_N")
		)
		(pad "11" smd rect
			(at -6.75005 -5.275072)
			(size 0.3048 1.5494)
			(layers "F.Cu" "F.Mask" "F.Paste")
			(net "PCIE_COMP_TO_IOM_15_DN")
		)
		(pad "12" smd rect
			(at -6.500114 2.275078)
			(size 0.3048 1.5494)
			(layers "F.Cu" "F.Mask" "F.Paste")
			(net "P3V3_M2")
		)
		(pad "13" smd rect
			(at -6.249924 -5.275072)
			(size 0.3048 1.5494)
			(layers "F.Cu" "F.Mask" "F.Paste")
			(net "PCIE_COMP_TO_IOM_15_DP")
		)
		(pad "14" smd rect
			(at -5.999988 2.275078)
			(size 0.3048 1.5494)
			(layers "F.Cu" "F.Mask" "F.Paste")
			(net "P3V3_M2")
		)
		(pad "15" smd rect
			(at -5.750052 -5.275072)
			(size 0.3048 1.5494)
			(layers "F.Cu" "F.Mask" "F.Paste")
			(net "GND")
		)
		(pad "16" smd rect
			(at -5.500116 2.275078)
			(size 0.3048 1.5494)
			(layers "F.Cu" "F.Mask" "F.Paste")
			(net "P3V3_M2")
		)
		(pad "17" smd rect
			(at -5.249926 -5.275072)
			(size 0.3048 1.5494)
			(layers "F.Cu" "F.Mask" "F.Paste")
			(net "PCIE_IOM_TO_COMP_14_DN")
		)
		(pad "18" smd rect
			(at -4.99999 2.275078)
			(size 0.3048 1.5494)
			(layers "F.Cu" "F.Mask" "F.Paste")
			(net "P3V3_M2")
		)
		(pad "19" smd rect
			(at -4.750054 -5.275072)
			(size 0.3048 1.5494)
			(layers "F.Cu" "F.Mask" "F.Paste")
			(net "PCIE_IOM_TO_COMP_14_DP")
		)
		(pad "20" smd rect
			(at -4.500118 2.275078)
			(size 0.3048 1.5494)
			(layers "F.Cu" "F.Mask" "F.Paste")
			(net "Net_605")
		)
		(pad "21" smd rect
			(at -4.249928 -5.275072)
			(size 0.3048 1.5494)
			(layers "F.Cu" "F.Mask" "F.Paste")
			(net "GND")
		)
		(pad "22" smd rect
			(at -3.999992 2.275078)
			(size 0.3048 1.5494)
			(layers "F.Cu" "F.Mask" "F.Paste")
			(net "Net_606")
		)
		(pad "23" smd rect
			(at -3.750056 -5.275072)
			(size 0.3048 1.5494)
			(layers "F.Cu" "F.Mask" "F.Paste")
			(net "PCIE_COMP_TO_IOM_14_DN")
		)
		(pad "24" smd rect
			(at -3.50012 2.275078)
			(size 0.3048 1.5494)
			(layers "F.Cu" "F.Mask" "F.Paste")
			(net "Net_593")
		)
		(pad "25" smd rect
			(at -3.24993 -5.275072)
			(size 0.3048 1.5494)
			(layers "F.Cu" "F.Mask" "F.Paste")
			(net "PCIE_COMP_TO_IOM_14_DP")
		)
		(pad "26" smd rect
			(at -2.999994 2.275078)
			(size 0.3048 1.5494)
			(layers "F.Cu" "F.Mask" "F.Paste")
			(net "Net_594")
		)
		(pad "27" smd rect
			(at -2.750058 -5.275072)
			(size 0.3048 1.5494)
			(layers "F.Cu" "F.Mask" "F.Paste")
			(net "GND")
		)
		(pad "28" smd rect
			(at -2.500122 2.275078)
			(size 0.3048 1.5494)
			(layers "F.Cu" "F.Mask" "F.Paste")
			(net "Net_595")
		)
		(pad "29" smd rect
			(at -2.249932 -5.275072)
			(size 0.3048 1.5494)
			(layers "F.Cu" "F.Mask" "F.Paste")
			(net "PCIE_IOM_TO_COMP_13_DN")
		)
		(pad "30" smd rect
			(at -1.999996 2.275078)
			(size 0.3048 1.5494)
			(layers "F.Cu" "F.Mask" "F.Paste")
			(net "Net_596")
		)
		(pad "31" smd rect
			(at -1.75006 -5.275072)
			(size 0.3048 1.5494)
			(layers "F.Cu" "F.Mask" "F.Paste")
			(net "PCIE_IOM_TO_COMP_13_DP")
		)
		(pad "32" smd rect
			(at -1.500124 2.275078)
			(size 0.3048 1.5494)
			(layers "F.Cu" "F.Mask" "F.Paste")
			(net "Net_597")
		)
		(pad "33" smd rect
			(at -1.249934 -5.275072)
			(size 0.3048 1.5494)
			(layers "F.Cu" "F.Mask" "F.Paste")
			(net "GND")
		)
		(pad "34" smd rect
			(at -0.999998 2.275078)
			(size 0.3048 1.5494)
			(layers "F.Cu" "F.Mask" "F.Paste")
			(net "Net_598")
		)
		(pad "35" smd rect
			(at -0.750062 -5.275072)
			(size 0.3048 1.5494)
			(layers "F.Cu" "F.Mask" "F.Paste")
			(net "PCIE_COMP_TO_IOM_13_DN")
		)
		(pad "36" smd rect
			(at -0.500126 2.275078)
			(size 0.3048 1.5494)
			(layers "F.Cu" "F.Mask" "F.Paste")
			(net "Net_599")
		)
		(pad "37" smd rect
			(at -0.249936 -5.275072)
			(size 0.3048 1.5494)
			(layers "F.Cu" "F.Mask" "F.Paste")
			(net "PCIE_COMP_TO_IOM_13_DP")
		)
		(pad "38" smd rect
			(at 0 2.275078)
			(size 0.3048 1.5494)
			(layers "F.Cu" "F.Mask" "F.Paste")
			(net "Net_600")
		)
		(pad "39" smd rect
			(at 0.249936 -5.275072)
			(size 0.3048 1.5494)
			(layers "F.Cu" "F.Mask" "F.Paste")
			(net "GND")
		)
		(pad "40" smd rect
			(at 0.500126 2.275078)
			(size 0.3048 1.5494)
			(layers "F.Cu" "F.Mask" "F.Paste")
			(net "I2C_M2_2_1V8_SCL")
		)
		(pad "41" smd rect
			(at 0.750062 -5.275072)
			(size 0.3048 1.5494)
			(layers "F.Cu" "F.Mask" "F.Paste")
			(net "PCIE_IOM_TO_COMP_12_DN")
		)
		(pad "42" smd rect
			(at 0.999998 2.275078)
			(size 0.3048 1.5494)
			(layers "F.Cu" "F.Mask" "F.Paste")
			(net "I2C_M2_2_1V8_SDA")
		)
		(pad "43" smd rect
			(at 1.249934 -5.275072)
			(size 0.3048 1.5494)
			(layers "F.Cu" "F.Mask" "F.Paste")
			(net "PCIE_IOM_TO_COMP_12_DP")
		)
		(pad "44" smd rect
			(at 1.500124 2.275078)
			(size 0.3048 1.5494)
			(layers "F.Cu" "F.Mask" "F.Paste")
			(net "M2_2_ALERT#")
		)
		(pad "45" smd rect
			(at 1.75006 -5.275072)
			(size 0.3048 1.5494)
			(layers "F.Cu" "F.Mask" "F.Paste")
			(net "GND")
		)
		(pad "46" smd rect
			(at 1.999996 2.275078)
			(size 0.3048 1.5494)
			(layers "F.Cu" "F.Mask" "F.Paste")
			(net "Net_601")
		)
		(pad "47" smd rect
			(at 2.249932 -5.275072)
			(size 0.3048 1.5494)
			(layers "F.Cu" "F.Mask" "F.Paste")
			(net "PCIE_COMP_TO_IOM_12_DN")
		)
		(pad "48" smd rect
			(at 2.500122 2.275078)
			(size 0.3048 1.5494)
			(layers "F.Cu" "F.Mask" "F.Paste")
			(net "Net_602")
		)
		(pad "49" smd rect
			(at 2.750058 -5.275072)
			(size 0.3048 1.5494)
			(layers "F.Cu" "F.Mask" "F.Paste")
			(net "PCIE_COMP_TO_IOM_12_DP")
		)
		(pad "50" smd rect
			(at 2.999994 2.275078)
			(size 0.3048 1.5494)
			(layers "F.Cu" "F.Mask" "F.Paste")
			(net "PCIE_COMP_TO_IOM_RST_3")
		)
		(pad "51" smd rect
			(at 3.24993 -5.275072)
			(size 0.3048 1.5494)
			(layers "F.Cu" "F.Mask" "F.Paste")
			(net "GND")
		)
		(pad "52" smd rect
			(at 3.50012 2.275078)
			(size 0.3048 1.5494)
			(layers "F.Cu" "F.Mask" "F.Paste")
			(net "M2_2_CLKREQ#")
		)
		(pad "53" smd rect
			(at 3.750056 -5.275072)
			(size 0.3048 1.5494)
			(layers "F.Cu" "F.Mask" "F.Paste")
			(net "PCIE_COMP_TO_IOM_CLK_3_DN")
		)
		(pad "54" smd rect
			(at 3.999992 2.275078)
			(size 0.3048 1.5494)
			(layers "F.Cu" "F.Mask" "F.Paste")
			(net "Net_590")
		)
		(pad "55" smd rect
			(at 4.249928 -5.275072)
			(size 0.3048 1.5494)
			(layers "F.Cu" "F.Mask" "F.Paste")
			(net "PCIE_COMP_TO_IOM_CLK_3_DP")
		)
		(pad "56" smd rect
			(at 4.500118 2.275078)
			(size 0.3048 1.5494)
			(layers "F.Cu" "F.Mask" "F.Paste")
			(net "TP_M2_2_MFG_DAT")
		)
		(pad "57" smd rect
			(at 4.750054 -5.275072)
			(size 0.3048 1.5494)
			(layers "F.Cu" "F.Mask" "F.Paste")
			(net "GND")
		)
		(pad "58" smd rect
			(at 4.99999 2.275078)
			(size 0.3048 1.5494)
			(layers "F.Cu" "F.Mask" "F.Paste")
			(net "TP_M2_2_MFG_CLK")
		)
		(pad "67" smd rect
			(at 7.249922 -5.275072)
			(size 0.3048 1.5494)
			(layers "F.Cu" "F.Mask" "F.Paste")
			(net "Net_588")
		)
		(pad "68" smd rect
			(at 7.500112 2.275078)
			(size 0.3048 1.5494)
			(layers "F.Cu" "F.Mask" "F.Paste")
			(net "Net_591")
		)
		(pad "69" smd rect
			(at 7.750048 -5.275072)
			(size 0.3048 1.5494)
			(layers "F.Cu" "F.Mask" "F.Paste")
			(net "Net_589")
		)
		(pad "70" smd rect
			(at 7.999984 2.275078)
			(size 0.3048 1.5494)
			(layers "F.Cu" "F.Mask" "F.Paste")
			(net "P3V3_M2")
		)
		(pad "71" smd rect
			(at 8.24992 -5.275072)
			(size 0.3048 1.5494)
			(layers "F.Cu" "F.Mask" "F.Paste")
			(net "GND")
		)
		(pad "72" smd rect
			(at 8.50011 2.275078)
			(size 0.3048 1.5494)
			(layers "F.Cu" "F.Mask" "F.Paste")
			(net "P3V3_M2")
		)
		(pad "73" smd rect
			(at 8.750046 -5.275072)
			(size 0.3048 1.5494)
			(layers "F.Cu" "F.Mask" "F.Paste")
			(net "GND")
		)
		(pad "74" smd rect
			(at 8.999982 2.275078)
			(size 0.3048 1.5494)
			(layers "F.Cu" "F.Mask" "F.Paste")
			(net "P3V3_M2")
		)
		(pad "75" smd rect
			(at 9.249918 -5.275072)
			(size 0.3048 1.5494)
			(layers "F.Cu" "F.Mask" "F.Paste")
			(net "GND")
		)
		(pad "76" smd rect
			(at -10.349992 -4.500118)
			(size 1.1938 2.7432)
			(layers "F.Cu" "F.Mask" "F.Paste")
			(net "GND")
		)
		(pad "77" smd rect
			(at 10.349992 -4.500118)
			(size 1.1938 2.7432)
			(layers "F.Cu" "F.Mask" "F.Paste")
			(net "GND")
		)
		(zone
			(layer "F.Cu")
			(hatch none 0.5)
			(connect_pads
				(clearance 0)
			)
			(min_thickness 0.25)
			(keepout
				(tracks allowed)
				(vias not_allowed)
				(pads allowed)
				(copperpour not_allowed)
				(footprints allowed)
			)
			(placement
				(enabled no)
				(sheetname "")
			)
			(fill
				(thermal_gap 0.5)
				(thermal_bridge_width 0.5)
				(island_removal_mode 0)
			)
			(polygon
				(pts
					(xy 169.997628 -133.592316) (xy 184.3024 -133.592316) (xy 184.3024 -134.100316) (xy 169.997628 -134.100316)
				)
			)
		)
		(zone
			(layer "F.Cu")
			(hatch none 0.5)
			(connect_pads
				(clearance 0)
			)
			(min_thickness 0.25)
			(keepout
				(tracks allowed)
				(vias not_allowed)
				(pads allowed)
				(copperpour not_allowed)
				(footprints allowed)
			)
			(placement
				(enabled no)
				(sheetname "")
			)
			(fill
				(thermal_gap 0.5)
				(thermal_bridge_width 0.5)
				(island_removal_mode 0)
			)
			(polygon
				(pts
					(xy 170.247564 -128.099566) (xy 184.552336 -128.099566) (xy 184.552336 -128.607566) (xy 170.247564 -128.607566)
				)
			)
		)
		(zone
			(layer "F.Cu")
			(hatch none 0.5)
			(connect_pads
				(clearance 0)
			)
			(min_thickness 0.25)
			(keepout
				(tracks allowed)
				(vias not_allowed)
				(pads allowed)
				(copperpour not_allowed)
				(footprints allowed)
			)
			(placement
				(enabled no)
				(sheetname "")
			)
			(fill
				(thermal_gap 0.5)
				(thermal_bridge_width 0.5)
				(island_removal_mode 0)
			)
			(polygon
				(pts
					(xy 186.497468 -133.592316) (xy 188.802264 -133.592316) (xy 188.802264 -134.100316) (xy 186.497468 -134.100316)
				)
			)
		)
		(zone
			(layer "F.Cu")
			(hatch none 0.5)
			(connect_pads
				(clearance 0)
			)
			(min_thickness 0.25)
			(keepout
				(tracks allowed)
				(vias not_allowed)
				(pads allowed)
				(copperpour not_allowed)
				(footprints allowed)
			)
			(placement
				(enabled no)
				(sheetname "")
			)
			(fill
				(thermal_gap 0.5)
				(thermal_bridge_width 0.5)
				(island_removal_mode 0)
			)
			(polygon
				(pts
					(xy 186.747658 -128.099566) (xy 188.552328 -128.099566) (xy 188.552328 -128.607566) (xy 186.747658 -128.607566)
				)
			)
		)
		(zone
			(layers "F.Cu" "B.Cu" "In1.Cu" "In2.Cu" "In3.Cu" "In4.Cu" "In5.Cu" "In6.Cu")
			(hatch none 0.5)
			(connect_pads
				(clearance 0)
			)
			(min_thickness 0.25)
			(keepout
				(tracks not_allowed)
				(vias allowed)
				(pads allowed)
				(copperpour not_allowed)
				(footprints allowed)
			)
			(placement
				(enabled no)
				(sheetname "")
			)
			(fill
				(thermal_gap 0.5)
				(thermal_bridge_width 0.5)
				(island_removal_mode 0)
			)
			(polygon
				(pts
					(arc
						(start 170.263566 -129.599944)
						(mid 168.536366 -129.599944)
						(end 170.263566 -129.599944)
					)
				)
			)
		)
		(zone
			(layers "F.Cu" "B.Cu" "In1.Cu" "In2.Cu" "In3.Cu" "In4.Cu" "In5.Cu" "In6.Cu")
			(hatch none 0.5)
			(connect_pads
				(clearance 0)
			)
			(min_thickness 0.25)
			(keepout
				(tracks not_allowed)
				(vias allowed)
				(pads allowed)
				(copperpour not_allowed)
				(footprints allowed)
			)
			(placement
				(enabled no)
				(sheetname "")
			)
			(fill
				(thermal_gap 0.5)
				(thermal_bridge_width 0.5)
				(island_removal_mode 0)
			)
			(polygon
				(pts
					(arc
						(start 190.504826 -129.599944)
						(mid 188.295026 -129.599944)
						(end 190.504826 -129.599944)
					)
				)
			)
		)
	)
	(footprint ""
		(layer "F.Cu")
		(at 102.999794 -9.99998)
		(property "Reference" ""
			(at 0 0 0)
			(layer "F.SilkS")
			(hide yes)
			(effects
				(font
					(size 1.27 1.27)
				)
			)
		)
		(property "Value" "*"
			(at -6.38175 0.19685 0)
			(unlocked yes)
			(layer "F.Fab")
			(hide yes)
			(effects
				(font
					(size 1.016 1.016)
					(thickness 0.1524)
				)
			)
		)
		(duplicate_pad_numbers_are_jumpers no)
		(fp_poly
			(pts
				(arc
					(start 5.0673 0)
					(mid -5.0673 0)
					(end 5.0673 0)
				)
			)
			(stroke
				(width 0)
				(type default)
			)
			(fill no)
			(layer "B.CrtYd")
		)
		(fp_poly
			(pts
				(arc
					(start 5.0673 0)
					(mid -5.0673 0)
					(end 5.0673 0)
				)
			)
			(stroke
				(width 0)
				(type default)
			)
			(fill no)
			(layer "F.CrtYd")
		)
		(fp_poly
			(pts
				(arc
					(start 5.0673 0)
					(mid -5.0673 0)
					(end 5.0673 0)
				)
			)
			(stroke
				(width 0)
				(type default)
			)
			(fill no)
			(layer "B.Fab")
		)
		(fp_poly
			(pts
				(arc
					(start 5.0673 0)
					(mid -5.0673 0)
					(end 5.0673 0)
				)
			)
			(stroke
				(width 0)
				(type default)
			)
			(fill no)
			(layer "F.Fab")
		)
		(pad "1" thru_hole circle
			(at 0 0)
			(size 9.525 9.525)
			(drill 3.5052)
			(layers "*.Cu" "*.Mask")
			(remove_unused_layers no)
			(net "Net_35")
			(clearance -2.5019)
			(thermal_gap 0.3048)
			(padstack
				(mode front_inner_back)
				(layer "Inner"
					(shape circle)
					(size 3.9116 3.9116)
					(clearance 0.3048)
				)
				(layer "B.Cu"
					(shape circle)
					(size 9.525 9.525)
					(clearance -2.5019)
				)
			)
		)
	)
	(footprint ""
		(layer "F.Cu")
		(at 94.1451 -48.720756 180)
		(property "Reference" "C507"
			(at 0 0 180)
			(layer "F.SilkS")
			(hide yes)
			(effects
				(font
					(size 1.27 1.27)
				)
			)
		)
		(property "Value" "SCD1U16V2KX-3GP"
			(at 1.1811 -2.7051 180)
			(unlocked yes)
			(layer "F.Fab")
			(hide yes)
			(effects
				(font
					(size 1.016 1.016)
					(thickness 0.1524)
				)
			)
		)
		(property "Device Type" "C402H22"
			(at 1.1811 -4.2291 180)
			(unlocked yes)
			(layer "F.Fab")
			(hide yes)
			(effects
				(font
					(size 1.016 1.016)
					(thickness 0.1524)
				)
			)
		)
		(duplicate_pad_numbers_are_jumpers no)
		(fp_rect
			(start -0.4318 0.9525)
			(end 0.4318 -0.9525)
			(stroke
				(width 0)
				(type default)
			)
			(fill no)
			(layer "F.CrtYd")
		)
		(fp_rect
			(start -0.4318 0.9525)
			(end 0.4318 -0.9525)
			(stroke
				(width 0)
				(type default)
			)
			(fill no)
			(layer "F.Fab")
		)
		(pad "1" smd custom
			(at 0 -0.4445 180)
			(size 0.1524 0.1524)
			(layers "F.Cu" "F.Mask" "F.Paste")
			(net "P3V3_EN_R")
			(options
				(clearance outline)
				(anchor circle)
			)
			(primitives
				(gr_poly
					(pts
						(arc
							(start 0.3048 -0.2032)
							(mid 0.275042 -0.275042)
							(end 0.2032 -0.3048)
						)
						(arc
							(start -0.2032 -0.3048)
							(mid -0.275042 -0.275042)
							(end -0.3048 -0.2032)
						)
						(arc
							(start -0.3048 0.2032)
							(mid -0.275042 0.275042)
							(end -0.2032 0.3048)
						)
						(arc
							(start 0.2032 0.3048)
							(mid 0.275042 0.275042)
							(end 0.3048 0.2032)
						)
					)
					(width 0)
					(fill yes)
				)
			)
		)
		(pad "2" smd custom
			(at 0 0.4445 180)
			(size 0.1524 0.1524)
			(layers "F.Cu" "F.Mask" "F.Paste")
			(net "GND")
			(options
				(clearance outline)
				(anchor circle)
			)
			(primitives
				(gr_poly
					(pts
						(arc
							(start 0.3048 -0.2032)
							(mid 0.275042 -0.275042)
							(end 0.2032 -0.3048)
						)
						(arc
							(start -0.2032 -0.3048)
							(mid -0.275042 -0.275042)
							(end -0.3048 -0.2032)
						)
						(arc
							(start -0.3048 0.2032)
							(mid -0.275042 0.275042)
							(end -0.2032 0.3048)
						)
						(arc
							(start 0.2032 0.3048)
							(mid 0.275042 0.275042)
							(end 0.3048 0.2032)
						)
					)
					(width 0)
					(fill yes)
				)
			)
		)
	)
	(footprint ""
		(layer "F.Cu")
		(at 94.03588 -148.230844)
		(property "Reference" "C18"
			(at 0 0 0)
			(layer "F.SilkS")
			(hide yes)
			(effects
				(font
					(size 1.27 1.27)
				)
			)
		)
		(property "Value" "SC1U16V3KX-5GP"
			(at 0 -2.8194 0)
			(unlocked yes)
			(layer "F.Fab")
			(hide yes)
			(effects
				(font
					(size 1.016 1.016)
					(thickness 0.1524)
				)
			)
		)
		(property "Device Type" "C603H36"
			(at 0 -4.3434 0)
			(unlocked yes)
			(layer "F.Fab")
			(hide yes)
			(effects
				(font
					(size 1.016 1.016)
					(thickness 0.1524)
				)
			)
		)
		(duplicate_pad_numbers_are_jumpers no)
		(fp_line
			(start 0.508 0)
			(end -0.508 0)
			(stroke
				(width 0.2032)
				(type default)
			)
			(layer "F.SilkS")
		)
		(fp_rect
			(start -0.5842 1.3335)
			(end 0.5842 -1.3335)
			(stroke
				(width 0)
				(type default)
			)
			(fill no)
			(layer "F.CrtYd")
		)
		(fp_rect
			(start -0.5842 1.3335)
			(end 0.5842 -1.3335)
			(stroke
				(width 0)
				(type default)
			)
			(fill no)
			(layer "F.Fab")
		)
		(pad "1" smd custom
			(at 0 -0.762)
			(size 0.2159 0.2159)
			(layers "F.Cu" "F.Mask" "F.Paste")
			(net "CRFILT")
			(options
				(clearance outline)
				(anchor circle)
			)
			(primitives
				(gr_poly
					(pts
						(arc
							(start -0.3302 -0.4318)
							(mid -0.402042 -0.402042)
							(end -0.4318 -0.3302)
						)
						(arc
							(start -0.4318 0.3302)
							(mid -0.402042 0.402042)
							(end -0.3302 0.4318)
						)
						(arc
							(start 0.3302 0.4318)
							(mid 0.402042 0.402042)
							(end 0.4318 0.3302)
						)
						(arc
							(start 0.4318 -0.3302)
							(mid 0.402042 -0.402042)
							(end 0.3302 -0.4318)
						)
					)
					(width 0)
					(fill yes)
				)
			)
		)
		(pad "2" smd custom
			(at 0 0.762)
			(size 0.2159 0.2159)
			(layers "F.Cu" "F.Mask" "F.Paste")
			(net "GND")
			(options
				(clearance outline)
				(anchor circle)
			)
			(primitives
				(gr_poly
					(pts
						(arc
							(start -0.3302 -0.4318)
							(mid -0.402042 -0.402042)
							(end -0.4318 -0.3302)
						)
						(arc
							(start -0.4318 0.3302)
							(mid -0.402042 0.402042)
							(end -0.3302 0.4318)
						)
						(arc
							(start 0.3302 0.4318)
							(mid 0.402042 0.402042)
							(end 0.4318 0.3302)
						)
						(arc
							(start 0.4318 -0.3302)
							(mid 0.402042 -0.402042)
							(end 0.3302 -0.4318)
						)
					)
					(width 0)
					(fill yes)
				)
			)
		)
	)
	(footprint ""
		(layer "F.Cu")
		(at 52.832 -132.207)
		(property "Reference" "TP10"
			(at 0 0 0)
			(layer "F.SilkS")
			(hide yes)
			(effects
				(font
					(size 1.27 1.27)
				)
			)
		)
		(property "Value" "TPAD28-2-GP"
			(at -0.0127 -1.6637 0)
			(unlocked yes)
			(layer "F.Fab")
			(hide yes)
			(effects
				(font
					(size 1.016 1.016)
					(thickness 0.1524)
				)
			)
		)
		(property "Device Type" "TPAD28"
			(at -0.0127 -3.1877 0)
			(unlocked yes)
			(layer "F.Fab")
			(hide yes)
			(effects
				(font
					(size 1.016 1.016)
					(thickness 0.1524)
				)
			)
		)
		(duplicate_pad_numbers_are_jumpers no)
		(fp_poly
			(pts
				(arc
					(start 0.3556 0)
					(mid -0.3556 0)
					(end 0.3556 0)
				)
			)
			(stroke
				(width 0)
				(type default)
			)
			(fill no)
			(layer "F.CrtYd")
		)
		(fp_poly
			(pts
				(arc
					(start 0.6096 0)
					(mid -0.6096 0)
					(end 0.6096 0)
				)
			)
			(stroke
				(width 0)
				(type default)
			)
			(fill no)
			(layer "F.Fab")
		)
		(pad "1" smd circle
			(at 0 0)
			(size 0.7112 0.7112)
			(layers "F.Cu" "F.Mask" "F.Paste")
			(net "TP_BMC0_LPC_LAD1")
		)
	)
	(footprint ""
		(layer "F.Cu")
		(at 57.216548 -131.28752 180)
		(property "Reference" "R288"
			(at 0 0 180)
			(layer "F.SilkS")
			(hide yes)
			(effects
				(font
					(size 1.27 1.27)
				)
			)
		)
		(property "Value" "0R2J-2-GP"
			(at 0.064008 -3.993896 180)
			(unlocked yes)
			(layer "F.Fab")
			(hide yes)
			(effects
				(font
					(size 1.016 1.016)
					(thickness 0.1524)
				)
			)
		)
		(property "Device Type" "R402H16"
			(at 0.064008 -5.517896 180)
			(unlocked yes)
			(layer "F.Fab")
			(hide yes)
			(effects
				(font
					(size 1.016 1.016)
					(thickness 0.1524)
				)
			)
		)
		(duplicate_pad_numbers_are_jumpers no)
		(fp_line
			(start 0.508 -0.9398)
			(end -0.508 -0.9398)
			(stroke
				(width 0.1524)
				(type default)
			)
			(layer "F.SilkS")
		)
		(fp_line
			(start -0.508 -0.9398)
			(end -0.508 0.9398)
			(stroke
				(width 0.1524)
				(type default)
			)
			(layer "F.SilkS")
		)
		(fp_rect
			(start -0.508 0.9398)
			(end 0.508 -0.9398)
			(stroke
				(width 0)
				(type default)
			)
			(fill no)
			(layer "F.CrtYd")
		)
		(fp_rect
			(start -0.508 0.9398)
			(end 0.508 -0.9398)
			(stroke
				(width 0)
				(type default)
			)
			(fill no)
			(layer "F.Fab")
		)
		(pad "1" smd custom
			(at 0 -0.4445 180)
			(size 0.1397 0.1397)
			(layers "F.Cu" "F.Mask" "F.Paste")
			(net "EXP_SPARE_0")
			(options
				(clearance outline)
				(anchor circle)
			)
			(primitives
				(gr_poly
					(pts
						(arc
							(start -0.1778 -0.2794)
							(mid -0.249642 -0.249642)
							(end -0.2794 -0.1778)
						)
						(arc
							(start -0.2794 0.1778)
							(mid -0.249642 0.249642)
							(end -0.1778 0.2794)
						)
						(arc
							(start 0.1778 0.2794)
							(mid 0.249642 0.249642)
							(end 0.2794 0.1778)
						)
						(arc
							(start 0.2794 -0.1778)
							(mid 0.249642 -0.249642)
							(end 0.1778 -0.2794)
						)
					)
					(width 0)
					(fill yes)
				)
			)
		)
		(pad "2" smd custom
			(at 0 0.4445 180)
			(size 0.1397 0.1397)
			(layers "F.Cu" "F.Mask" "F.Paste")
			(net "EXP_SPARE_0_R")
			(options
				(clearance outline)
				(anchor circle)
			)
			(primitives
				(gr_poly
					(pts
						(arc
							(start -0.1778 -0.2794)
							(mid -0.249642 -0.249642)
							(end -0.2794 -0.1778)
						)
						(arc
							(start -0.2794 0.1778)
							(mid -0.249642 0.249642)
							(end -0.1778 0.2794)
						)
						(arc
							(start 0.1778 0.2794)
							(mid 0.249642 0.249642)
							(end 0.2794 0.1778)
						)
						(arc
							(start 0.2794 -0.1778)
							(mid 0.249642 -0.249642)
							(end 0.1778 -0.2794)
						)
					)
					(width 0)
					(fill yes)
				)
			)
		)
	)
	(footprint ""
		(layer "F.Cu")
		(at 71.7804 -173.7106 180)
		(property "Reference" "C78"
			(at 0 0 180)
			(layer "F.SilkS")
			(hide yes)
			(effects
				(font
					(size 1.27 1.27)
				)
			)
		)
		(property "Value" "SCD1U16V2KX-3GP"
			(at 1.1811 -2.7051 180)
			(unlocked yes)
			(layer "F.Fab")
			(hide yes)
			(effects
				(font
					(size 1.016 1.016)
					(thickness 0.1524)
				)
			)
		)
		(property "Device Type" "C402H22"
			(at 1.1811 -4.2291 180)
			(unlocked yes)
			(layer "F.Fab")
			(hide yes)
			(effects
				(font
					(size 1.016 1.016)
					(thickness 0.1524)
				)
			)
		)
		(duplicate_pad_numbers_are_jumpers no)
		(fp_rect
			(start -0.4318 0.9525)
			(end 0.4318 -0.9525)
			(stroke
				(width 0)
				(type default)
			)
			(fill no)
			(layer "F.CrtYd")
		)
		(fp_rect
			(start -0.4318 0.9525)
			(end 0.4318 -0.9525)
			(stroke
				(width 0)
				(type default)
			)
			(fill no)
			(layer "F.Fab")
		)
		(pad "1" smd custom
			(at 0 -0.4445 180)
			(size 0.1524 0.1524)
			(layers "F.Cu" "F.Mask" "F.Paste")
			(net "P3V3_STBY")
			(options
				(clearance outline)
				(anchor circle)
			)
			(primitives
				(gr_poly
					(pts
						(arc
							(start 0.3048 -0.2032)
							(mid 0.275042 -0.275042)
							(end 0.2032 -0.3048)
						)
						(arc
							(start -0.2032 -0.3048)
							(mid -0.275042 -0.275042)
							(end -0.3048 -0.2032)
						)
						(arc
							(start -0.3048 0.2032)
							(mid -0.275042 0.275042)
							(end -0.2032 0.3048)
						)
						(arc
							(start 0.2032 0.3048)
							(mid 0.275042 0.275042)
							(end 0.3048 0.2032)
						)
					)
					(width 0)
					(fill yes)
				)
			)
		)
		(pad "2" smd custom
			(at 0 0.4445 180)
			(size 0.1524 0.1524)
			(layers "F.Cu" "F.Mask" "F.Paste")
			(net "GND")
			(options
				(clearance outline)
				(anchor circle)
			)
			(primitives
				(gr_poly
					(pts
						(arc
							(start 0.3048 -0.2032)
							(mid 0.275042 -0.275042)
							(end 0.2032 -0.3048)
						)
						(arc
							(start -0.2032 -0.3048)
							(mid -0.275042 -0.275042)
							(end -0.3048 -0.2032)
						)
						(arc
							(start -0.3048 0.2032)
							(mid -0.275042 0.275042)
							(end -0.2032 0.3048)
						)
						(arc
							(start 0.2032 0.3048)
							(mid 0.275042 0.275042)
							(end 0.3048 0.2032)
						)
					)
					(width 0)
					(fill yes)
				)
			)
		)
	)
	(footprint ""
		(layer "F.Cu")
		(at 226.217988 -18.469356)
		(property "Reference" "C165"
			(at 0 0 0)
			(layer "F.SilkS")
			(hide yes)
			(effects
				(font
					(size 1.27 1.27)
				)
			)
		)
		(property "Value" "SC10U16V5KX-7-GP-U"
			(at -0.0762 -6.1214 0)
			(unlocked yes)
			(layer "F.Fab")
			(hide yes)
			(effects
				(font
					(size 1.016 1.016)
					(thickness 0.1524)
				)
			)
		)
		(property "Device Type" "C805H58"
			(at -0.0762 -8.1534 0)
			(unlocked yes)
			(layer "F.Fab")
			(hide yes)
			(effects
				(font
					(size 1.016 1.016)
					(thickness 0.1524)
				)
			)
		)
		(duplicate_pad_numbers_are_jumpers no)
		(fp_line
			(start 0.635 0)
			(end -0.635 0)
			(stroke
				(width 0.508)
				(type default)
			)
			(layer "F.SilkS")
		)
		(fp_rect
			(start -0.9652 1.778)
			(end 0.9652 -1.778)
			(stroke
				(width 0)
				(type default)
			)
			(fill no)
			(layer "F.CrtYd")
		)
		(fp_poly
			(pts
				(xy -0.9652 -1.778) (xy 0.9652 -1.778) (xy 0.9652 1.778) (xy -0.9652 1.778)
			)
			(stroke
				(width 0)
				(type default)
			)
			(fill no)
			(layer "F.Fab")
		)
		(pad "1" smd rect
			(at 0 -0.9652)
			(size 1.397 1.143)
			(layers "F.Cu" "F.Mask" "F.Paste")
			(net "P5V_STBY")
		)
		(pad "2" smd rect
			(at 0 0.9652)
			(size 1.397 1.143)
			(layers "F.Cu" "F.Mask" "F.Paste")
			(net "GND")
		)
	)
	(footprint ""
		(layer "F.Cu")
		(at 62.770512 -136.31164 -90)
		(property "Reference" "R352"
			(at 0 0 270)
			(layer "F.SilkS")
			(hide yes)
			(effects
				(font
					(size 1.27 1.27)
				)
			)
		)
		(property "Value" "4K7R2F-GP"
			(at 0.064008 -3.993896 270)
			(unlocked yes)
			(layer "F.Fab")
			(hide yes)
			(effects
				(font
					(size 1.016 1.016)
					(thickness 0.1524)
				)
			)
		)
		(property "Device Type" "R402H16"
			(at 0.064008 -5.517896 270)
			(unlocked yes)
			(layer "F.Fab")
			(hide yes)
			(effects
				(font
					(size 1.016 1.016)
					(thickness 0.1524)
				)
			)
		)
		(duplicate_pad_numbers_are_jumpers no)
		(fp_line
			(start -0.508 -0.9398)
			(end -0.508 0.9398)
			(stroke
				(width 0.1524)
				(type default)
			)
			(layer "F.SilkS")
		)
		(fp_line
			(start 0.508 -0.9398)
			(end -0.508 -0.9398)
			(stroke
				(width 0.1524)
				(type default)
			)
			(layer "F.SilkS")
		)
		(fp_rect
			(start -0.508 0.9398)
			(end 0.508 -0.9398)
			(stroke
				(width 0)
				(type default)
			)
			(fill no)
			(layer "F.CrtYd")
		)
		(fp_rect
			(start -0.508 0.9398)
			(end 0.508 -0.9398)
			(stroke
				(width 0)
				(type default)
			)
			(fill no)
			(layer "F.Fab")
		)
		(pad "1" smd custom
			(at 0 -0.4445 270)
			(size 0.1397 0.1397)
			(layers "F.Cu" "F.Mask" "F.Paste")
			(net "P3V3_STBY")
			(options
				(clearance outline)
				(anchor circle)
			)
			(primitives
				(gr_poly
					(pts
						(arc
							(start -0.1778 -0.2794)
							(mid -0.249642 -0.249642)
							(end -0.2794 -0.1778)
						)
						(arc
							(start -0.2794 0.1778)
							(mid -0.249642 0.249642)
							(end -0.1778 0.2794)
						)
						(arc
							(start 0.1778 0.2794)
							(mid 0.249642 0.249642)
							(end 0.2794 0.1778)
						)
						(arc
							(start 0.2794 -0.1778)
							(mid 0.249642 -0.249642)
							(end 0.1778 -0.2794)
						)
					)
					(width 0)
					(fill yes)
				)
			)
		)
		(pad "2" smd custom
			(at 0 0.4445 270)
			(size 0.1397 0.1397)
			(layers "F.Cu" "F.Mask" "F.Paste")
			(net "SLOTID_0")
			(options
				(clearance outline)
				(anchor circle)
			)
			(primitives
				(gr_poly
					(pts
						(arc
							(start -0.1778 -0.2794)
							(mid -0.249642 -0.249642)
							(end -0.2794 -0.1778)
						)
						(arc
							(start -0.2794 0.1778)
							(mid -0.249642 0.249642)
							(end -0.1778 0.2794)
						)
						(arc
							(start 0.1778 0.2794)
							(mid 0.249642 0.249642)
							(end 0.2794 0.1778)
						)
						(arc
							(start 0.2794 -0.1778)
							(mid 0.249642 -0.249642)
							(end 0.1778 -0.2794)
						)
					)
					(width 0)
					(fill yes)
				)
			)
		)
	)
	(footprint ""
		(layer "F.Cu")
		(at 153.351738 -16.486378 180)
		(property "Reference" "C202"
			(at 0 0 180)
			(layer "F.SilkS")
			(hide yes)
			(effects
				(font
					(size 1.27 1.27)
				)
			)
		)
		(property "Value" "SC1U16V3KX-5GP"
			(at 0 -2.8194 180)
			(unlocked yes)
			(layer "F.Fab")
			(hide yes)
			(effects
				(font
					(size 1.016 1.016)
					(thickness 0.1524)
				)
			)
		)
		(property "Device Type" "C603H36"
			(at 0 -4.3434 180)
			(unlocked yes)
			(layer "F.Fab")
			(hide yes)
			(effects
				(font
					(size 1.016 1.016)
					(thickness 0.1524)
				)
			)
		)
		(duplicate_pad_numbers_are_jumpers no)
		(fp_line
			(start 0.508 0)
			(end -0.508 0)
			(stroke
				(width 0.2032)
				(type default)
			)
			(layer "F.SilkS")
		)
		(fp_rect
			(start -0.5842 1.3335)
			(end 0.5842 -1.3335)
			(stroke
				(width 0)
				(type default)
			)
			(fill no)
			(layer "F.CrtYd")
		)
		(fp_rect
			(start -0.5842 1.3335)
			(end 0.5842 -1.3335)
			(stroke
				(width 0)
				(type default)
			)
			(fill no)
			(layer "F.Fab")
		)
		(pad "1" smd custom
			(at 0 -0.762 180)
			(size 0.2159 0.2159)
			(layers "F.Cu" "F.Mask" "F.Paste")
			(net "P12V_STBY_VCC_PU4")
			(options
				(clearance outline)
				(anchor circle)
			)
			(primitives
				(gr_poly
					(pts
						(arc
							(start -0.3302 -0.4318)
							(mid -0.402042 -0.402042)
							(end -0.4318 -0.3302)
						)
						(arc
							(start -0.4318 0.3302)
							(mid -0.402042 0.402042)
							(end -0.3302 0.4318)
						)
						(arc
							(start 0.3302 0.4318)
							(mid 0.402042 0.402042)
							(end 0.4318 0.3302)
						)
						(arc
							(start 0.4318 -0.3302)
							(mid 0.402042 -0.402042)
							(end 0.3302 -0.4318)
						)
					)
					(width 0)
					(fill yes)
				)
			)
		)
		(pad "2" smd custom
			(at 0 0.762 180)
			(size 0.2159 0.2159)
			(layers "F.Cu" "F.Mask" "F.Paste")
			(net "GND")
			(options
				(clearance outline)
				(anchor circle)
			)
			(primitives
				(gr_poly
					(pts
						(arc
							(start -0.3302 -0.4318)
							(mid -0.402042 -0.402042)
							(end -0.4318 -0.3302)
						)
						(arc
							(start -0.4318 0.3302)
							(mid -0.402042 0.402042)
							(end -0.3302 0.4318)
						)
						(arc
							(start 0.3302 0.4318)
							(mid 0.402042 0.402042)
							(end 0.4318 0.3302)
						)
						(arc
							(start 0.4318 -0.3302)
							(mid 0.402042 -0.402042)
							(end 0.3302 -0.4318)
						)
					)
					(width 0)
					(fill yes)
				)
			)
		)
	)
	(footprint ""
		(layer "F.Cu")
		(at 34.531046 -152.161748 -90)
		(property "Reference" "R333"
			(at 0 0 270)
			(layer "F.SilkS")
			(hide yes)
			(effects
				(font
					(size 1.27 1.27)
				)
			)
		)
		(property "Value" "0R2J-2-GP"
			(at 0.064008 -3.993896 270)
			(unlocked yes)
			(layer "F.Fab")
			(hide yes)
			(effects
				(font
					(size 1.016 1.016)
					(thickness 0.1524)
				)
			)
		)
		(property "Device Type" "R402H16"
			(at 0.064008 -5.517896 270)
			(unlocked yes)
			(layer "F.Fab")
			(hide yes)
			(effects
				(font
					(size 1.016 1.016)
					(thickness 0.1524)
				)
			)
		)
		(duplicate_pad_numbers_are_jumpers no)
		(fp_line
			(start -0.508 -0.9398)
			(end -0.508 0.9398)
			(stroke
				(width 0.1524)
				(type default)
			)
			(layer "F.SilkS")
		)
		(fp_line
			(start 0.508 -0.9398)
			(end -0.508 -0.9398)
			(stroke
				(width 0.1524)
				(type default)
			)
			(layer "F.SilkS")
		)
		(fp_rect
			(start -0.508 0.9398)
			(end 0.508 -0.9398)
			(stroke
				(width 0)
				(type default)
			)
			(fill no)
			(layer "F.CrtYd")
		)
		(fp_rect
			(start -0.508 0.9398)
			(end 0.508 -0.9398)
			(stroke
				(width 0)
				(type default)
			)
			(fill no)
			(layer "F.Fab")
		)
		(pad "1" smd custom
			(at 0 -0.4445 270)
			(size 0.1397 0.1397)
			(layers "F.Cu" "F.Mask" "F.Paste")
			(net "THROTTLE_N")
			(options
				(clearance outline)
				(anchor circle)
			)
			(primitives
				(gr_poly
					(pts
						(arc
							(start -0.1778 -0.2794)
							(mid -0.249642 -0.249642)
							(end -0.2794 -0.1778)
						)
						(arc
							(start -0.2794 0.1778)
							(mid -0.249642 0.249642)
							(end -0.1778 0.2794)
						)
						(arc
							(start 0.1778 0.2794)
							(mid 0.249642 0.249642)
							(end 0.2794 0.1778)
						)
						(arc
							(start 0.2794 -0.1778)
							(mid 0.249642 -0.249642)
							(end 0.1778 -0.2794)
						)
					)
					(width 0)
					(fill yes)
				)
			)
		)
		(pad "2" smd custom
			(at 0 0.4445 270)
			(size 0.1397 0.1397)
			(layers "F.Cu" "F.Mask" "F.Paste")
			(net "COMP_FAST_THROTTLE_N")
			(options
				(clearance outline)
				(anchor circle)
			)
			(primitives
				(gr_poly
					(pts
						(arc
							(start -0.1778 -0.2794)
							(mid -0.249642 -0.249642)
							(end -0.2794 -0.1778)
						)
						(arc
							(start -0.2794 0.1778)
							(mid -0.249642 0.249642)
							(end -0.1778 0.2794)
						)
						(arc
							(start 0.1778 0.2794)
							(mid 0.249642 0.249642)
							(end 0.2794 0.1778)
						)
						(arc
							(start 0.2794 -0.1778)
							(mid 0.249642 -0.249642)
							(end 0.1778 -0.2794)
						)
					)
					(width 0)
					(fill yes)
				)
			)
		)
	)
	(footprint ""
		(layer "F.Cu")
		(at 212.830664 -89.386156 -90)
		(property "Reference" "R839"
			(at 0 0 270)
			(layer "F.SilkS")
			(hide yes)
			(effects
				(font
					(size 1.27 1.27)
				)
			)
		)
		(property "Value" "10KR2F-2-GP"
			(at 0.064008 -3.993896 270)
			(unlocked yes)
			(layer "F.Fab")
			(hide yes)
			(effects
				(font
					(size 1.016 1.016)
					(thickness 0.1524)
				)
			)
		)
		(property "Device Type" "R402H16"
			(at 0.064008 -5.517896 270)
			(unlocked yes)
			(layer "F.Fab")
			(hide yes)
			(effects
				(font
					(size 1.016 1.016)
					(thickness 0.1524)
				)
			)
		)
		(duplicate_pad_numbers_are_jumpers no)
		(fp_line
			(start -0.508 -0.9398)
			(end -0.508 0.9398)
			(stroke
				(width 0.1524)
				(type default)
			)
			(layer "F.SilkS")
		)
		(fp_line
			(start 0.508 -0.9398)
			(end -0.508 -0.9398)
			(stroke
				(width 0.1524)
				(type default)
			)
			(layer "F.SilkS")
		)
		(fp_rect
			(start -0.508 0.9398)
			(end 0.508 -0.9398)
			(stroke
				(width 0)
				(type default)
			)
			(fill no)
			(layer "F.CrtYd")
		)
		(fp_rect
			(start -0.508 0.9398)
			(end 0.508 -0.9398)
			(stroke
				(width 0)
				(type default)
			)
			(fill no)
			(layer "F.Fab")
		)
		(pad "1" smd custom
			(at 0 -0.4445 270)
			(size 0.1397 0.1397)
			(layers "F.Cu" "F.Mask" "F.Paste")
			(net "GND")
			(options
				(clearance outline)
				(anchor circle)
			)
			(primitives
				(gr_poly
					(pts
						(arc
							(start -0.1778 -0.2794)
							(mid -0.249642 -0.249642)
							(end -0.2794 -0.1778)
						)
						(arc
							(start -0.2794 0.1778)
							(mid -0.249642 0.249642)
							(end -0.1778 0.2794)
						)
						(arc
							(start 0.1778 0.2794)
							(mid 0.249642 0.249642)
							(end 0.2794 0.1778)
						)
						(arc
							(start 0.2794 -0.1778)
							(mid 0.249642 -0.249642)
							(end 0.1778 -0.2794)
						)
					)
					(width 0)
					(fill yes)
				)
			)
		)
		(pad "2" smd custom
			(at 0 0.4445 270)
			(size 0.1397 0.1397)
			(layers "F.Cu" "F.Mask" "F.Paste")
			(net "P3V3_PG")
			(options
				(clearance outline)
				(anchor circle)
			)
			(primitives
				(gr_poly
					(pts
						(arc
							(start -0.1778 -0.2794)
							(mid -0.249642 -0.249642)
							(end -0.2794 -0.1778)
						)
						(arc
							(start -0.2794 0.1778)
							(mid -0.249642 0.249642)
							(end -0.1778 0.2794)
						)
						(arc
							(start 0.1778 0.2794)
							(mid 0.249642 0.249642)
							(end 0.2794 0.1778)
						)
						(arc
							(start 0.2794 -0.1778)
							(mid 0.249642 -0.249642)
							(end 0.1778 -0.2794)
						)
					)
					(width 0)
					(fill yes)
				)
			)
		)
	)
	(footprint ""
		(layer "F.Cu")
		(at 89.52992 -148.809456 180)
		(property "Reference" "R33"
			(at 0 0 180)
			(layer "F.SilkS")
			(hide yes)
			(effects
				(font
					(size 1.27 1.27)
				)
			)
		)
		(property "Value" "4K7R2F-GP"
			(at 0.064008 -3.993896 180)
			(unlocked yes)
			(layer "F.Fab")
			(hide yes)
			(effects
				(font
					(size 1.016 1.016)
					(thickness 0.1524)
				)
			)
		)
		(property "Device Type" "R402H16"
			(at 0.064008 -5.517896 180)
			(unlocked yes)
			(layer "F.Fab")
			(hide yes)
			(effects
				(font
					(size 1.016 1.016)
					(thickness 0.1524)
				)
			)
		)
		(duplicate_pad_numbers_are_jumpers no)
		(fp_line
			(start 0.508 -0.9398)
			(end -0.508 -0.9398)
			(stroke
				(width 0.1524)
				(type default)
			)
			(layer "F.SilkS")
		)
		(fp_line
			(start -0.508 -0.9398)
			(end -0.508 0.9398)
			(stroke
				(width 0.1524)
				(type default)
			)
			(layer "F.SilkS")
		)
		(fp_rect
			(start -0.508 0.9398)
			(end 0.508 -0.9398)
			(stroke
				(width 0)
				(type default)
			)
			(fill no)
			(layer "F.CrtYd")
		)
		(fp_rect
			(start -0.508 0.9398)
			(end 0.508 -0.9398)
			(stroke
				(width 0)
				(type default)
			)
			(fill no)
			(layer "F.Fab")
		)
		(pad "1" smd custom
			(at 0 -0.4445 180)
			(size 0.1397 0.1397)
			(layers "F.Cu" "F.Mask" "F.Paste")
			(net "P3V3_STBY")
			(options
				(clearance outline)
				(anchor circle)
			)
			(primitives
				(gr_poly
					(pts
						(arc
							(start -0.1778 -0.2794)
							(mid -0.249642 -0.249642)
							(end -0.2794 -0.1778)
						)
						(arc
							(start -0.2794 0.1778)
							(mid -0.249642 0.249642)
							(end -0.1778 0.2794)
						)
						(arc
							(start 0.1778 0.2794)
							(mid 0.249642 0.249642)
							(end 0.2794 0.1778)
						)
						(arc
							(start 0.2794 -0.1778)
							(mid 0.249642 -0.249642)
							(end 0.1778 -0.2794)
						)
					)
					(width 0)
					(fill yes)
				)
			)
		)
		(pad "2" smd custom
			(at 0 0.4445 180)
			(size 0.1397 0.1397)
			(layers "F.Cu" "F.Mask" "F.Paste")
			(net "USB_EN_1")
			(options
				(clearance outline)
				(anchor circle)
			)
			(primitives
				(gr_poly
					(pts
						(arc
							(start -0.1778 -0.2794)
							(mid -0.249642 -0.249642)
							(end -0.2794 -0.1778)
						)
						(arc
							(start -0.2794 0.1778)
							(mid -0.249642 0.249642)
							(end -0.1778 0.2794)
						)
						(arc
							(start 0.1778 0.2794)
							(mid 0.249642 0.249642)
							(end 0.2794 0.1778)
						)
						(arc
							(start 0.2794 -0.1778)
							(mid 0.249642 -0.249642)
							(end 0.1778 -0.2794)
						)
					)
					(width 0)
					(fill yes)
				)
			)
		)
	)
	(footprint ""
		(layer "F.Cu")
		(at 195.453 -140.716 -135)
		(property "Reference" "VIA56"
			(at 0 0 225)
			(layer "F.SilkS")
			(hide yes)
			(effects
				(font
					(size 1.27 1.27)
				)
			)
		)
		(property "Value" "85OHM-8L-1D6MM-L16L18-GP"
			(at 4.064105 0.609655 225)
			(unlocked yes)
			(layer "F.Fab")
			(hide yes)
			(effects
				(font
					(size 1.016 1.016)
					(thickness 0.1524)
				)
			)
		)
		(property "Device Type" "VIA-PCIE-4P-368076"
			(at 4.064105 -0.914474 225)
			(unlocked yes)
			(layer "F.Fab")
			(hide yes)
			(effects
				(font
					(size 1.016 1.016)
					(thickness 0.1524)
				)
			)
		)
		(duplicate_pad_numbers_are_jumpers no)
		(fp_poly
			(pts
				(xy -1.841491 -0.381057) (xy 1.841509 -0.381058) (xy 1.841508 0.380942) (xy -1.841491 0.380942)
			)
			(stroke
				(width 0)
				(type default)
			)
			(fill no)
			(layer "F.CrtYd")
		)
		(fp_poly
			(pts
				(xy -1.841491 -0.381057) (xy 1.841509 -0.381058) (xy 1.841508 0.380942) (xy -1.841491 0.380942)
			)
			(stroke
				(width 0)
				(type default)
			)
			(fill no)
			(layer "F.Fab")
		)
		(pad "1" thru_hole circle
			(at -1.460499 0 225)
			(size 0.508 0.508)
			(drill 0.254)
			(layers "*.Cu" "*.Mask")
			(remove_unused_layers no)
			(net "GND")
			(clearance 0.127)
			(thermal_gap 0.127)
		)
		(pad "2" thru_hole circle
			(at -0.4445 0 225)
			(size 0.508 0.508)
			(drill 0.254)
			(layers "*.Cu" "*.Mask")
			(remove_unused_layers no)
			(net "PCIE_COMP_TO_IOM_11_DP")
			(clearance 0.127)
			(thermal_gap 0.127)
		)
		(pad "3" thru_hole circle
			(at 0.4445 0 225)
			(size 0.508 0.508)
			(drill 0.254)
			(layers "*.Cu" "*.Mask")
			(remove_unused_layers no)
			(net "PCIE_COMP_TO_IOM_11_DN")
			(clearance 0.127)
			(thermal_gap 0.127)
		)
		(pad "4" thru_hole circle
			(at 1.460499 0 225)
			(size 0.508 0.508)
			(drill 0.254)
			(layers "*.Cu" "*.Mask")
			(remove_unused_layers no)
			(net "GND")
			(clearance 0.127)
			(thermal_gap 0.127)
		)
	)
	(footprint ""
		(layer "F.Cu")
		(at 42.5196 -157.0482)
		(property "Reference" "TP187"
			(at 0 0 0)
			(layer "F.SilkS")
			(hide yes)
			(effects
				(font
					(size 1.27 1.27)
				)
			)
		)
		(property "Value" "TPAD28-2-GP"
			(at -0.0127 -1.6637 0)
			(unlocked yes)
			(layer "F.Fab")
			(hide yes)
			(effects
				(font
					(size 1.016 1.016)
					(thickness 0.1524)
				)
			)
		)
		(property "Device Type" "TPAD28"
			(at -0.0127 -3.1877 0)
			(unlocked yes)
			(layer "F.Fab")
			(hide yes)
			(effects
				(font
					(size 1.016 1.016)
					(thickness 0.1524)
				)
			)
		)
		(duplicate_pad_numbers_are_jumpers no)
		(fp_poly
			(pts
				(arc
					(start 0.3556 0)
					(mid -0.3556 0)
					(end 0.3556 0)
				)
			)
			(stroke
				(width 0)
				(type default)
			)
			(fill no)
			(layer "F.CrtYd")
		)
		(fp_poly
			(pts
				(arc
					(start 0.6096 0)
					(mid -0.6096 0)
					(end 0.6096 0)
				)
			)
			(stroke
				(width 0)
				(type default)
			)
			(fill no)
			(layer "F.Fab")
		)
		(pad "1" smd circle
			(at 0 0)
			(size 0.7112 0.7112)
			(layers "F.Cu" "F.Mask" "F.Paste")
			(net "TP_BMC_GPIOL1")
		)
	)
	(footprint ""
		(layer "F.Cu")
		(at 74.0918 -185.9026)
		(property "Reference" "R507"
			(at 0 0 0)
			(layer "F.SilkS")
			(hide yes)
			(effects
				(font
					(size 1.27 1.27)
				)
			)
		)
		(property "Value" "10KR2F-2-GP"
			(at 0.064008 -3.993896 0)
			(unlocked yes)
			(layer "F.Fab")
			(hide yes)
			(effects
				(font
					(size 1.016 1.016)
					(thickness 0.1524)
				)
			)
		)
		(property "Device Type" "R402H16"
			(at 0.064008 -5.517896 0)
			(unlocked yes)
			(layer "F.Fab")
			(hide yes)
			(effects
				(font
					(size 1.016 1.016)
					(thickness 0.1524)
				)
			)
		)
		(duplicate_pad_numbers_are_jumpers no)
		(fp_line
			(start -0.508 -0.9398)
			(end -0.508 0.9398)
			(stroke
				(width 0.1524)
				(type default)
			)
			(layer "F.SilkS")
		)
		(fp_line
			(start 0.508 -0.9398)
			(end -0.508 -0.9398)
			(stroke
				(width 0.1524)
				(type default)
			)
			(layer "F.SilkS")
		)
		(fp_rect
			(start -0.508 0.9398)
			(end 0.508 -0.9398)
			(stroke
				(width 0)
				(type default)
			)
			(fill no)
			(layer "F.CrtYd")
		)
		(fp_rect
			(start -0.508 0.9398)
			(end 0.508 -0.9398)
			(stroke
				(width 0)
				(type default)
			)
			(fill no)
			(layer "F.Fab")
		)
		(pad "1" smd custom
			(at 0 -0.4445)
			(size 0.1397 0.1397)
			(layers "F.Cu" "F.Mask" "F.Paste")
			(net "P3V3_STBY")
			(options
				(clearance outline)
				(anchor circle)
			)
			(primitives
				(gr_poly
					(pts
						(arc
							(start -0.1778 -0.2794)
							(mid -0.249642 -0.249642)
							(end -0.2794 -0.1778)
						)
						(arc
							(start -0.2794 0.1778)
							(mid -0.249642 0.249642)
							(end -0.1778 0.2794)
						)
						(arc
							(start 0.1778 0.2794)
							(mid 0.249642 0.249642)
							(end 0.2794 0.1778)
						)
						(arc
							(start 0.2794 -0.1778)
							(mid 0.249642 -0.249642)
							(end 0.1778 -0.2794)
						)
					)
					(width 0)
					(fill yes)
				)
			)
		)
		(pad "2" smd custom
			(at 0 0.4445)
			(size 0.1397 0.1397)
			(layers "F.Cu" "F.Mask" "F.Paste")
			(net "PWRGD_P2V5_STBY")
			(options
				(clearance outline)
				(anchor circle)
			)
			(primitives
				(gr_poly
					(pts
						(arc
							(start -0.1778 -0.2794)
							(mid -0.249642 -0.249642)
							(end -0.2794 -0.1778)
						)
						(arc
							(start -0.2794 0.1778)
							(mid -0.249642 0.249642)
							(end -0.1778 0.2794)
						)
						(arc
							(start 0.1778 0.2794)
							(mid 0.249642 0.249642)
							(end 0.2794 0.1778)
						)
						(arc
							(start 0.2794 -0.1778)
							(mid 0.249642 -0.249642)
							(end 0.1778 -0.2794)
						)
					)
					(width 0)
					(fill yes)
				)
			)
		)
	)
	(footprint ""
		(layer "F.Cu")
		(at 21.6916 -161.725864)
		(property "Reference" "C227"
			(at 0 0 0)
			(layer "F.SilkS")
			(hide yes)
			(effects
				(font
					(size 1.27 1.27)
				)
			)
		)
		(property "Value" "SCD1U16V2KX-3GP"
			(at 1.1811 -2.7051 0)
			(unlocked yes)
			(layer "F.Fab")
			(hide yes)
			(effects
				(font
					(size 1.016 1.016)
					(thickness 0.1524)
				)
			)
		)
		(property "Device Type" "C402H22"
			(at 1.1811 -4.2291 0)
			(unlocked yes)
			(layer "F.Fab")
			(hide yes)
			(effects
				(font
					(size 1.016 1.016)
					(thickness 0.1524)
				)
			)
		)
		(duplicate_pad_numbers_are_jumpers no)
		(fp_rect
			(start -0.4318 0.9525)
			(end 0.4318 -0.9525)
			(stroke
				(width 0)
				(type default)
			)
			(fill no)
			(layer "F.CrtYd")
		)
		(fp_rect
			(start -0.4318 0.9525)
			(end 0.4318 -0.9525)
			(stroke
				(width 0)
				(type default)
			)
			(fill no)
			(layer "F.Fab")
		)
		(pad "1" smd custom
			(at 0 -0.4445)
			(size 0.1524 0.1524)
			(layers "F.Cu" "F.Mask" "F.Paste")
			(net "TPS74801_P1V2_STBY_OUT")
			(options
				(clearance outline)
				(anchor circle)
			)
			(primitives
				(gr_poly
					(pts
						(arc
							(start 0.3048 -0.2032)
							(mid 0.275042 -0.275042)
							(end 0.2032 -0.3048)
						)
						(arc
							(start -0.2032 -0.3048)
							(mid -0.275042 -0.275042)
							(end -0.3048 -0.2032)
						)
						(arc
							(start -0.3048 0.2032)
							(mid -0.275042 0.275042)
							(end -0.2032 0.3048)
						)
						(arc
							(start 0.2032 0.3048)
							(mid 0.275042 0.275042)
							(end 0.3048 0.2032)
						)
					)
					(width 0)
					(fill yes)
				)
			)
		)
		(pad "2" smd custom
			(at 0 0.4445)
			(size 0.1524 0.1524)
			(layers "F.Cu" "F.Mask" "F.Paste")
			(net "GND")
			(options
				(clearance outline)
				(anchor circle)
			)
			(primitives
				(gr_poly
					(pts
						(arc
							(start 0.3048 -0.2032)
							(mid 0.275042 -0.275042)
							(end 0.2032 -0.3048)
						)
						(arc
							(start -0.2032 -0.3048)
							(mid -0.275042 -0.275042)
							(end -0.3048 -0.2032)
						)
						(arc
							(start -0.3048 0.2032)
							(mid -0.275042 0.275042)
							(end -0.2032 0.3048)
						)
						(arc
							(start 0.2032 0.3048)
							(mid 0.275042 0.275042)
							(end 0.3048 0.2032)
						)
					)
					(width 0)
					(fill yes)
				)
			)
		)
	)
	(footprint ""
		(layer "F.Cu")
		(at 70.5104 -170.2054)
		(property "Reference" "D11"
			(at 0 0 0)
			(layer "F.SilkS")
			(hide yes)
			(effects
				(font
					(size 1.27 1.27)
				)
			)
		)
		(property "Value" "BAT54WS-7-F-GP"
			(at 0 -6.7818 0)
			(unlocked yes)
			(layer "F.Fab")
			(hide yes)
			(effects
				(font
					(size 1.016 1.016)
					(thickness 0.1524)
				)
			)
		)
		(property "Device Type" "SOD323AKH42"
			(at 0 -8.6868 0)
			(unlocked yes)
			(layer "F.Fab")
			(hide yes)
			(effects
				(font
					(size 1.016 1.016)
					(thickness 0.1524)
				)
			)
		)
		(duplicate_pad_numbers_are_jumpers no)
		(fp_line
			(start -0.889 -1.9304)
			(end 0.889 -1.9304)
			(stroke
				(width 0.1524)
				(type default)
			)
			(layer "F.SilkS")
		)
		(fp_line
			(start -0.889 2.159)
			(end -0.889 -1.9304)
			(stroke
				(width 0.1524)
				(type default)
			)
			(layer "F.SilkS")
		)
		(fp_line
			(start 0.762 2.0574)
			(end -0.762 2.0574)
			(stroke
				(width 0.508)
				(type default)
			)
			(layer "F.SilkS")
		)
		(fp_line
			(start 0.889 -1.9304)
			(end 0.889 2.159)
			(stroke
				(width 0.1524)
				(type default)
			)
			(layer "F.SilkS")
		)
		(fp_line
			(start 0.889 2.159)
			(end -0.889 2.159)
			(stroke
				(width 0.1524)
				(type default)
			)
			(layer "F.SilkS")
		)
		(fp_rect
			(start -1.016 2.3114)
			(end 1.016 -2.0066)
			(stroke
				(width 0)
				(type default)
			)
			(fill no)
			(layer "F.CrtYd")
		)
		(fp_poly
			(pts
				(xy -1.016 -2.0066) (xy 1.016 -2.0066) (xy 1.016 2.3114) (xy -1.016 2.3114)
			)
			(stroke
				(width 0)
				(type default)
			)
			(fill no)
			(layer "F.Fab")
		)
		(pad "A" smd rect
			(at 0 -1.143)
			(size 0.5588 1.016)
			(layers "F.Cu" "F.Mask" "F.Paste")
			(net "BMC_SELF_HW_RST")
		)
		(pad "K" smd rect
			(at 0 1.143)
			(size 0.5588 1.016)
			(layers "F.Cu" "F.Mask" "F.Paste")
			(net "BMC_SELF_HW_RST_D")
		)
	)
	(footprint ""
		(layer "F.Cu")
		(at 98.501708 -176.332642 -90)
		(property "Reference" "R736"
			(at 0 0 270)
			(layer "F.SilkS")
			(hide yes)
			(effects
				(font
					(size 1.27 1.27)
				)
			)
		)
		(property "Value" "0R2J-2-GP"
			(at 0.064008 -3.993896 270)
			(unlocked yes)
			(layer "F.Fab")
			(hide yes)
			(effects
				(font
					(size 1.016 1.016)
					(thickness 0.1524)
				)
			)
		)
		(property "Device Type" "R402H16"
			(at 0.064008 -5.517896 270)
			(unlocked yes)
			(layer "F.Fab")
			(hide yes)
			(effects
				(font
					(size 1.016 1.016)
					(thickness 0.1524)
				)
			)
		)
		(duplicate_pad_numbers_are_jumpers no)
		(fp_line
			(start -0.508 -0.9398)
			(end -0.508 0.9398)
			(stroke
				(width 0.1524)
				(type default)
			)
			(layer "F.SilkS")
		)
		(fp_line
			(start 0.508 -0.9398)
			(end -0.508 -0.9398)
			(stroke
				(width 0.1524)
				(type default)
			)
			(layer "F.SilkS")
		)
		(fp_rect
			(start -0.508 0.9398)
			(end 0.508 -0.9398)
			(stroke
				(width 0)
				(type default)
			)
			(fill no)
			(layer "F.CrtYd")
		)
		(fp_rect
			(start -0.508 0.9398)
			(end 0.508 -0.9398)
			(stroke
				(width 0)
				(type default)
			)
			(fill no)
			(layer "F.Fab")
		)
		(pad "1" smd custom
			(at 0 -0.4445 270)
			(size 0.1397 0.1397)
			(layers "F.Cu" "F.Mask" "F.Paste")
			(net "PWRGD_P3V3_STBY_N")
			(options
				(clearance outline)
				(anchor circle)
			)
			(primitives
				(gr_poly
					(pts
						(arc
							(start -0.1778 -0.2794)
							(mid -0.249642 -0.249642)
							(end -0.2794 -0.1778)
						)
						(arc
							(start -0.2794 0.1778)
							(mid -0.249642 0.249642)
							(end -0.1778 0.2794)
						)
						(arc
							(start 0.1778 0.2794)
							(mid 0.249642 0.249642)
							(end 0.2794 0.1778)
						)
						(arc
							(start 0.2794 -0.1778)
							(mid 0.249642 -0.249642)
							(end 0.1778 -0.2794)
						)
					)
					(width 0)
					(fill yes)
				)
			)
		)
		(pad "2" smd custom
			(at 0 0.4445 270)
			(size 0.1397 0.1397)
			(layers "F.Cu" "F.Mask" "F.Paste")
			(net "PWRGD_P3V3_STBY_N_R2")
			(options
				(clearance outline)
				(anchor circle)
			)
			(primitives
				(gr_poly
					(pts
						(arc
							(start -0.1778 -0.2794)
							(mid -0.249642 -0.249642)
							(end -0.2794 -0.1778)
						)
						(arc
							(start -0.2794 0.1778)
							(mid -0.249642 0.249642)
							(end -0.1778 0.2794)
						)
						(arc
							(start 0.1778 0.2794)
							(mid 0.249642 0.249642)
							(end 0.2794 0.1778)
						)
						(arc
							(start 0.2794 -0.1778)
							(mid 0.249642 -0.249642)
							(end 0.1778 -0.2794)
						)
					)
					(width 0)
					(fill yes)
				)
			)
		)
	)
	(footprint ""
		(layer "F.Cu")
		(at 72.4408 -134.8994 -90)
		(property "Reference" "C40"
			(at 0 0 270)
			(layer "F.SilkS")
			(hide yes)
			(effects
				(font
					(size 1.27 1.27)
				)
			)
		)
		(property "Value" "SCD1U16V2KX-3GP"
			(at 1.1811 -2.7051 270)
			(unlocked yes)
			(layer "F.Fab")
			(hide yes)
			(effects
				(font
					(size 1.016 1.016)
					(thickness 0.1524)
				)
			)
		)
		(property "Device Type" "C402H22"
			(at 1.1811 -4.2291 270)
			(unlocked yes)
			(layer "F.Fab")
			(hide yes)
			(effects
				(font
					(size 1.016 1.016)
					(thickness 0.1524)
				)
			)
		)
		(duplicate_pad_numbers_are_jumpers no)
		(fp_rect
			(start -0.4318 0.9525)
			(end 0.4318 -0.9525)
			(stroke
				(width 0)
				(type default)
			)
			(fill no)
			(layer "F.CrtYd")
		)
		(fp_rect
			(start -0.4318 0.9525)
			(end 0.4318 -0.9525)
			(stroke
				(width 0)
				(type default)
			)
			(fill no)
			(layer "F.Fab")
		)
		(pad "1" smd custom
			(at 0 -0.4445 270)
			(size 0.1524 0.1524)
			(layers "F.Cu" "F.Mask" "F.Paste")
			(net "D_FLIP_CLR#")
			(options
				(clearance outline)
				(anchor circle)
			)
			(primitives
				(gr_poly
					(pts
						(arc
							(start 0.3048 -0.2032)
							(mid 0.275042 -0.275042)
							(end 0.2032 -0.3048)
						)
						(arc
							(start -0.2032 -0.3048)
							(mid -0.275042 -0.275042)
							(end -0.3048 -0.2032)
						)
						(arc
							(start -0.3048 0.2032)
							(mid -0.275042 0.275042)
							(end -0.2032 0.3048)
						)
						(arc
							(start 0.2032 0.3048)
							(mid 0.275042 0.275042)
							(end 0.3048 0.2032)
						)
					)
					(width 0)
					(fill yes)
				)
			)
		)
		(pad "2" smd custom
			(at 0 0.4445 270)
			(size 0.1524 0.1524)
			(layers "F.Cu" "F.Mask" "F.Paste")
			(net "GND")
			(options
				(clearance outline)
				(anchor circle)
			)
			(primitives
				(gr_poly
					(pts
						(arc
							(start 0.3048 -0.2032)
							(mid 0.275042 -0.275042)
							(end 0.2032 -0.3048)
						)
						(arc
							(start -0.2032 -0.3048)
							(mid -0.275042 -0.275042)
							(end -0.3048 -0.2032)
						)
						(arc
							(start -0.3048 0.2032)
							(mid -0.275042 0.275042)
							(end -0.2032 0.3048)
						)
						(arc
							(start 0.2032 0.3048)
							(mid 0.275042 0.275042)
							(end 0.3048 0.2032)
						)
					)
					(width 0)
					(fill yes)
				)
			)
		)
	)
	(footprint ""
		(layer "F.Cu")
		(at 228.249988 -18.469356)
		(property "Reference" "C166"
			(at 0 0 0)
			(layer "F.SilkS")
			(hide yes)
			(effects
				(font
					(size 1.27 1.27)
				)
			)
		)
		(property "Value" "SC10U16V5KX-7-GP-U"
			(at -0.0762 -6.1214 0)
			(unlocked yes)
			(layer "F.Fab")
			(hide yes)
			(effects
				(font
					(size 1.016 1.016)
					(thickness 0.1524)
				)
			)
		)
		(property "Device Type" "C805H58"
			(at -0.0762 -8.1534 0)
			(unlocked yes)
			(layer "F.Fab")
			(hide yes)
			(effects
				(font
					(size 1.016 1.016)
					(thickness 0.1524)
				)
			)
		)
		(duplicate_pad_numbers_are_jumpers no)
		(fp_line
			(start 0.635 0)
			(end -0.635 0)
			(stroke
				(width 0.508)
				(type default)
			)
			(layer "F.SilkS")
		)
		(fp_rect
			(start -0.9652 1.778)
			(end 0.9652 -1.778)
			(stroke
				(width 0)
				(type default)
			)
			(fill no)
			(layer "F.CrtYd")
		)
		(fp_poly
			(pts
				(xy -0.9652 -1.778) (xy 0.9652 -1.778) (xy 0.9652 1.778) (xy -0.9652 1.778)
			)
			(stroke
				(width 0)
				(type default)
			)
			(fill no)
			(layer "F.Fab")
		)
		(pad "1" smd rect
			(at 0 -0.9652)
			(size 1.397 1.143)
			(layers "F.Cu" "F.Mask" "F.Paste")
			(net "P5V_STBY")
		)
		(pad "2" smd rect
			(at 0 0.9652)
			(size 1.397 1.143)
			(layers "F.Cu" "F.Mask" "F.Paste")
			(net "GND")
		)
	)
	(footprint ""
		(layer "F.Cu")
		(at 41.1226 -159.4612)
		(property "Reference" "TP188"
			(at 0 0 0)
			(layer "F.SilkS")
			(hide yes)
			(effects
				(font
					(size 1.27 1.27)
				)
			)
		)
		(property "Value" "TPAD28-2-GP"
			(at -0.0127 -1.6637 0)
			(unlocked yes)
			(layer "F.Fab")
			(hide yes)
			(effects
				(font
					(size 1.016 1.016)
					(thickness 0.1524)
				)
			)
		)
		(property "Device Type" "TPAD28"
			(at -0.0127 -3.1877 0)
			(unlocked yes)
			(layer "F.Fab")
			(hide yes)
			(effects
				(font
					(size 1.016 1.016)
					(thickness 0.1524)
				)
			)
		)
		(duplicate_pad_numbers_are_jumpers no)
		(fp_poly
			(pts
				(arc
					(start 0.3556 0)
					(mid -0.3556 0)
					(end 0.3556 0)
				)
			)
			(stroke
				(width 0)
				(type default)
			)
			(fill no)
			(layer "F.CrtYd")
		)
		(fp_poly
			(pts
				(arc
					(start 0.6096 0)
					(mid -0.6096 0)
					(end 0.6096 0)
				)
			)
			(stroke
				(width 0)
				(type default)
			)
			(fill no)
			(layer "F.Fab")
		)
		(pad "1" smd circle
			(at 0 0)
			(size 0.7112 0.7112)
			(layers "F.Cu" "F.Mask" "F.Paste")
			(net "TP_BMC_GPIOL2")
		)
	)
	(footprint ""
		(layer "F.Cu")
		(at 61.468 -149.8092 90)
		(property "Reference" "R338"
			(at 0 0 90)
			(layer "F.SilkS")
			(hide yes)
			(effects
				(font
					(size 1.27 1.27)
				)
			)
		)
		(property "Value" "8K2R2J-3-GP"
			(at 0.064008 -3.993896 90)
			(unlocked yes)
			(layer "F.Fab")
			(hide yes)
			(effects
				(font
					(size 1.016 1.016)
					(thickness 0.1524)
				)
			)
		)
		(property "Device Type" "R402H16"
			(at 0.064008 -5.517896 90)
			(unlocked yes)
			(layer "F.Fab")
			(hide yes)
			(effects
				(font
					(size 1.016 1.016)
					(thickness 0.1524)
				)
			)
		)
		(duplicate_pad_numbers_are_jumpers no)
		(fp_line
			(start 0.508 -0.9398)
			(end -0.508 -0.9398)
			(stroke
				(width 0.1524)
				(type default)
			)
			(layer "F.SilkS")
		)
		(fp_line
			(start -0.508 -0.9398)
			(end -0.508 0.9398)
			(stroke
				(width 0.1524)
				(type default)
			)
			(layer "F.SilkS")
		)
		(fp_rect
			(start -0.508 0.9398)
			(end 0.508 -0.9398)
			(stroke
				(width 0)
				(type default)
			)
			(fill no)
			(layer "F.CrtYd")
		)
		(fp_rect
			(start -0.508 0.9398)
			(end 0.508 -0.9398)
			(stroke
				(width 0)
				(type default)
			)
			(fill no)
			(layer "F.Fab")
		)
		(pad "1" smd custom
			(at 0 -0.4445 90)
			(size 0.1397 0.1397)
			(layers "F.Cu" "F.Mask" "F.Paste")
			(net "PD_USB2AVRES")
			(options
				(clearance outline)
				(anchor circle)
			)
			(primitives
				(gr_poly
					(pts
						(arc
							(start -0.1778 -0.2794)
							(mid -0.249642 -0.249642)
							(end -0.2794 -0.1778)
						)
						(arc
							(start -0.2794 0.1778)
							(mid -0.249642 0.249642)
							(end -0.1778 0.2794)
						)
						(arc
							(start 0.1778 0.2794)
							(mid 0.249642 0.249642)
							(end 0.2794 0.1778)
						)
						(arc
							(start 0.2794 -0.1778)
							(mid 0.249642 -0.249642)
							(end 0.1778 -0.2794)
						)
					)
					(width 0)
					(fill yes)
				)
			)
		)
		(pad "2" smd custom
			(at 0 0.4445 90)
			(size 0.1397 0.1397)
			(layers "F.Cu" "F.Mask" "F.Paste")
			(net "GND")
			(options
				(clearance outline)
				(anchor circle)
			)
			(primitives
				(gr_poly
					(pts
						(arc
							(start -0.1778 -0.2794)
							(mid -0.249642 -0.249642)
							(end -0.2794 -0.1778)
						)
						(arc
							(start -0.2794 0.1778)
							(mid -0.249642 0.249642)
							(end -0.1778 0.2794)
						)
						(arc
							(start 0.1778 0.2794)
							(mid 0.249642 0.249642)
							(end 0.2794 0.1778)
						)
						(arc
							(start 0.2794 -0.1778)
							(mid 0.249642 -0.249642)
							(end 0.1778 -0.2794)
						)
					)
					(width 0)
					(fill yes)
				)
			)
		)
	)
	(footprint ""
		(layer "F.Cu")
		(at 209.931 -140.843 -135)
		(property "Reference" "VIA50"
			(at 0 0 225)
			(layer "F.SilkS")
			(hide yes)
			(effects
				(font
					(size 1.27 1.27)
				)
			)
		)
		(property "Value" "85OHM-8L-1D6MM-L16L18-GP"
			(at 4.064105 0.609655 225)
			(unlocked yes)
			(layer "F.Fab")
			(hide yes)
			(effects
				(font
					(size 1.016 1.016)
					(thickness 0.1524)
				)
			)
		)
		(property "Device Type" "VIA-PCIE-4P-368076"
			(at 4.064105 -0.914474 225)
			(unlocked yes)
			(layer "F.Fab")
			(hide yes)
			(effects
				(font
					(size 1.016 1.016)
					(thickness 0.1524)
				)
			)
		)
		(duplicate_pad_numbers_are_jumpers no)
		(fp_poly
			(pts
				(xy -1.841491 -0.381057) (xy 1.841509 -0.381058) (xy 1.841508 0.380942) (xy -1.841491 0.380942)
			)
			(stroke
				(width 0)
				(type default)
			)
			(fill no)
			(layer "F.CrtYd")
		)
		(fp_poly
			(pts
				(xy -1.841491 -0.381057) (xy 1.841509 -0.381058) (xy 1.841508 0.380942) (xy -1.841491 0.380942)
			)
			(stroke
				(width 0)
				(type default)
			)
			(fill no)
			(layer "F.Fab")
		)
		(pad "1" thru_hole circle
			(at -1.460499 0 225)
			(size 0.508 0.508)
			(drill 0.254)
			(layers "*.Cu" "*.Mask")
			(remove_unused_layers no)
			(net "GND")
			(clearance 0.127)
			(thermal_gap 0.127)
		)
		(pad "2" thru_hole circle
			(at -0.4445 0 225)
			(size 0.508 0.508)
			(drill 0.254)
			(layers "*.Cu" "*.Mask")
			(remove_unused_layers no)
			(net "PCIE_COMP_TO_IOM_8_DP")
			(clearance 0.127)
			(thermal_gap 0.127)
		)
		(pad "3" thru_hole circle
			(at 0.4445 0 225)
			(size 0.508 0.508)
			(drill 0.254)
			(layers "*.Cu" "*.Mask")
			(remove_unused_layers no)
			(net "PCIE_COMP_TO_IOM_8_DN")
			(clearance 0.127)
			(thermal_gap 0.127)
		)
		(pad "4" thru_hole circle
			(at 1.460499 0 225)
			(size 0.508 0.508)
			(drill 0.254)
			(layers "*.Cu" "*.Mask")
			(remove_unused_layers no)
			(net "GND")
			(clearance 0.127)
			(thermal_gap 0.127)
		)
	)
	(footprint ""
		(layer "F.Cu")
		(at 61.4426 -148.7678 -90)
		(property "Reference" "R164"
			(at 0 0 270)
			(layer "F.SilkS")
			(hide yes)
			(effects
				(font
					(size 1.27 1.27)
				)
			)
		)
		(property "Value" "0R2J-2-GP"
			(at 0.064008 -3.993896 270)
			(unlocked yes)
			(layer "F.Fab")
			(hide yes)
			(effects
				(font
					(size 1.016 1.016)
					(thickness 0.1524)
				)
			)
		)
		(property "Device Type" "R402H16"
			(at 0.064008 -5.517896 270)
			(unlocked yes)
			(layer "F.Fab")
			(hide yes)
			(effects
				(font
					(size 1.016 1.016)
					(thickness 0.1524)
				)
			)
		)
		(duplicate_pad_numbers_are_jumpers no)
		(fp_line
			(start -0.508 -0.9398)
			(end -0.508 0.9398)
			(stroke
				(width 0.1524)
				(type default)
			)
			(layer "F.SilkS")
		)
		(fp_line
			(start 0.508 -0.9398)
			(end -0.508 -0.9398)
			(stroke
				(width 0.1524)
				(type default)
			)
			(layer "F.SilkS")
		)
		(fp_rect
			(start -0.508 0.9398)
			(end 0.508 -0.9398)
			(stroke
				(width 0)
				(type default)
			)
			(fill no)
			(layer "F.CrtYd")
		)
		(fp_rect
			(start -0.508 0.9398)
			(end 0.508 -0.9398)
			(stroke
				(width 0)
				(type default)
			)
			(fill no)
			(layer "F.Fab")
		)
		(pad "1" smd custom
			(at 0 -0.4445 270)
			(size 0.1397 0.1397)
			(layers "F.Cu" "F.Mask" "F.Paste")
			(net "I2C_BMC_COMP_SCL_OUT")
			(options
				(clearance outline)
				(anchor circle)
			)
			(primitives
				(gr_poly
					(pts
						(arc
							(start -0.1778 -0.2794)
							(mid -0.249642 -0.249642)
							(end -0.2794 -0.1778)
						)
						(arc
							(start -0.2794 0.1778)
							(mid -0.249642 0.249642)
							(end -0.1778 0.2794)
						)
						(arc
							(start 0.1778 0.2794)
							(mid 0.249642 0.249642)
							(end 0.2794 0.1778)
						)
						(arc
							(start 0.2794 -0.1778)
							(mid 0.249642 -0.249642)
							(end 0.1778 -0.2794)
						)
					)
					(width 0)
					(fill yes)
				)
			)
		)
		(pad "2" smd custom
			(at 0 0.4445 270)
			(size 0.1397 0.1397)
			(layers "F.Cu" "F.Mask" "F.Paste")
			(net "BMC_SMB4_CLK")
			(options
				(clearance outline)
				(anchor circle)
			)
			(primitives
				(gr_poly
					(pts
						(arc
							(start -0.1778 -0.2794)
							(mid -0.249642 -0.249642)
							(end -0.2794 -0.1778)
						)
						(arc
							(start -0.2794 0.1778)
							(mid -0.249642 0.249642)
							(end -0.1778 0.2794)
						)
						(arc
							(start 0.1778 0.2794)
							(mid 0.249642 0.249642)
							(end 0.2794 0.1778)
						)
						(arc
							(start 0.2794 -0.1778)
							(mid 0.249642 -0.249642)
							(end 0.1778 -0.2794)
						)
					)
					(width 0)
					(fill yes)
				)
			)
		)
	)
	(footprint ""
		(layer "F.Cu")
		(at 21.851112 -175.625506)
		(property "Reference" "R532"
			(at 0 0 0)
			(layer "F.SilkS")
			(hide yes)
			(effects
				(font
					(size 1.27 1.27)
				)
			)
		)
		(property "Value" "10KR2F-2-GP"
			(at 0.064008 -3.993896 0)
			(unlocked yes)
			(layer "F.Fab")
			(hide yes)
			(effects
				(font
					(size 1.016 1.016)
					(thickness 0.1524)
				)
			)
		)
		(property "Device Type" "R402H16"
			(at 0.064008 -5.517896 0)
			(unlocked yes)
			(layer "F.Fab")
			(hide yes)
			(effects
				(font
					(size 1.016 1.016)
					(thickness 0.1524)
				)
			)
		)
		(duplicate_pad_numbers_are_jumpers no)
		(fp_line
			(start -0.508 -0.9398)
			(end -0.508 0.9398)
			(stroke
				(width 0.1524)
				(type default)
			)
			(layer "F.SilkS")
		)
		(fp_line
			(start 0.508 -0.9398)
			(end -0.508 -0.9398)
			(stroke
				(width 0.1524)
				(type default)
			)
			(layer "F.SilkS")
		)
		(fp_rect
			(start -0.508 0.9398)
			(end 0.508 -0.9398)
			(stroke
				(width 0)
				(type default)
			)
			(fill no)
			(layer "F.CrtYd")
		)
		(fp_rect
			(start -0.508 0.9398)
			(end 0.508 -0.9398)
			(stroke
				(width 0)
				(type default)
			)
			(fill no)
			(layer "F.Fab")
		)
		(pad "1" smd custom
			(at 0 -0.4445)
			(size 0.1397 0.1397)
			(layers "F.Cu" "F.Mask" "F.Paste")
			(net "P3V3_STBY")
			(options
				(clearance outline)
				(anchor circle)
			)
			(primitives
				(gr_poly
					(pts
						(arc
							(start -0.1778 -0.2794)
							(mid -0.249642 -0.249642)
							(end -0.2794 -0.1778)
						)
						(arc
							(start -0.2794 0.1778)
							(mid -0.249642 0.249642)
							(end -0.1778 0.2794)
						)
						(arc
							(start 0.1778 0.2794)
							(mid 0.249642 0.249642)
							(end 0.2794 0.1778)
						)
						(arc
							(start 0.2794 -0.1778)
							(mid 0.249642 -0.249642)
							(end 0.1778 -0.2794)
						)
					)
					(width 0)
					(fill yes)
				)
			)
		)
		(pad "2" smd custom
			(at 0 0.4445)
			(size 0.1397 0.1397)
			(layers "F.Cu" "F.Mask" "F.Paste")
			(net "PWRGD_P1V2_STBY")
			(options
				(clearance outline)
				(anchor circle)
			)
			(primitives
				(gr_poly
					(pts
						(arc
							(start -0.1778 -0.2794)
							(mid -0.249642 -0.249642)
							(end -0.2794 -0.1778)
						)
						(arc
							(start -0.2794 0.1778)
							(mid -0.249642 0.249642)
							(end -0.1778 0.2794)
						)
						(arc
							(start 0.1778 0.2794)
							(mid 0.249642 0.249642)
							(end 0.2794 0.1778)
						)
						(arc
							(start 0.2794 -0.1778)
							(mid 0.249642 -0.249642)
							(end 0.1778 -0.2794)
						)
					)
					(width 0)
					(fill yes)
				)
			)
		)
	)
	(footprint ""
		(layer "F.Cu")
		(at 202.946 -141.097 -135)
		(property "Reference" "VIA53"
			(at 0 0 225)
			(layer "F.SilkS")
			(hide yes)
			(effects
				(font
					(size 1.27 1.27)
				)
			)
		)
		(property "Value" "85OHM-8L-1D6MM-L16L18-GP"
			(at 4.064105 0.609655 225)
			(unlocked yes)
			(layer "F.Fab")
			(hide yes)
			(effects
				(font
					(size 1.016 1.016)
					(thickness 0.1524)
				)
			)
		)
		(property "Device Type" "VIA-PCIE-4P-368076"
			(at 4.064105 -0.914474 225)
			(unlocked yes)
			(layer "F.Fab")
			(hide yes)
			(effects
				(font
					(size 1.016 1.016)
					(thickness 0.1524)
				)
			)
		)
		(duplicate_pad_numbers_are_jumpers no)
		(fp_poly
			(pts
				(xy -1.841491 -0.381057) (xy 1.841509 -0.381058) (xy 1.841508 0.380942) (xy -1.841491 0.380942)
			)
			(stroke
				(width 0)
				(type default)
			)
			(fill no)
			(layer "F.CrtYd")
		)
		(fp_poly
			(pts
				(xy -1.841491 -0.381057) (xy 1.841509 -0.381058) (xy 1.841508 0.380942) (xy -1.841491 0.380942)
			)
			(stroke
				(width 0)
				(type default)
			)
			(fill no)
			(layer "F.Fab")
		)
		(pad "1" thru_hole circle
			(at -1.460499 0 225)
			(size 0.508 0.508)
			(drill 0.254)
			(layers "*.Cu" "*.Mask")
			(remove_unused_layers no)
			(net "GND")
			(clearance 0.127)
			(thermal_gap 0.127)
		)
		(pad "2" thru_hole circle
			(at -0.4445 0 225)
			(size 0.508 0.508)
			(drill 0.254)
			(layers "*.Cu" "*.Mask")
			(remove_unused_layers no)
			(net "PCIE_IOM_TO_COMP_9_DP")
			(clearance 0.127)
			(thermal_gap 0.127)
		)
		(pad "3" thru_hole circle
			(at 0.4445 0 225)
			(size 0.508 0.508)
			(drill 0.254)
			(layers "*.Cu" "*.Mask")
			(remove_unused_layers no)
			(net "PCIE_IOM_TO_COMP_9_DN")
			(clearance 0.127)
			(thermal_gap 0.127)
		)
		(pad "4" thru_hole circle
			(at 1.460499 0 225)
			(size 0.508 0.508)
			(drill 0.254)
			(layers "*.Cu" "*.Mask")
			(remove_unused_layers no)
			(net "GND")
			(clearance 0.127)
			(thermal_gap 0.127)
		)
	)
	(footprint ""
		(layer "F.Cu")
		(at 58.407808 -159.54502)
		(property "Reference" "R391"
			(at 0 0 0)
			(layer "F.SilkS")
			(hide yes)
			(effects
				(font
					(size 1.27 1.27)
				)
			)
		)
		(property "Value" "4K7R2F-GP"
			(at 0.064008 -3.993896 0)
			(unlocked yes)
			(layer "F.Fab")
			(hide yes)
			(effects
				(font
					(size 1.016 1.016)
					(thickness 0.1524)
				)
			)
		)
		(property "Device Type" "R402H16"
			(at 0.064008 -5.517896 0)
			(unlocked yes)
			(layer "F.Fab")
			(hide yes)
			(effects
				(font
					(size 1.016 1.016)
					(thickness 0.1524)
				)
			)
		)
		(duplicate_pad_numbers_are_jumpers no)
		(fp_line
			(start -0.508 -0.9398)
			(end -0.508 0.9398)
			(stroke
				(width 0.1524)
				(type default)
			)
			(layer "F.SilkS")
		)
		(fp_line
			(start 0.508 -0.9398)
			(end -0.508 -0.9398)
			(stroke
				(width 0.1524)
				(type default)
			)
			(layer "F.SilkS")
		)
		(fp_rect
			(start -0.508 0.9398)
			(end 0.508 -0.9398)
			(stroke
				(width 0)
				(type default)
			)
			(fill no)
			(layer "F.CrtYd")
		)
		(fp_rect
			(start -0.508 0.9398)
			(end 0.508 -0.9398)
			(stroke
				(width 0)
				(type default)
			)
			(fill no)
			(layer "F.Fab")
		)
		(pad "1" smd custom
			(at 0 -0.4445)
			(size 0.1397 0.1397)
			(layers "F.Cu" "F.Mask" "F.Paste")
			(net "P3V3_STBY")
			(options
				(clearance outline)
				(anchor circle)
			)
			(primitives
				(gr_poly
					(pts
						(arc
							(start -0.1778 -0.2794)
							(mid -0.249642 -0.249642)
							(end -0.2794 -0.1778)
						)
						(arc
							(start -0.2794 0.1778)
							(mid -0.249642 0.249642)
							(end -0.1778 0.2794)
						)
						(arc
							(start 0.1778 0.2794)
							(mid 0.249642 0.249642)
							(end 0.2794 0.1778)
						)
						(arc
							(start 0.2794 -0.1778)
							(mid 0.249642 -0.249642)
							(end 0.1778 -0.2794)
						)
					)
					(width 0)
					(fill yes)
				)
			)
		)
		(pad "2" smd custom
			(at 0 0.4445)
			(size 0.1397 0.1397)
			(layers "F.Cu" "F.Mask" "F.Paste")
			(net "MAC2_TXD0")
			(options
				(clearance outline)
				(anchor circle)
			)
			(primitives
				(gr_poly
					(pts
						(arc
							(start -0.1778 -0.2794)
							(mid -0.249642 -0.249642)
							(end -0.2794 -0.1778)
						)
						(arc
							(start -0.2794 0.1778)
							(mid -0.249642 0.249642)
							(end -0.1778 0.2794)
						)
						(arc
							(start 0.1778 0.2794)
							(mid 0.249642 0.249642)
							(end 0.2794 0.1778)
						)
						(arc
							(start 0.2794 -0.1778)
							(mid 0.249642 -0.249642)
							(end 0.1778 -0.2794)
						)
					)
					(width 0)
					(fill yes)
				)
			)
		)
	)
	(footprint ""
		(layer "F.Cu")
		(at 56.362092 -157.129988 90)
		(property "Reference" "TP53"
			(at 0 0 90)
			(layer "F.SilkS")
			(hide yes)
			(effects
				(font
					(size 1.27 1.27)
				)
			)
		)
		(property "Value" "TPAD28-2-GP"
			(at -0.0127 -1.6637 90)
			(unlocked yes)
			(layer "F.Fab")
			(hide yes)
			(effects
				(font
					(size 1.016 1.016)
					(thickness 0.1524)
				)
			)
		)
		(property "Device Type" "TPAD28"
			(at -0.0127 -3.1877 90)
			(unlocked yes)
			(layer "F.Fab")
			(hide yes)
			(effects
				(font
					(size 1.016 1.016)
					(thickness 0.1524)
				)
			)
		)
		(duplicate_pad_numbers_are_jumpers no)
		(fp_poly
			(pts
				(arc
					(start 0 0.3556)
					(mid 0 -0.3556)
					(end 0 0.3556)
				)
			)
			(stroke
				(width 0)
				(type default)
			)
			(fill no)
			(layer "F.CrtYd")
		)
		(fp_poly
			(pts
				(arc
					(start 0 0.6096)
					(mid 0 -0.6096)
					(end 0 0.6096)
				)
			)
			(stroke
				(width 0)
				(type default)
			)
			(fill no)
			(layer "F.Fab")
		)
		(pad "1" smd circle
			(at 0 0 90)
			(size 0.7112 0.7112)
			(layers "F.Cu" "F.Mask" "F.Paste")
			(net "TP_BMC_GPIOT6")
		)
	)
	(footprint ""
		(layer "F.Cu")
		(at 31.70428 -186.992514 180)
		(property "Reference" "C173"
			(at 0 0 180)
			(layer "F.SilkS")
			(hide yes)
			(effects
				(font
					(size 1.27 1.27)
				)
			)
		)
		(property "Value" "SC10U16V5KX-7-GP-U"
			(at -0.0762 -6.1214 180)
			(unlocked yes)
			(layer "F.Fab")
			(hide yes)
			(effects
				(font
					(size 1.016 1.016)
					(thickness 0.1524)
				)
			)
		)
		(property "Device Type" "C805H58"
			(at -0.0762 -8.1534 180)
			(unlocked yes)
			(layer "F.Fab")
			(hide yes)
			(effects
				(font
					(size 1.016 1.016)
					(thickness 0.1524)
				)
			)
		)
		(duplicate_pad_numbers_are_jumpers no)
		(fp_line
			(start 0.635 0)
			(end -0.635 0)
			(stroke
				(width 0.508)
				(type default)
			)
			(layer "F.SilkS")
		)
		(fp_rect
			(start -0.9652 1.778)
			(end 0.9652 -1.778)
			(stroke
				(width 0)
				(type default)
			)
			(fill no)
			(layer "F.CrtYd")
		)
		(fp_poly
			(pts
				(xy -0.9652 -1.778) (xy 0.9652 -1.778) (xy 0.9652 1.778) (xy -0.9652 1.778)
			)
			(stroke
				(width 0)
				(type default)
			)
			(fill no)
			(layer "F.Fab")
		)
		(pad "1" smd rect
			(at 0 -0.9652 180)
			(size 1.397 1.143)
			(layers "F.Cu" "F.Mask" "F.Paste")
			(net "P12V_STBY_VIN_PU2")
		)
		(pad "2" smd rect
			(at 0 0.9652 180)
			(size 1.397 1.143)
			(layers "F.Cu" "F.Mask" "F.Paste")
			(net "GND")
		)
	)
	(footprint ""
		(layer "F.Cu")
		(at 83.82 -148.59 90)
		(property "Reference" "C37"
			(at 0 0 90)
			(layer "F.SilkS")
			(hide yes)
			(effects
				(font
					(size 1.27 1.27)
				)
			)
		)
		(property "Value" "SCD1U16V2KX-3GP"
			(at 1.1811 -2.7051 90)
			(unlocked yes)
			(layer "F.Fab")
			(hide yes)
			(effects
				(font
					(size 1.016 1.016)
					(thickness 0.1524)
				)
			)
		)
		(property "Device Type" "C402H22"
			(at 1.1811 -4.2291 90)
			(unlocked yes)
			(layer "F.Fab")
			(hide yes)
			(effects
				(font
					(size 1.016 1.016)
					(thickness 0.1524)
				)
			)
		)
		(duplicate_pad_numbers_are_jumpers no)
		(fp_rect
			(start -0.4318 0.9525)
			(end 0.4318 -0.9525)
			(stroke
				(width 0)
				(type default)
			)
			(fill no)
			(layer "F.CrtYd")
		)
		(fp_rect
			(start -0.4318 0.9525)
			(end 0.4318 -0.9525)
			(stroke
				(width 0)
				(type default)
			)
			(fill no)
			(layer "F.Fab")
		)
		(pad "1" smd custom
			(at 0 -0.4445 90)
			(size 0.1524 0.1524)
			(layers "F.Cu" "F.Mask" "F.Paste")
			(net "P3V3_STBY")
			(options
				(clearance outline)
				(anchor circle)
			)
			(primitives
				(gr_poly
					(pts
						(arc
							(start 0.3048 -0.2032)
							(mid 0.275042 -0.275042)
							(end 0.2032 -0.3048)
						)
						(arc
							(start -0.2032 -0.3048)
							(mid -0.275042 -0.275042)
							(end -0.3048 -0.2032)
						)
						(arc
							(start -0.3048 0.2032)
							(mid -0.275042 0.275042)
							(end -0.2032 0.3048)
						)
						(arc
							(start 0.2032 0.3048)
							(mid 0.275042 0.275042)
							(end 0.3048 0.2032)
						)
					)
					(width 0)
					(fill yes)
				)
			)
		)
		(pad "2" smd custom
			(at 0 0.4445 90)
			(size 0.1524 0.1524)
			(layers "F.Cu" "F.Mask" "F.Paste")
			(net "GND")
			(options
				(clearance outline)
				(anchor circle)
			)
			(primitives
				(gr_poly
					(pts
						(arc
							(start 0.3048 -0.2032)
							(mid 0.275042 -0.275042)
							(end 0.2032 -0.3048)
						)
						(arc
							(start -0.2032 -0.3048)
							(mid -0.275042 -0.275042)
							(end -0.3048 -0.2032)
						)
						(arc
							(start -0.3048 0.2032)
							(mid -0.275042 0.275042)
							(end -0.2032 0.3048)
						)
						(arc
							(start 0.2032 0.3048)
							(mid 0.275042 0.275042)
							(end 0.3048 0.2032)
						)
					)
					(width 0)
					(fill yes)
				)
			)
		)
	)
	(footprint ""
		(layer "F.Cu")
		(at 43.8658 -158.5976)
		(property "Reference" "R174"
			(at 0 0 0)
			(layer "F.SilkS")
			(hide yes)
			(effects
				(font
					(size 1.27 1.27)
				)
			)
		)
		(property "Value" "0R2J-2-GP"
			(at 0.064008 -3.993896 0)
			(unlocked yes)
			(layer "F.Fab")
			(hide yes)
			(effects
				(font
					(size 1.016 1.016)
					(thickness 0.1524)
				)
			)
		)
		(property "Device Type" "R402H16"
			(at 0.064008 -5.517896 0)
			(unlocked yes)
			(layer "F.Fab")
			(hide yes)
			(effects
				(font
					(size 1.016 1.016)
					(thickness 0.1524)
				)
			)
		)
		(duplicate_pad_numbers_are_jumpers no)
		(fp_line
			(start -0.508 -0.9398)
			(end -0.508 0.9398)
			(stroke
				(width 0.1524)
				(type default)
			)
			(layer "F.SilkS")
		)
		(fp_line
			(start 0.508 -0.9398)
			(end -0.508 -0.9398)
			(stroke
				(width 0.1524)
				(type default)
			)
			(layer "F.SilkS")
		)
		(fp_rect
			(start -0.508 0.9398)
			(end 0.508 -0.9398)
			(stroke
				(width 0)
				(type default)
			)
			(fill no)
			(layer "F.CrtYd")
		)
		(fp_rect
			(start -0.508 0.9398)
			(end 0.508 -0.9398)
			(stroke
				(width 0)
				(type default)
			)
			(fill no)
			(layer "F.Fab")
		)
		(pad "1" smd custom
			(at 0 -0.4445)
			(size 0.1397 0.1397)
			(layers "F.Cu" "F.Mask" "F.Paste")
			(net "I2C_M2_1_SDA")
			(options
				(clearance outline)
				(anchor circle)
			)
			(primitives
				(gr_poly
					(pts
						(arc
							(start -0.1778 -0.2794)
							(mid -0.249642 -0.249642)
							(end -0.2794 -0.1778)
						)
						(arc
							(start -0.2794 0.1778)
							(mid -0.249642 0.249642)
							(end -0.1778 0.2794)
						)
						(arc
							(start 0.1778 0.2794)
							(mid 0.249642 0.249642)
							(end 0.2794 0.1778)
						)
						(arc
							(start 0.2794 -0.1778)
							(mid 0.249642 -0.249642)
							(end 0.1778 -0.2794)
						)
					)
					(width 0)
					(fill yes)
				)
			)
		)
		(pad "2" smd custom
			(at 0 0.4445)
			(size 0.1397 0.1397)
			(layers "F.Cu" "F.Mask" "F.Paste")
			(net "BMC_SMB8_DAT")
			(options
				(clearance outline)
				(anchor circle)
			)
			(primitives
				(gr_poly
					(pts
						(arc
							(start -0.1778 -0.2794)
							(mid -0.249642 -0.249642)
							(end -0.2794 -0.1778)
						)
						(arc
							(start -0.2794 0.1778)
							(mid -0.249642 0.249642)
							(end -0.1778 0.2794)
						)
						(arc
							(start 0.1778 0.2794)
							(mid 0.249642 0.249642)
							(end 0.2794 0.1778)
						)
						(arc
							(start 0.2794 -0.1778)
							(mid 0.249642 -0.249642)
							(end 0.1778 -0.2794)
						)
					)
					(width 0)
					(fill yes)
				)
			)
		)
	)
	(footprint ""
		(layer "F.Cu")
		(at 51.8414 -162.4838)
		(property "Reference" "R409"
			(at 0 0 0)
			(layer "F.SilkS")
			(hide yes)
			(effects
				(font
					(size 1.27 1.27)
				)
			)
		)
		(property "Value" "1K4R2F-1-GP"
			(at 0.064008 -3.993896 0)
			(unlocked yes)
			(layer "F.Fab")
			(hide yes)
			(effects
				(font
					(size 1.016 1.016)
					(thickness 0.1524)
				)
			)
		)
		(property "Device Type" "R402H16"
			(at 0.064008 -5.517896 0)
			(unlocked yes)
			(layer "F.Fab")
			(hide yes)
			(effects
				(font
					(size 1.016 1.016)
					(thickness 0.1524)
				)
			)
		)
		(duplicate_pad_numbers_are_jumpers no)
		(fp_line
			(start -0.508 -0.9398)
			(end -0.508 0.9398)
			(stroke
				(width 0.1524)
				(type default)
			)
			(layer "F.SilkS")
		)
		(fp_line
			(start 0.508 -0.9398)
			(end -0.508 -0.9398)
			(stroke
				(width 0.1524)
				(type default)
			)
			(layer "F.SilkS")
		)
		(fp_rect
			(start -0.508 0.9398)
			(end 0.508 -0.9398)
			(stroke
				(width 0)
				(type default)
			)
			(fill no)
			(layer "F.CrtYd")
		)
		(fp_rect
			(start -0.508 0.9398)
			(end 0.508 -0.9398)
			(stroke
				(width 0)
				(type default)
			)
			(fill no)
			(layer "F.Fab")
		)
		(pad "1" smd custom
			(at 0 -0.4445)
			(size 0.1397 0.1397)
			(layers "F.Cu" "F.Mask" "F.Paste")
			(net "P3V3")
			(options
				(clearance outline)
				(anchor circle)
			)
			(primitives
				(gr_poly
					(pts
						(arc
							(start -0.1778 -0.2794)
							(mid -0.249642 -0.249642)
							(end -0.2794 -0.1778)
						)
						(arc
							(start -0.2794 0.1778)
							(mid -0.249642 0.249642)
							(end -0.1778 0.2794)
						)
						(arc
							(start 0.1778 0.2794)
							(mid 0.249642 0.249642)
							(end 0.2794 0.1778)
						)
						(arc
							(start 0.2794 -0.1778)
							(mid 0.249642 -0.249642)
							(end 0.1778 -0.2794)
						)
					)
					(width 0)
					(fill yes)
				)
			)
		)
		(pad "2" smd custom
			(at 0 0.4445)
			(size 0.1397 0.1397)
			(layers "F.Cu" "F.Mask" "F.Paste")
			(net "ADC_P3V3")
			(options
				(clearance outline)
				(anchor circle)
			)
			(primitives
				(gr_poly
					(pts
						(arc
							(start -0.1778 -0.2794)
							(mid -0.249642 -0.249642)
							(end -0.2794 -0.1778)
						)
						(arc
							(start -0.2794 0.1778)
							(mid -0.249642 0.249642)
							(end -0.1778 0.2794)
						)
						(arc
							(start 0.1778 0.2794)
							(mid 0.249642 0.249642)
							(end 0.2794 0.1778)
						)
						(arc
							(start 0.2794 -0.1778)
							(mid 0.249642 -0.249642)
							(end 0.1778 -0.2794)
						)
					)
					(width 0)
					(fill yes)
				)
			)
		)
	)
	(footprint ""
		(layer "F.Cu")
		(at 66.802 -172.085)
		(property "Reference" "C34"
			(at 0 0 0)
			(layer "F.SilkS")
			(hide yes)
			(effects
				(font
					(size 1.27 1.27)
				)
			)
		)
		(property "Value" "SCD1U16V2KX-3GP"
			(at 1.1811 -2.7051 0)
			(unlocked yes)
			(layer "F.Fab")
			(hide yes)
			(effects
				(font
					(size 1.016 1.016)
					(thickness 0.1524)
				)
			)
		)
		(property "Device Type" "C402H22"
			(at 1.1811 -4.2291 0)
			(unlocked yes)
			(layer "F.Fab")
			(hide yes)
			(effects
				(font
					(size 1.016 1.016)
					(thickness 0.1524)
				)
			)
		)
		(duplicate_pad_numbers_are_jumpers no)
		(fp_rect
			(start -0.4318 0.9525)
			(end 0.4318 -0.9525)
			(stroke
				(width 0)
				(type default)
			)
			(fill no)
			(layer "F.CrtYd")
		)
		(fp_rect
			(start -0.4318 0.9525)
			(end 0.4318 -0.9525)
			(stroke
				(width 0)
				(type default)
			)
			(fill no)
			(layer "F.Fab")
		)
		(pad "1" smd custom
			(at 0 -0.4445)
			(size 0.1524 0.1524)
			(layers "F.Cu" "F.Mask" "F.Paste")
			(net "P5V_STBY")
			(options
				(clearance outline)
				(anchor circle)
			)
			(primitives
				(gr_poly
					(pts
						(arc
							(start 0.3048 -0.2032)
							(mid 0.275042 -0.275042)
							(end 0.2032 -0.3048)
						)
						(arc
							(start -0.2032 -0.3048)
							(mid -0.275042 -0.275042)
							(end -0.3048 -0.2032)
						)
						(arc
							(start -0.3048 0.2032)
							(mid -0.275042 0.275042)
							(end -0.2032 0.3048)
						)
						(arc
							(start 0.2032 0.3048)
							(mid 0.275042 0.275042)
							(end 0.3048 0.2032)
						)
					)
					(width 0)
					(fill yes)
				)
			)
		)
		(pad "2" smd custom
			(at 0 0.4445)
			(size 0.1524 0.1524)
			(layers "F.Cu" "F.Mask" "F.Paste")
			(net "GND")
			(options
				(clearance outline)
				(anchor circle)
			)
			(primitives
				(gr_poly
					(pts
						(arc
							(start 0.3048 -0.2032)
							(mid 0.275042 -0.275042)
							(end 0.2032 -0.3048)
						)
						(arc
							(start -0.2032 -0.3048)
							(mid -0.275042 -0.275042)
							(end -0.3048 -0.2032)
						)
						(arc
							(start -0.3048 0.2032)
							(mid -0.275042 0.275042)
							(end -0.2032 0.3048)
						)
						(arc
							(start 0.2032 0.3048)
							(mid 0.275042 0.275042)
							(end 0.3048 0.2032)
						)
					)
					(width 0)
					(fill yes)
				)
			)
		)
	)
	(footprint ""
		(layer "F.Cu")
		(at 206.000096 -6.199886)
		(property "Reference" "LED3"
			(at 0 0 0)
			(layer "F.SilkS")
			(hide yes)
			(effects
				(font
					(size 1.27 1.27)
				)
			)
		)
		(property "Value" "LED-BY-14-GP"
			(at -4.7752 -2.1844 0)
			(unlocked yes)
			(layer "F.Fab")
			(hide yes)
			(effects
				(font
					(size 1.016 1.016)
					(thickness 0.1524)
				)
			)
		)
		(property "Device Type" "LED-100-3PH206"
			(at -4.7752 -3.7084 0)
			(unlocked yes)
			(layer "F.Fab")
			(hide yes)
			(effects
				(font
					(size 1.016 1.016)
					(thickness 0.1524)
				)
			)
		)
		(duplicate_pad_numbers_are_jumpers no)
		(fp_line
			(start -3.7592 -1.524)
			(end 3.7592 -1.524)
			(stroke
				(width 0.1524)
				(type default)
			)
			(layer "F.SilkS")
		)
		(fp_line
			(start -3.7592 8.0264)
			(end -3.7592 -1.524)
			(stroke
				(width 0.1524)
				(type default)
			)
			(layer "F.SilkS")
		)
		(fp_line
			(start -1.75387 1.04394)
			(end -1.75387 3.63474)
			(stroke
				(width 0.1524)
				(type default)
			)
			(layer "F.SilkS")
		)
		(fp_line
			(start -1.75387 2.33934)
			(end -3.45567 2.33934)
			(stroke
				(width 0.1524)
				(type default)
			)
			(layer "F.SilkS")
		)
		(fp_line
			(start -1.75387 3.63474)
			(end -0.45847 2.33934)
			(stroke
				(width 0.1524)
				(type default)
			)
			(layer "F.SilkS")
		)
		(fp_line
			(start -0.45847 2.33934)
			(end -1.75387 1.04394)
			(stroke
				(width 0.1524)
				(type default)
			)
			(layer "F.SilkS")
		)
		(fp_line
			(start -0.45847 2.33934)
			(end 0.58293 2.33934)
			(stroke
				(width 0.1524)
				(type default)
			)
			(layer "F.SilkS")
		)
		(fp_line
			(start -0.45847 3.05054)
			(end -0.45847 1.42494)
			(stroke
				(width 0.1524)
				(type default)
			)
			(layer "F.SilkS")
		)
		(fp_line
			(start 0.58293 2.33934)
			(end 1.87833 1.04394)
			(stroke
				(width 0.1524)
				(type default)
			)
			(layer "F.SilkS")
		)
		(fp_line
			(start 0.58293 3.05054)
			(end 0.58293 1.42494)
			(stroke
				(width 0.1524)
				(type default)
			)
			(layer "F.SilkS")
		)
		(fp_line
			(start 1.87833 1.04394)
			(end 1.87833 3.63474)
			(stroke
				(width 0.1524)
				(type default)
			)
			(layer "F.SilkS")
		)
		(fp_line
			(start 1.87833 2.33934)
			(end 2.81813 2.33934)
			(stroke
				(width 0.1524)
				(type default)
			)
			(layer "F.SilkS")
		)
		(fp_line
			(start 1.87833 3.63474)
			(end 0.58293 2.33934)
			(stroke
				(width 0.1524)
				(type default)
			)
			(layer "F.SilkS")
		)
		(fp_line
			(start 3.7592 -1.524)
			(end 3.7592 8.0264)
			(stroke
				(width 0.1524)
				(type default)
			)
			(layer "F.SilkS")
		)
		(fp_line
			(start 3.7592 8.0264)
			(end -3.7592 8.0264)
			(stroke
				(width 0.1524)
				(type default)
			)
			(layer "F.SilkS")
		)
		(fp_circle
			(center -2.54 0)
			(end -1.5494 0)
			(stroke
				(width 0.3048)
				(type default)
			)
			(fill no)
			(layer "F.SilkS")
		)
		(fp_circle
			(center 0 0)
			(end 0.9906 0)
			(stroke
				(width 0.3048)
				(type default)
			)
			(fill no)
			(layer "F.SilkS")
		)
		(fp_circle
			(center 2.54 0)
			(end 3.5306 0)
			(stroke
				(width 0.3048)
				(type default)
			)
			(fill no)
			(layer "F.SilkS")
		)
		(fp_rect
			(start -3.5052 7.7724)
			(end 3.5052 -1.27)
			(stroke
				(width 0)
				(type default)
			)
			(fill no)
			(layer "F.CrtYd")
		)
		(fp_poly
			(pts
				(xy -4.0132 8.2804) (xy -4.0132 -1.778) (xy -3.5052 -1.778) (xy -3.5052 7.7724) (xy 3.5052 7.7724)
				(xy 3.5052 -1.27) (xy -3.50012 -1.27) (xy -3.50012 -1.778) (xy 4.0132 -1.778) (xy 4.0132 8.2804)
			)
			(stroke
				(width 0)
				(type default)
			)
			(fill no)
			(layer "F.CrtYd")
		)
		(fp_rect
			(start -4.0132 8.2804)
			(end 4.0132 -1.778)
			(stroke
				(width 0)
				(type default)
			)
			(fill no)
			(layer "F.Fab")
		)
		(pad "1" thru_hole circle
			(at -2.54 0)
			(size 1.27 1.27)
			(drill 0.889)
			(layers "*.Cu" "*.Mask")
			(remove_unused_layers no)
			(net "ML_PWR_BLUE_LED_R")
			(clearance 0.1651)
			(thermal_gap 0.1651)
		)
		(pad "2" thru_hole circle
			(at 0 0)
			(size 1.27 1.27)
			(drill 0.889)
			(layers "*.Cu" "*.Mask")
			(remove_unused_layers no)
			(net "GND")
			(clearance 0.1651)
			(thermal_gap 0.1651)
		)
		(pad "3" thru_hole circle
			(at 2.54 0)
			(size 1.27 1.27)
			(drill 0.889)
			(layers "*.Cu" "*.Mask")
			(remove_unused_layers no)
			(net "ML_PWR_YELLOW_LED_R")
			(clearance 0.1651)
			(thermal_gap 0.1651)
		)
	)
	(footprint ""
		(layer "F.Cu")
		(at 147.585938 -9.450578 -90)
		(property "Reference" "R521"
			(at 0 0 270)
			(layer "F.SilkS")
			(hide yes)
			(effects
				(font
					(size 1.27 1.27)
				)
			)
		)
		(property "Value" "15KR2F-GP"
			(at 0.064008 -3.993896 270)
			(unlocked yes)
			(layer "F.Fab")
			(hide yes)
			(effects
				(font
					(size 1.016 1.016)
					(thickness 0.1524)
				)
			)
		)
		(property "Device Type" "R402H16"
			(at 0.064008 -5.517896 270)
			(unlocked yes)
			(layer "F.Fab")
			(hide yes)
			(effects
				(font
					(size 1.016 1.016)
					(thickness 0.1524)
				)
			)
		)
		(duplicate_pad_numbers_are_jumpers no)
		(fp_line
			(start -0.508 -0.9398)
			(end -0.508 0.9398)
			(stroke
				(width 0.1524)
				(type default)
			)
			(layer "F.SilkS")
		)
		(fp_line
			(start 0.508 -0.9398)
			(end -0.508 -0.9398)
			(stroke
				(width 0.1524)
				(type default)
			)
			(layer "F.SilkS")
		)
		(fp_rect
			(start -0.508 0.9398)
			(end 0.508 -0.9398)
			(stroke
				(width 0)
				(type default)
			)
			(fill no)
			(layer "F.CrtYd")
		)
		(fp_rect
			(start -0.508 0.9398)
			(end 0.508 -0.9398)
			(stroke
				(width 0)
				(type default)
			)
			(fill no)
			(layer "F.Fab")
		)
		(pad "1" smd custom
			(at 0 -0.4445 270)
			(size 0.1397 0.1397)
			(layers "F.Cu" "F.Mask" "F.Paste")
			(net "PWRGD_P1V8_STBY")
			(options
				(clearance outline)
				(anchor circle)
			)
			(primitives
				(gr_poly
					(pts
						(arc
							(start -0.1778 -0.2794)
							(mid -0.249642 -0.249642)
							(end -0.2794 -0.1778)
						)
						(arc
							(start -0.2794 0.1778)
							(mid -0.249642 0.249642)
							(end -0.1778 0.2794)
						)
						(arc
							(start 0.1778 0.2794)
							(mid 0.249642 0.249642)
							(end 0.2794 0.1778)
						)
						(arc
							(start 0.2794 -0.1778)
							(mid 0.249642 -0.249642)
							(end 0.1778 -0.2794)
						)
					)
					(width 0)
					(fill yes)
				)
			)
		)
		(pad "2" smd custom
			(at 0 0.4445 270)
			(size 0.1397 0.1397)
			(layers "F.Cu" "F.Mask" "F.Paste")
			(net "GND")
			(options
				(clearance outline)
				(anchor circle)
			)
			(primitives
				(gr_poly
					(pts
						(arc
							(start -0.1778 -0.2794)
							(mid -0.249642 -0.249642)
							(end -0.2794 -0.1778)
						)
						(arc
							(start -0.2794 0.1778)
							(mid -0.249642 0.249642)
							(end -0.1778 0.2794)
						)
						(arc
							(start 0.1778 0.2794)
							(mid 0.249642 0.249642)
							(end 0.2794 0.1778)
						)
						(arc
							(start 0.2794 -0.1778)
							(mid 0.249642 -0.249642)
							(end 0.1778 -0.2794)
						)
					)
					(width 0)
					(fill yes)
				)
			)
		)
	)
	(footprint ""
		(layer "F.Cu")
		(at 79.99984 -120.000014)
		(property "Reference" ""
			(at 0 0 0)
			(layer "F.SilkS")
			(hide yes)
			(effects
				(font
					(size 1.27 1.27)
				)
			)
		)
		(property "Value" "*"
			(at -6.38175 0.19685 0)
			(unlocked yes)
			(layer "F.Fab")
			(hide yes)
			(effects
				(font
					(size 1.016 1.016)
					(thickness 0.1524)
				)
			)
		)
		(duplicate_pad_numbers_are_jumpers no)
		(fp_poly
			(pts
				(arc
					(start 5.0673 0)
					(mid -5.0673 0)
					(end 5.0673 0)
				)
			)
			(stroke
				(width 0)
				(type default)
			)
			(fill no)
			(layer "B.CrtYd")
		)
		(fp_poly
			(pts
				(arc
					(start 5.0673 0)
					(mid -5.0673 0)
					(end 5.0673 0)
				)
			)
			(stroke
				(width 0)
				(type default)
			)
			(fill no)
			(layer "F.CrtYd")
		)
		(fp_poly
			(pts
				(arc
					(start 5.0673 0)
					(mid -5.0673 0)
					(end 5.0673 0)
				)
			)
			(stroke
				(width 0)
				(type default)
			)
			(fill no)
			(layer "B.Fab")
		)
		(fp_poly
			(pts
				(arc
					(start 5.0673 0)
					(mid -5.0673 0)
					(end 5.0673 0)
				)
			)
			(stroke
				(width 0)
				(type default)
			)
			(fill no)
			(layer "F.Fab")
		)
		(pad "1" thru_hole circle
			(at 0 0)
			(size 9.525 9.525)
			(drill 3.5052)
			(layers "*.Cu" "*.Mask")
			(remove_unused_layers no)
			(net "Net_40")
			(clearance -2.5019)
			(thermal_gap 0.3048)
			(padstack
				(mode front_inner_back)
				(layer "Inner"
					(shape circle)
					(size 3.9116 3.9116)
					(clearance 0.3048)
				)
				(layer "B.Cu"
					(shape circle)
					(size 9.525 9.525)
					(clearance -2.5019)
				)
			)
		)
	)
	(footprint ""
		(layer "F.Cu")
		(at 10.529316 -172.6565 -90)
		(property "Reference" "R535"
			(at 0 0 270)
			(layer "F.SilkS")
			(hide yes)
			(effects
				(font
					(size 1.27 1.27)
				)
			)
		)
		(property "Value" "0R2J-2-GP"
			(at 0.064008 -3.993896 270)
			(unlocked yes)
			(layer "F.Fab")
			(hide yes)
			(effects
				(font
					(size 1.016 1.016)
					(thickness 0.1524)
				)
			)
		)
		(property "Device Type" "R402H16"
			(at 0.064008 -5.517896 270)
			(unlocked yes)
			(layer "F.Fab")
			(hide yes)
			(effects
				(font
					(size 1.016 1.016)
					(thickness 0.1524)
				)
			)
		)
		(duplicate_pad_numbers_are_jumpers no)
		(fp_line
			(start -0.508 -0.9398)
			(end -0.508 0.9398)
			(stroke
				(width 0.1524)
				(type default)
			)
			(layer "F.SilkS")
		)
		(fp_line
			(start 0.508 -0.9398)
			(end -0.508 -0.9398)
			(stroke
				(width 0.1524)
				(type default)
			)
			(layer "F.SilkS")
		)
		(fp_rect
			(start -0.508 0.9398)
			(end 0.508 -0.9398)
			(stroke
				(width 0)
				(type default)
			)
			(fill no)
			(layer "F.CrtYd")
		)
		(fp_rect
			(start -0.508 0.9398)
			(end 0.508 -0.9398)
			(stroke
				(width 0)
				(type default)
			)
			(fill no)
			(layer "F.Fab")
		)
		(pad "1" smd custom
			(at 0 -0.4445 270)
			(size 0.1397 0.1397)
			(layers "F.Cu" "F.Mask" "F.Paste")
			(net "TPS74801_P1V2_STBY_EN")
			(options
				(clearance outline)
				(anchor circle)
			)
			(primitives
				(gr_poly
					(pts
						(arc
							(start -0.1778 -0.2794)
							(mid -0.249642 -0.249642)
							(end -0.2794 -0.1778)
						)
						(arc
							(start -0.2794 0.1778)
							(mid -0.249642 0.249642)
							(end -0.1778 0.2794)
						)
						(arc
							(start 0.1778 0.2794)
							(mid 0.249642 0.249642)
							(end 0.2794 0.1778)
						)
						(arc
							(start 0.2794 -0.1778)
							(mid 0.249642 -0.249642)
							(end 0.1778 -0.2794)
						)
					)
					(width 0)
					(fill yes)
				)
			)
		)
		(pad "2" smd custom
			(at 0 0.4445 270)
			(size 0.1397 0.1397)
			(layers "F.Cu" "F.Mask" "F.Paste")
			(net "PWRGD_P1V8_STBY")
			(options
				(clearance outline)
				(anchor circle)
			)
			(primitives
				(gr_poly
					(pts
						(arc
							(start -0.1778 -0.2794)
							(mid -0.249642 -0.249642)
							(end -0.2794 -0.1778)
						)
						(arc
							(start -0.2794 0.1778)
							(mid -0.249642 0.249642)
							(end -0.1778 0.2794)
						)
						(arc
							(start 0.1778 0.2794)
							(mid 0.249642 0.249642)
							(end 0.2794 0.1778)
						)
						(arc
							(start 0.2794 -0.1778)
							(mid 0.249642 -0.249642)
							(end 0.1778 -0.2794)
						)
					)
					(width 0)
					(fill yes)
				)
			)
		)
	)
	(footprint ""
		(layer "F.Cu")
		(at 62.214252 -134.239254 -90)
		(property "Reference" "R343"
			(at 0 0 270)
			(layer "F.SilkS")
			(hide yes)
			(effects
				(font
					(size 1.27 1.27)
				)
			)
		)
		(property "Value" "0R2J-2-GP"
			(at 0.064008 -3.993896 270)
			(unlocked yes)
			(layer "F.Fab")
			(hide yes)
			(effects
				(font
					(size 1.016 1.016)
					(thickness 0.1524)
				)
			)
		)
		(property "Device Type" "R402H16"
			(at 0.064008 -5.517896 270)
			(unlocked yes)
			(layer "F.Fab")
			(hide yes)
			(effects
				(font
					(size 1.016 1.016)
					(thickness 0.1524)
				)
			)
		)
		(duplicate_pad_numbers_are_jumpers no)
		(fp_line
			(start -0.508 -0.9398)
			(end -0.508 0.9398)
			(stroke
				(width 0.1524)
				(type default)
			)
			(layer "F.SilkS")
		)
		(fp_line
			(start 0.508 -0.9398)
			(end -0.508 -0.9398)
			(stroke
				(width 0.1524)
				(type default)
			)
			(layer "F.SilkS")
		)
		(fp_rect
			(start -0.508 0.9398)
			(end 0.508 -0.9398)
			(stroke
				(width 0)
				(type default)
			)
			(fill no)
			(layer "F.CrtYd")
		)
		(fp_rect
			(start -0.508 0.9398)
			(end 0.508 -0.9398)
			(stroke
				(width 0)
				(type default)
			)
			(fill no)
			(layer "F.Fab")
		)
		(pad "1" smd custom
			(at 0 -0.4445 270)
			(size 0.1397 0.1397)
			(layers "F.Cu" "F.Mask" "F.Paste")
			(net "COMP_SPARE_0")
			(options
				(clearance outline)
				(anchor circle)
			)
			(primitives
				(gr_poly
					(pts
						(arc
							(start -0.1778 -0.2794)
							(mid -0.249642 -0.249642)
							(end -0.2794 -0.1778)
						)
						(arc
							(start -0.2794 0.1778)
							(mid -0.249642 0.249642)
							(end -0.1778 0.2794)
						)
						(arc
							(start 0.1778 0.2794)
							(mid 0.249642 0.249642)
							(end 0.2794 0.1778)
						)
						(arc
							(start 0.2794 -0.1778)
							(mid 0.249642 -0.249642)
							(end 0.1778 -0.2794)
						)
					)
					(width 0)
					(fill yes)
				)
			)
		)
		(pad "2" smd custom
			(at 0 0.4445 270)
			(size 0.1397 0.1397)
			(layers "F.Cu" "F.Mask" "F.Paste")
			(net "COMP_SPARE_0_R")
			(options
				(clearance outline)
				(anchor circle)
			)
			(primitives
				(gr_poly
					(pts
						(arc
							(start -0.1778 -0.2794)
							(mid -0.249642 -0.249642)
							(end -0.2794 -0.1778)
						)
						(arc
							(start -0.2794 0.1778)
							(mid -0.249642 0.249642)
							(end -0.1778 0.2794)
						)
						(arc
							(start 0.1778 0.2794)
							(mid 0.249642 0.249642)
							(end 0.2794 0.1778)
						)
						(arc
							(start 0.2794 -0.1778)
							(mid 0.249642 -0.249642)
							(end 0.1778 -0.2794)
						)
					)
					(width 0)
					(fill yes)
				)
			)
		)
	)
	(footprint ""
		(layer "F.Cu")
		(at 81.788 -163.5252)
		(property "Reference" "C242"
			(at 0 0 0)
			(layer "F.SilkS")
			(hide yes)
			(effects
				(font
					(size 1.27 1.27)
				)
			)
		)
		(property "Value" "SCD1U16V2KX-3GP"
			(at 1.1811 -2.7051 0)
			(unlocked yes)
			(layer "F.Fab")
			(hide yes)
			(effects
				(font
					(size 1.016 1.016)
					(thickness 0.1524)
				)
			)
		)
		(property "Device Type" "C402H22"
			(at 1.1811 -4.2291 0)
			(unlocked yes)
			(layer "F.Fab")
			(hide yes)
			(effects
				(font
					(size 1.016 1.016)
					(thickness 0.1524)
				)
			)
		)
		(duplicate_pad_numbers_are_jumpers no)
		(fp_rect
			(start -0.4318 0.9525)
			(end 0.4318 -0.9525)
			(stroke
				(width 0)
				(type default)
			)
			(fill no)
			(layer "F.CrtYd")
		)
		(fp_rect
			(start -0.4318 0.9525)
			(end 0.4318 -0.9525)
			(stroke
				(width 0)
				(type default)
			)
			(fill no)
			(layer "F.Fab")
		)
		(pad "1" smd custom
			(at 0 -0.4445)
			(size 0.1524 0.1524)
			(layers "F.Cu" "F.Mask" "F.Paste")
			(net "P1V8_STBY")
			(options
				(clearance outline)
				(anchor circle)
			)
			(primitives
				(gr_poly
					(pts
						(arc
							(start 0.3048 -0.2032)
							(mid 0.275042 -0.275042)
							(end 0.2032 -0.3048)
						)
						(arc
							(start -0.2032 -0.3048)
							(mid -0.275042 -0.275042)
							(end -0.3048 -0.2032)
						)
						(arc
							(start -0.3048 0.2032)
							(mid -0.275042 0.275042)
							(end -0.2032 0.3048)
						)
						(arc
							(start 0.2032 0.3048)
							(mid 0.275042 0.275042)
							(end 0.3048 0.2032)
						)
					)
					(width 0)
					(fill yes)
				)
			)
		)
		(pad "2" smd custom
			(at 0 0.4445)
			(size 0.1524 0.1524)
			(layers "F.Cu" "F.Mask" "F.Paste")
			(net "GND")
			(options
				(clearance outline)
				(anchor circle)
			)
			(primitives
				(gr_poly
					(pts
						(arc
							(start 0.3048 -0.2032)
							(mid 0.275042 -0.275042)
							(end 0.2032 -0.3048)
						)
						(arc
							(start -0.2032 -0.3048)
							(mid -0.275042 -0.275042)
							(end -0.3048 -0.2032)
						)
						(arc
							(start -0.3048 0.2032)
							(mid -0.275042 0.275042)
							(end -0.2032 0.3048)
						)
						(arc
							(start 0.2032 0.3048)
							(mid 0.275042 0.275042)
							(end 0.3048 0.2032)
						)
					)
					(width 0)
					(fill yes)
				)
			)
		)
	)
	(footprint ""
		(layer "F.Cu")
		(at 99.283774 -158.05531 90)
		(property "Reference" "R26"
			(at 0 0 90)
			(layer "F.SilkS")
			(hide yes)
			(effects
				(font
					(size 1.27 1.27)
				)
			)
		)
		(property "Value" "0R2J-2-GP"
			(at 0.064008 -3.993896 90)
			(unlocked yes)
			(layer "F.Fab")
			(hide yes)
			(effects
				(font
					(size 1.016 1.016)
					(thickness 0.1524)
				)
			)
		)
		(property "Device Type" "R402H16"
			(at 0.064008 -5.517896 90)
			(unlocked yes)
			(layer "F.Fab")
			(hide yes)
			(effects
				(font
					(size 1.016 1.016)
					(thickness 0.1524)
				)
			)
		)
		(duplicate_pad_numbers_are_jumpers no)
		(fp_line
			(start 0.508 -0.9398)
			(end -0.508 -0.9398)
			(stroke
				(width 0.1524)
				(type default)
			)
			(layer "F.SilkS")
		)
		(fp_line
			(start -0.508 -0.9398)
			(end -0.508 0.9398)
			(stroke
				(width 0.1524)
				(type default)
			)
			(layer "F.SilkS")
		)
		(fp_rect
			(start -0.508 0.9398)
			(end 0.508 -0.9398)
			(stroke
				(width 0)
				(type default)
			)
			(fill no)
			(layer "F.CrtYd")
		)
		(fp_rect
			(start -0.508 0.9398)
			(end 0.508 -0.9398)
			(stroke
				(width 0)
				(type default)
			)
			(fill no)
			(layer "F.Fab")
		)
		(pad "1" smd custom
			(at 0 -0.4445 90)
			(size 0.1397 0.1397)
			(layers "F.Cu" "F.Mask" "F.Paste")
			(net "USB_RESET_N")
			(options
				(clearance outline)
				(anchor circle)
			)
			(primitives
				(gr_poly
					(pts
						(arc
							(start -0.1778 -0.2794)
							(mid -0.249642 -0.249642)
							(end -0.2794 -0.1778)
						)
						(arc
							(start -0.2794 0.1778)
							(mid -0.249642 0.249642)
							(end -0.1778 0.2794)
						)
						(arc
							(start 0.1778 0.2794)
							(mid 0.249642 0.249642)
							(end 0.2794 0.1778)
						)
						(arc
							(start 0.2794 -0.1778)
							(mid 0.249642 -0.249642)
							(end 0.1778 -0.2794)
						)
					)
					(width 0)
					(fill yes)
				)
			)
		)
		(pad "2" smd custom
			(at 0 0.4445 90)
			(size 0.1397 0.1397)
			(layers "F.Cu" "F.Mask" "F.Paste")
			(net "PCIE_COMP_TO_IOM_RST_4")
			(options
				(clearance outline)
				(anchor circle)
			)
			(primitives
				(gr_poly
					(pts
						(arc
							(start -0.1778 -0.2794)
							(mid -0.249642 -0.249642)
							(end -0.2794 -0.1778)
						)
						(arc
							(start -0.2794 0.1778)
							(mid -0.249642 0.249642)
							(end -0.1778 0.2794)
						)
						(arc
							(start 0.1778 0.2794)
							(mid 0.249642 0.249642)
							(end 0.2794 0.1778)
						)
						(arc
							(start 0.2794 -0.1778)
							(mid 0.249642 -0.249642)
							(end 0.1778 -0.2794)
						)
					)
					(width 0)
					(fill yes)
				)
			)
		)
	)
	(footprint ""
		(layer "F.Cu")
		(at 95.1484 -148.6154)
		(property "Reference" "R41"
			(at 0 0 0)
			(layer "F.SilkS")
			(hide yes)
			(effects
				(font
					(size 1.27 1.27)
				)
			)
		)
		(property "Value" "4K7R2F-GP"
			(at 0.064008 -3.993896 0)
			(unlocked yes)
			(layer "F.Fab")
			(hide yes)
			(effects
				(font
					(size 1.016 1.016)
					(thickness 0.1524)
				)
			)
		)
		(property "Device Type" "R402H16"
			(at 0.064008 -5.517896 0)
			(unlocked yes)
			(layer "F.Fab")
			(hide yes)
			(effects
				(font
					(size 1.016 1.016)
					(thickness 0.1524)
				)
			)
		)
		(duplicate_pad_numbers_are_jumpers no)
		(fp_line
			(start -0.508 -0.9398)
			(end -0.508 0.9398)
			(stroke
				(width 0.1524)
				(type default)
			)
			(layer "F.SilkS")
		)
		(fp_line
			(start 0.508 -0.9398)
			(end -0.508 -0.9398)
			(stroke
				(width 0.1524)
				(type default)
			)
			(layer "F.SilkS")
		)
		(fp_rect
			(start -0.508 0.9398)
			(end 0.508 -0.9398)
			(stroke
				(width 0)
				(type default)
			)
			(fill no)
			(layer "F.CrtYd")
		)
		(fp_rect
			(start -0.508 0.9398)
			(end 0.508 -0.9398)
			(stroke
				(width 0)
				(type default)
			)
			(fill no)
			(layer "F.Fab")
		)
		(pad "1" smd custom
			(at 0 -0.4445)
			(size 0.1397 0.1397)
			(layers "F.Cu" "F.Mask" "F.Paste")
			(net "USB_EN_2")
			(options
				(clearance outline)
				(anchor circle)
			)
			(primitives
				(gr_poly
					(pts
						(arc
							(start -0.1778 -0.2794)
							(mid -0.249642 -0.249642)
							(end -0.2794 -0.1778)
						)
						(arc
							(start -0.2794 0.1778)
							(mid -0.249642 0.249642)
							(end -0.1778 0.2794)
						)
						(arc
							(start 0.1778 0.2794)
							(mid 0.249642 0.249642)
							(end 0.2794 0.1778)
						)
						(arc
							(start 0.2794 -0.1778)
							(mid 0.249642 -0.249642)
							(end 0.1778 -0.2794)
						)
					)
					(width 0)
					(fill yes)
				)
			)
		)
		(pad "2" smd custom
			(at 0 0.4445)
			(size 0.1397 0.1397)
			(layers "F.Cu" "F.Mask" "F.Paste")
			(net "GND")
			(options
				(clearance outline)
				(anchor circle)
			)
			(primitives
				(gr_poly
					(pts
						(arc
							(start -0.1778 -0.2794)
							(mid -0.249642 -0.249642)
							(end -0.2794 -0.1778)
						)
						(arc
							(start -0.2794 0.1778)
							(mid -0.249642 0.249642)
							(end -0.1778 0.2794)
						)
						(arc
							(start 0.1778 0.2794)
							(mid 0.249642 0.249642)
							(end 0.2794 0.1778)
						)
						(arc
							(start 0.2794 -0.1778)
							(mid 0.249642 -0.249642)
							(end 0.1778 -0.2794)
						)
					)
					(width 0)
					(fill yes)
				)
			)
		)
	)
	(footprint ""
		(layer "F.Cu")
		(at 8.8392 -139.573 90)
		(property "Reference" "R217"
			(at 0 0 90)
			(layer "F.SilkS")
			(hide yes)
			(effects
				(font
					(size 1.27 1.27)
				)
			)
		)
		(property "Value" "120R2F-GP"
			(at 0.064008 -3.993896 90)
			(unlocked yes)
			(layer "F.Fab")
			(hide yes)
			(effects
				(font
					(size 1.016 1.016)
					(thickness 0.1524)
				)
			)
		)
		(property "Device Type" "R402H16"
			(at 0.064008 -5.517896 90)
			(unlocked yes)
			(layer "F.Fab")
			(hide yes)
			(effects
				(font
					(size 1.016 1.016)
					(thickness 0.1524)
				)
			)
		)
		(duplicate_pad_numbers_are_jumpers no)
		(fp_line
			(start 0.508 -0.9398)
			(end -0.508 -0.9398)
			(stroke
				(width 0.1524)
				(type default)
			)
			(layer "F.SilkS")
		)
		(fp_line
			(start -0.508 -0.9398)
			(end -0.508 0.9398)
			(stroke
				(width 0.1524)
				(type default)
			)
			(layer "F.SilkS")
		)
		(fp_rect
			(start -0.508 0.9398)
			(end 0.508 -0.9398)
			(stroke
				(width 0)
				(type default)
			)
			(fill no)
			(layer "F.CrtYd")
		)
		(fp_rect
			(start -0.508 0.9398)
			(end 0.508 -0.9398)
			(stroke
				(width 0)
				(type default)
			)
			(fill no)
			(layer "F.Fab")
		)
		(pad "1" smd custom
			(at 0 -0.4445 90)
			(size 0.1397 0.1397)
			(layers "F.Cu" "F.Mask" "F.Paste")
			(net "GND")
			(options
				(clearance outline)
				(anchor circle)
			)
			(primitives
				(gr_poly
					(pts
						(arc
							(start -0.1778 -0.2794)
							(mid -0.249642 -0.249642)
							(end -0.2794 -0.1778)
						)
						(arc
							(start -0.2794 0.1778)
							(mid -0.249642 0.249642)
							(end -0.1778 0.2794)
						)
						(arc
							(start 0.1778 0.2794)
							(mid 0.249642 0.249642)
							(end 0.2794 0.1778)
						)
						(arc
							(start 0.2794 -0.1778)
							(mid 0.249642 -0.249642)
							(end 0.1778 -0.2794)
						)
					)
					(width 0)
					(fill yes)
				)
			)
		)
		(pad "2" smd custom
			(at 0 0.4445 90)
			(size 0.1397 0.1397)
			(layers "F.Cu" "F.Mask" "F.Paste")
			(net "MEMBG_0")
			(options
				(clearance outline)
				(anchor circle)
			)
			(primitives
				(gr_poly
					(pts
						(arc
							(start -0.1778 -0.2794)
							(mid -0.249642 -0.249642)
							(end -0.2794 -0.1778)
						)
						(arc
							(start -0.2794 0.1778)
							(mid -0.249642 0.249642)
							(end -0.1778 0.2794)
						)
						(arc
							(start 0.1778 0.2794)
							(mid 0.249642 0.249642)
							(end 0.2794 0.1778)
						)
						(arc
							(start 0.2794 -0.1778)
							(mid 0.249642 -0.249642)
							(end 0.1778 -0.2794)
						)
					)
					(width 0)
					(fill yes)
				)
			)
		)
	)
	(footprint ""
		(layer "F.Cu")
		(at 42.23512 -131.7498 180)
		(property "Reference" "R263"
			(at 0 0 180)
			(layer "F.SilkS")
			(hide yes)
			(effects
				(font
					(size 1.27 1.27)
				)
			)
		)
		(property "Value" "4K7R2F-GP"
			(at 0.064008 -3.993896 180)
			(unlocked yes)
			(layer "F.Fab")
			(hide yes)
			(effects
				(font
					(size 1.016 1.016)
					(thickness 0.1524)
				)
			)
		)
		(property "Device Type" "R402H16"
			(at 0.064008 -5.517896 180)
			(unlocked yes)
			(layer "F.Fab")
			(hide yes)
			(effects
				(font
					(size 1.016 1.016)
					(thickness 0.1524)
				)
			)
		)
		(duplicate_pad_numbers_are_jumpers no)
		(fp_line
			(start 0.508 -0.9398)
			(end -0.508 -0.9398)
			(stroke
				(width 0.1524)
				(type default)
			)
			(layer "F.SilkS")
		)
		(fp_line
			(start -0.508 -0.9398)
			(end -0.508 0.9398)
			(stroke
				(width 0.1524)
				(type default)
			)
			(layer "F.SilkS")
		)
		(fp_rect
			(start -0.508 0.9398)
			(end 0.508 -0.9398)
			(stroke
				(width 0)
				(type default)
			)
			(fill no)
			(layer "F.CrtYd")
		)
		(fp_rect
			(start -0.508 0.9398)
			(end 0.508 -0.9398)
			(stroke
				(width 0)
				(type default)
			)
			(fill no)
			(layer "F.Fab")
		)
		(pad "1" smd custom
			(at 0 -0.4445 180)
			(size 0.1397 0.1397)
			(layers "F.Cu" "F.Mask" "F.Paste")
			(net "P3V3_STBY")
			(options
				(clearance outline)
				(anchor circle)
			)
			(primitives
				(gr_poly
					(pts
						(arc
							(start -0.1778 -0.2794)
							(mid -0.249642 -0.249642)
							(end -0.2794 -0.1778)
						)
						(arc
							(start -0.2794 0.1778)
							(mid -0.249642 0.249642)
							(end -0.1778 0.2794)
						)
						(arc
							(start 0.1778 0.2794)
							(mid 0.249642 0.249642)
							(end 0.2794 0.1778)
						)
						(arc
							(start 0.2794 -0.1778)
							(mid 0.249642 -0.249642)
							(end 0.1778 -0.2794)
						)
					)
					(width 0)
					(fill yes)
				)
			)
		)
		(pad "2" smd custom
			(at 0 0.4445 180)
			(size 0.1397 0.1397)
			(layers "F.Cu" "F.Mask" "F.Paste")
			(net "BMC_GPIOY1")
			(options
				(clearance outline)
				(anchor circle)
			)
			(primitives
				(gr_poly
					(pts
						(arc
							(start -0.1778 -0.2794)
							(mid -0.249642 -0.249642)
							(end -0.2794 -0.1778)
						)
						(arc
							(start -0.2794 0.1778)
							(mid -0.249642 0.249642)
							(end -0.1778 0.2794)
						)
						(arc
							(start 0.1778 0.2794)
							(mid 0.249642 0.249642)
							(end 0.2794 0.1778)
						)
						(arc
							(start 0.2794 -0.1778)
							(mid 0.249642 -0.249642)
							(end 0.1778 -0.2794)
						)
					)
					(width 0)
					(fill yes)
				)
			)
		)
	)
	(footprint ""
		(layer "F.Cu")
		(at 84.709 -29.21 180)
		(property "Reference" "L23"
			(at 0 0 180)
			(layer "F.SilkS")
			(hide yes)
			(effects
				(font
					(size 1.27 1.27)
				)
			)
		)
		(property "Value" "BLM21PG300SN-2GP"
			(at 0.0254 -5.6896 180)
			(unlocked yes)
			(layer "F.Fab")
			(hide yes)
			(effects
				(font
					(size 1.016 1.016)
					(thickness 0.1524)
				)
			)
		)
		(property "Device Type" "L20125H42"
			(at 0.0254 -7.5946 180)
			(unlocked yes)
			(layer "F.Fab")
			(hide yes)
			(effects
				(font
					(size 1.016 1.016)
					(thickness 0.1524)
				)
			)
		)
		(duplicate_pad_numbers_are_jumpers no)
		(fp_line
			(start 0.9144 1.7018)
			(end 0.9144 -1.7018)
			(stroke
				(width 0.1524)
				(type default)
			)
			(layer "F.SilkS")
		)
		(fp_line
			(start 0.9144 -1.7018)
			(end -0.9144 -1.7018)
			(stroke
				(width 0.1524)
				(type default)
			)
			(layer "F.SilkS")
		)
		(fp_line
			(start -0.9144 1.7018)
			(end 0.9144 1.7018)
			(stroke
				(width 0.1524)
				(type default)
			)
			(layer "F.SilkS")
		)
		(fp_line
			(start -0.9144 -1.7018)
			(end -0.9144 1.7018)
			(stroke
				(width 0.1524)
				(type default)
			)
			(layer "F.SilkS")
		)
		(fp_rect
			(start -1.0033 1.778)
			(end 1.0033 -1.778)
			(stroke
				(width 0)
				(type default)
			)
			(fill no)
			(layer "F.CrtYd")
		)
		(fp_poly
			(pts
				(xy -1.0033 -1.778) (xy 1.0033 -1.778) (xy 1.0033 1.778) (xy -1.0033 1.778)
			)
			(stroke
				(width 0)
				(type default)
			)
			(fill no)
			(layer "F.Fab")
		)
		(pad "1" smd rect
			(at 0 -0.9652 180)
			(size 1.397 1.143)
			(layers "F.Cu" "F.Mask" "F.Paste")
			(net "P5V_VBUS_CONN")
		)
		(pad "2" smd rect
			(at 0 0.9652 180)
			(size 1.397 1.143)
			(layers "F.Cu" "F.Mask" "F.Paste")
			(net "P5V_USB")
		)
	)
	(footprint ""
		(layer "F.Cu")
		(at 228.497638 -98.591878 180)
		(property "Reference" "L30"
			(at 0 0 180)
			(layer "F.SilkS")
			(hide yes)
			(effects
				(font
					(size 1.27 1.27)
				)
			)
		)
		(property "Value" "BLM21PG220SN1DGP"
			(at 0.0254 -5.6896 180)
			(unlocked yes)
			(layer "F.Fab")
			(hide yes)
			(effects
				(font
					(size 1.016 1.016)
					(thickness 0.1524)
				)
			)
		)
		(property "Device Type" "L20125H42"
			(at 0.0254 -7.5946 180)
			(unlocked yes)
			(layer "F.Fab")
			(hide yes)
			(effects
				(font
					(size 1.016 1.016)
					(thickness 0.1524)
				)
			)
		)
		(duplicate_pad_numbers_are_jumpers no)
		(fp_line
			(start 0.9144 1.7018)
			(end 0.9144 -1.7018)
			(stroke
				(width 0.1524)
				(type default)
			)
			(layer "F.SilkS")
		)
		(fp_line
			(start 0.9144 -1.7018)
			(end -0.9144 -1.7018)
			(stroke
				(width 0.1524)
				(type default)
			)
			(layer "F.SilkS")
		)
		(fp_line
			(start -0.9144 1.7018)
			(end 0.9144 1.7018)
			(stroke
				(width 0.1524)
				(type default)
			)
			(layer "F.SilkS")
		)
		(fp_line
			(start -0.9144 -1.7018)
			(end -0.9144 1.7018)
			(stroke
				(width 0.1524)
				(type default)
			)
			(layer "F.SilkS")
		)
		(fp_rect
			(start -1.0033 1.778)
			(end 1.0033 -1.778)
			(stroke
				(width 0)
				(type default)
			)
			(fill no)
			(layer "F.CrtYd")
		)
		(fp_poly
			(pts
				(xy -1.0033 -1.778) (xy 1.0033 -1.778) (xy 1.0033 1.778) (xy -1.0033 1.778)
			)
			(stroke
				(width 0)
				(type default)
			)
			(fill no)
			(layer "F.Fab")
		)
		(pad "1" smd rect
			(at 0 -0.9652 180)
			(size 1.397 1.143)
			(layers "F.Cu" "F.Mask" "F.Paste")
			(net "P12V_STBY")
		)
		(pad "2" smd rect
			(at 0 0.9652 180)
			(size 1.397 1.143)
			(layers "F.Cu" "F.Mask" "F.Paste")
			(net "P12V_STBY_VIN_U81")
		)
	)
	(footprint ""
		(layer "F.Cu")
		(at 124.841 -7.62 -90)
		(property "Reference" "R438"
			(at 0 0 270)
			(layer "F.SilkS")
			(hide yes)
			(effects
				(font
					(size 1.27 1.27)
				)
			)
		)
		(property "Value" "10KR2J-3-GP"
			(at 0.064008 -3.993896 270)
			(unlocked yes)
			(layer "F.Fab")
			(hide yes)
			(effects
				(font
					(size 1.016 1.016)
					(thickness 0.1524)
				)
			)
		)
		(property "Device Type" "R402H16"
			(at 0.064008 -5.517896 270)
			(unlocked yes)
			(layer "F.Fab")
			(hide yes)
			(effects
				(font
					(size 1.016 1.016)
					(thickness 0.1524)
				)
			)
		)
		(duplicate_pad_numbers_are_jumpers no)
		(fp_line
			(start -0.508 -0.9398)
			(end -0.508 0.9398)
			(stroke
				(width 0.1524)
				(type default)
			)
			(layer "F.SilkS")
		)
		(fp_line
			(start 0.508 -0.9398)
			(end -0.508 -0.9398)
			(stroke
				(width 0.1524)
				(type default)
			)
			(layer "F.SilkS")
		)
		(fp_rect
			(start -0.508 0.9398)
			(end 0.508 -0.9398)
			(stroke
				(width 0)
				(type default)
			)
			(fill no)
			(layer "F.CrtYd")
		)
		(fp_rect
			(start -0.508 0.9398)
			(end 0.508 -0.9398)
			(stroke
				(width 0)
				(type default)
			)
			(fill no)
			(layer "F.Fab")
		)
		(pad "1" smd custom
			(at 0 -0.4445 270)
			(size 0.1397 0.1397)
			(layers "F.Cu" "F.Mask" "F.Paste")
			(net "GND")
			(options
				(clearance outline)
				(anchor circle)
			)
			(primitives
				(gr_poly
					(pts
						(arc
							(start -0.1778 -0.2794)
							(mid -0.249642 -0.249642)
							(end -0.2794 -0.1778)
						)
						(arc
							(start -0.2794 0.1778)
							(mid -0.249642 0.249642)
							(end -0.1778 0.2794)
						)
						(arc
							(start 0.1778 0.2794)
							(mid 0.249642 0.249642)
							(end 0.2794 0.1778)
						)
						(arc
							(start 0.2794 -0.1778)
							(mid 0.249642 -0.249642)
							(end 0.1778 -0.2794)
						)
					)
					(width 0)
					(fill yes)
				)
			)
		)
		(pad "2" smd custom
			(at 0 0.4445 270)
			(size 0.1397 0.1397)
			(layers "F.Cu" "F.Mask" "F.Paste")
			(net "MB0_RETRY_R")
			(options
				(clearance outline)
				(anchor circle)
			)
			(primitives
				(gr_poly
					(pts
						(arc
							(start -0.1778 -0.2794)
							(mid -0.249642 -0.249642)
							(end -0.2794 -0.1778)
						)
						(arc
							(start -0.2794 0.1778)
							(mid -0.249642 0.249642)
							(end -0.1778 0.2794)
						)
						(arc
							(start 0.1778 0.2794)
							(mid 0.249642 0.249642)
							(end 0.2794 0.1778)
						)
						(arc
							(start 0.2794 -0.1778)
							(mid 0.249642 -0.249642)
							(end 0.1778 -0.2794)
						)
					)
					(width 0)
					(fill yes)
				)
			)
		)
	)
	(footprint ""
		(layer "F.Cu")
		(at 34.294826 -181.57063 -90)
		(property "Reference" "PU2"
			(at 0 0 270)
			(layer "F.SilkS")
			(hide yes)
			(effects
				(font
					(size 1.27 1.27)
				)
			)
		)
		(property "Value" "TPS53318DQPR-GP"
			(at -5.022088 -6.851904 270)
			(unlocked yes)
			(layer "F.Fab")
			(hide yes)
			(effects
				(font
					(size 1.016 1.016)
					(thickness 0.1524)
				)
			)
		)
		(property "Device Type" "DFN22G6050-G6133H60"
			(at -5.022088 -8.375904 270)
			(unlocked yes)
			(layer "F.Fab")
			(hide yes)
			(effects
				(font
					(size 1.016 1.016)
					(thickness 0.1524)
				)
			)
		)
		(duplicate_pad_numbers_are_jumpers no)
		(fp_line
			(start -3.5052 3.5179)
			(end -2.2352 3.5179)
			(stroke
				(width 0.1524)
				(type default)
			)
			(layer "F.SilkS")
		)
		(fp_line
			(start 2.2352 3.5179)
			(end 3.5052 3.5179)
			(stroke
				(width 0.1524)
				(type default)
			)
			(layer "F.SilkS")
		)
		(fp_line
			(start 3.5052 3.5179)
			(end 3.5052 2.2479)
			(stroke
				(width 0.1524)
				(type default)
			)
			(layer "F.SilkS")
		)
		(fp_line
			(start -0.999998 3.262122)
			(end -0.999998 3.770122)
			(stroke
				(width 0.1524)
				(type default)
			)
			(layer "F.SilkS")
		)
		(fp_line
			(start 1.500124 3.262122)
			(end 1.500124 4.024122)
			(stroke
				(width 0.1524)
				(type default)
			)
			(layer "F.SilkS")
		)
		(fp_line
			(start -3.5052 2.2479)
			(end -3.5052 3.5179)
			(stroke
				(width 0.1524)
				(type default)
			)
			(layer "F.SilkS")
		)
		(fp_line
			(start -1.999996 -3.262122)
			(end -1.999996 -4.024122)
			(stroke
				(width 0.1524)
				(type default)
			)
			(layer "F.SilkS")
		)
		(fp_line
			(start 0.500126 -3.262122)
			(end 0.500126 -3.770122)
			(stroke
				(width 0.1524)
				(type default)
			)
			(layer "F.SilkS")
		)
		(fp_line
			(start -3.5052 -3.5179)
			(end -3.5052 -2.2479)
			(stroke
				(width 0.1524)
				(type default)
			)
			(layer "F.SilkS")
		)
		(fp_line
			(start -2.2352 -3.5179)
			(end -3.5052 -3.5179)
			(stroke
				(width 0.1524)
				(type default)
			)
			(layer "F.SilkS")
		)
		(fp_poly
			(pts
				(xy 3.5052 -3.5179) (xy 2.4765 -3.5179) (xy 3.5052 -2.4892)
			)
			(stroke
				(width 0)
				(type default)
			)
			(fill yes)
			(layer "F.SilkS")
		)
		(fp_rect
			(start -2.9972 2.5019)
			(end 2.9972 -2.5019)
			(stroke
				(width 0)
				(type default)
			)
			(fill no)
			(layer "F.CrtYd")
		)
		(fp_poly
			(pts
				(xy 3.556 -2.5019) (xy -2.9972 -2.5019) (xy -2.9972 2.5019) (xy 2.9972 2.5019) (xy 2.9972 -2.4892)
				(xy 3.556 -2.4892) (xy 3.556 3.5179) (xy -3.556 3.5179) (xy -3.556 -3.5179) (xy 3.556 -3.5179)
			)
			(stroke
				(width 0)
				(type default)
			)
			(fill no)
			(layer "F.CrtYd")
		)
		(fp_rect
			(start -3.556 3.5179)
			(end 3.556 -3.5179)
			(stroke
				(width 0)
				(type default)
			)
			(fill no)
			(layer "F.Fab")
		)
		(pad "1" smd rect
			(at 2.500122 -2.449322 270)
			(size 0.3048 1.1176)
			(layers "F.Cu" "F.Mask" "F.Paste")
			(net "P3V3_STBY_VFB")
		)
		(pad "2" smd rect
			(at 1.999996 -2.449322 270)
			(size 0.3048 1.1176)
			(layers "F.Cu" "F.Mask" "F.Paste")
			(net "P3V3_STBY_EN")
		)
		(pad "3" smd rect
			(at 1.500124 -2.449322 270)
			(size 0.3048 1.1176)
			(layers "F.Cu" "F.Mask" "F.Paste")
			(net "PWRGD_P3V3_STBY")
		)
		(pad "4" smd rect
			(at 0.999998 -2.449322 270)
			(size 0.3048 1.1176)
			(layers "F.Cu" "F.Mask" "F.Paste")
			(net "P3V3_VBST")
		)
		(pad "5" smd rect
			(at 0.500126 -2.449322 270)
			(size 0.3048 1.1176)
			(layers "F.Cu" "F.Mask" "F.Paste")
			(net "P3V3_STBY_ROVP")
		)
		(pad "6" smd rect
			(at 0 -2.449322 270)
			(size 0.3048 1.1176)
			(layers "F.Cu" "F.Mask" "F.Paste")
			(net "P3V3_STBY_LL")
		)
		(pad "7" smd rect
			(at -0.500126 -2.449322 270)
			(size 0.3048 1.1176)
			(layers "F.Cu" "F.Mask" "F.Paste")
			(net "P3V3_STBY_LL")
		)
		(pad "8" smd rect
			(at -0.999998 -2.449322 270)
			(size 0.3048 1.1176)
			(layers "F.Cu" "F.Mask" "F.Paste")
			(net "P3V3_STBY_LL")
		)
		(pad "9" smd rect
			(at -1.500124 -2.449322 270)
			(size 0.3048 1.1176)
			(layers "F.Cu" "F.Mask" "F.Paste")
			(net "P3V3_STBY_LL")
		)
		(pad "10" smd rect
			(at -1.999996 -2.449322 270)
			(size 0.3048 1.1176)
			(layers "F.Cu" "F.Mask" "F.Paste")
			(net "P3V3_STBY_LL")
		)
		(pad "11" smd rect
			(at -2.500122 -2.449322 270)
			(size 0.3048 1.1176)
			(layers "F.Cu" "F.Mask" "F.Paste")
			(net "P3V3_STBY_LL")
		)
		(pad "12" smd rect
			(at -2.500122 2.449322 270)
			(size 0.3048 1.1176)
			(layers "F.Cu" "F.Mask" "F.Paste")
			(net "P12V_STBY_VIN_PU2")
		)
		(pad "13" smd rect
			(at -1.999996 2.449322 270)
			(size 0.3048 1.1176)
			(layers "F.Cu" "F.Mask" "F.Paste")
			(net "P12V_STBY_VIN_PU2")
		)
		(pad "14" smd rect
			(at -1.500124 2.449322 270)
			(size 0.3048 1.1176)
			(layers "F.Cu" "F.Mask" "F.Paste")
			(net "P12V_STBY_VIN_PU2")
		)
		(pad "15" smd rect
			(at -0.999998 2.449322 270)
			(size 0.3048 1.1176)
			(layers "F.Cu" "F.Mask" "F.Paste")
			(net "P12V_STBY_VIN_PU2")
		)
		(pad "16" smd rect
			(at -0.500126 2.449322 270)
			(size 0.3048 1.1176)
			(layers "F.Cu" "F.Mask" "F.Paste")
			(net "P12V_STBY_VIN_PU2")
		)
		(pad "17" smd rect
			(at 0 2.449322 270)
			(size 0.3048 1.1176)
			(layers "F.Cu" "F.Mask" "F.Paste")
			(net "P12V_STBY_VIN_PU2")
		)
		(pad "18" smd rect
			(at 0.500126 2.449322 270)
			(size 0.3048 1.1176)
			(layers "F.Cu" "F.Mask" "F.Paste")
			(net "P3V3_STBY_VREG")
		)
		(pad "19" smd rect
			(at 0.999998 2.449322 270)
			(size 0.3048 1.1176)
			(layers "F.Cu" "F.Mask" "F.Paste")
			(net "P12V_STBY_VDD_PU2")
		)
		(pad "20" smd rect
			(at 1.500124 2.449322 270)
			(size 0.3048 1.1176)
			(layers "F.Cu" "F.Mask" "F.Paste")
			(net "P3V3_STBY_MODE")
		)
		(pad "21" smd rect
			(at 1.999996 2.449322 270)
			(size 0.3048 1.1176)
			(layers "F.Cu" "F.Mask" "F.Paste")
			(net "P3V3_STBY_TRIP")
		)
		(pad "22" smd rect
			(at 2.500122 2.449322 270)
			(size 0.3048 1.1176)
			(layers "F.Cu" "F.Mask" "F.Paste")
			(net "P3V3_STBY_RF")
		)
		(pad "23" smd custom
			(at 0 0 270)
			(size 0.83185 0.83185)
			(layers "F.Cu" "F.Mask" "F.Paste")
			(net "GND")
			(options
				(clearance outline)
				(anchor circle)
			)
			(primitives
				(gr_poly
					(pts
						(xy -2.7813 1.6637) (xy -2.7813 1.2954) (xy -3.048 1.2954) (xy -3.048 0.9525) (xy -2.7813 0.9525)
						(xy -2.7813 -0.9525) (xy -3.048 -0.9525) (xy -3.048 -1.2954) (xy -2.7813 -1.2954) (xy -2.7813 -1.6637)
						(xy 2.7813 -1.6637) (xy 2.7813 -1.2954) (xy 3.048 -1.2954) (xy 3.048 -0.9525) (xy 2.7813 -0.9525)
						(xy 2.7813 0.9525) (xy 3.048 0.9525) (xy 3.048 1.2954) (xy 2.7813 1.2954) (xy 2.7813 1.6637)
					)
					(width 0)
					(fill yes)
				)
			)
		)
	)
	(footprint ""
		(layer "F.Cu")
		(at 110.75797 -11.974576 -90)
		(property "Reference" "C147"
			(at 0 0 270)
			(layer "F.SilkS")
			(hide yes)
			(effects
				(font
					(size 1.27 1.27)
				)
			)
		)
		(property "Value" "SC1U16V3KX-5GP"
			(at 0 -2.8194 270)
			(unlocked yes)
			(layer "F.Fab")
			(hide yes)
			(effects
				(font
					(size 1.016 1.016)
					(thickness 0.1524)
				)
			)
		)
		(property "Device Type" "C603H36"
			(at 0 -4.3434 270)
			(unlocked yes)
			(layer "F.Fab")
			(hide yes)
			(effects
				(font
					(size 1.016 1.016)
					(thickness 0.1524)
				)
			)
		)
		(duplicate_pad_numbers_are_jumpers no)
		(fp_line
			(start 0.508 0)
			(end -0.508 0)
			(stroke
				(width 0.2032)
				(type default)
			)
			(layer "F.SilkS")
		)
		(fp_rect
			(start -0.5842 1.3335)
			(end 0.5842 -1.3335)
			(stroke
				(width 0)
				(type default)
			)
			(fill no)
			(layer "F.CrtYd")
		)
		(fp_rect
			(start -0.5842 1.3335)
			(end 0.5842 -1.3335)
			(stroke
				(width 0)
				(type default)
			)
			(fill no)
			(layer "F.Fab")
		)
		(pad "1" smd custom
			(at 0 -0.762 270)
			(size 0.2159 0.2159)
			(layers "F.Cu" "F.Mask" "F.Paste")
			(net "MB0_VCAP_R")
			(options
				(clearance outline)
				(anchor circle)
			)
			(primitives
				(gr_poly
					(pts
						(arc
							(start -0.3302 -0.4318)
							(mid -0.402042 -0.402042)
							(end -0.4318 -0.3302)
						)
						(arc
							(start -0.4318 0.3302)
							(mid -0.402042 0.402042)
							(end -0.3302 0.4318)
						)
						(arc
							(start 0.3302 0.4318)
							(mid 0.402042 0.402042)
							(end 0.4318 0.3302)
						)
						(arc
							(start 0.4318 -0.3302)
							(mid 0.402042 -0.402042)
							(end 0.3302 -0.4318)
						)
					)
					(width 0)
					(fill yes)
				)
			)
		)
		(pad "2" smd custom
			(at 0 0.762 270)
			(size 0.2159 0.2159)
			(layers "F.Cu" "F.Mask" "F.Paste")
			(net "AGND_CURRENT_MON")
			(options
				(clearance outline)
				(anchor circle)
			)
			(primitives
				(gr_poly
					(pts
						(arc
							(start -0.3302 -0.4318)
							(mid -0.402042 -0.402042)
							(end -0.4318 -0.3302)
						)
						(arc
							(start -0.4318 0.3302)
							(mid -0.402042 0.402042)
							(end -0.3302 0.4318)
						)
						(arc
							(start 0.3302 0.4318)
							(mid 0.402042 0.402042)
							(end 0.4318 0.3302)
						)
						(arc
							(start 0.4318 -0.3302)
							(mid 0.402042 -0.402042)
							(end 0.3302 -0.4318)
						)
					)
					(width 0)
					(fill yes)
				)
			)
		)
	)
	(footprint ""
		(layer "F.Cu")
		(at 60.375546 -185.000138 -90)
		(property "Reference" "R480"
			(at 0 0 270)
			(layer "F.SilkS")
			(hide yes)
			(effects
				(font
					(size 1.27 1.27)
				)
			)
		)
		(property "Value" "0R6J-3-GP"
			(at -0.0508 -4.8514 270)
			(unlocked yes)
			(layer "F.Fab")
			(hide yes)
			(effects
				(font
					(size 1.016 1.016)
					(thickness 0.1524)
				)
			)
		)
		(property "Device Type" "R1206H28"
			(at 0 -6.3754 270)
			(unlocked yes)
			(layer "F.Fab")
			(hide yes)
			(effects
				(font
					(size 1.016 1.016)
					(thickness 0.1524)
				)
			)
		)
		(duplicate_pad_numbers_are_jumpers no)
		(fp_line
			(start -1.016 2.2352)
			(end -1.016 -2.2352)
			(stroke
				(width 0.1524)
				(type default)
			)
			(layer "F.SilkS")
		)
		(fp_line
			(start 1.016 2.2352)
			(end -1.016 2.2352)
			(stroke
				(width 0.1524)
				(type default)
			)
			(layer "F.SilkS")
		)
		(fp_line
			(start -1.016 -2.2352)
			(end 1.016 -2.2352)
			(stroke
				(width 0.1524)
				(type default)
			)
			(layer "F.SilkS")
		)
		(fp_line
			(start 1.016 -2.2352)
			(end 1.016 2.2352)
			(stroke
				(width 0.1524)
				(type default)
			)
			(layer "F.SilkS")
		)
		(fp_rect
			(start -1.0922 2.3114)
			(end 1.0922 -2.3114)
			(stroke
				(width 0)
				(type default)
			)
			(fill no)
			(layer "F.CrtYd")
		)
		(fp_poly
			(pts
				(xy -1.0922 -2.3114) (xy 1.0922 -2.3114) (xy 1.0922 2.3114) (xy -1.0922 2.3114)
			)
			(stroke
				(width 0)
				(type default)
			)
			(fill no)
			(layer "F.Fab")
		)
		(pad "1" smd rect
			(at 0 -1.397 270)
			(size 1.651 1.27)
			(layers "F.Cu" "F.Mask" "F.Paste")
			(net "P3V3_STBY")
		)
		(pad "2" smd rect
			(at 0 1.397 270)
			(size 1.651 1.27)
			(layers "F.Cu" "F.Mask" "F.Paste")
			(net "P3V3_STBY_OUT")
		)
	)
	(footprint ""
		(layer "F.Cu")
		(at 91.72448 -149.196044)
		(property "Reference" "R25"
			(at 0 0 0)
			(layer "F.SilkS")
			(hide yes)
			(effects
				(font
					(size 1.27 1.27)
				)
			)
		)
		(property "Value" "15KR2F-GP"
			(at 0.064008 -3.993896 0)
			(unlocked yes)
			(layer "F.Fab")
			(hide yes)
			(effects
				(font
					(size 1.016 1.016)
					(thickness 0.1524)
				)
			)
		)
		(property "Device Type" "R402H16"
			(at 0.064008 -5.517896 0)
			(unlocked yes)
			(layer "F.Fab")
			(hide yes)
			(effects
				(font
					(size 1.016 1.016)
					(thickness 0.1524)
				)
			)
		)
		(duplicate_pad_numbers_are_jumpers no)
		(fp_line
			(start -0.508 -0.9398)
			(end -0.508 0.9398)
			(stroke
				(width 0.1524)
				(type default)
			)
			(layer "F.SilkS")
		)
		(fp_line
			(start 0.508 -0.9398)
			(end -0.508 -0.9398)
			(stroke
				(width 0.1524)
				(type default)
			)
			(layer "F.SilkS")
		)
		(fp_rect
			(start -0.508 0.9398)
			(end 0.508 -0.9398)
			(stroke
				(width 0)
				(type default)
			)
			(fill no)
			(layer "F.CrtYd")
		)
		(fp_rect
			(start -0.508 0.9398)
			(end 0.508 -0.9398)
			(stroke
				(width 0)
				(type default)
			)
			(fill no)
			(layer "F.Fab")
		)
		(pad "1" smd custom
			(at 0 -0.4445)
			(size 0.1397 0.1397)
			(layers "F.Cu" "F.Mask" "F.Paste")
			(net "USB_OCS_N1")
			(options
				(clearance outline)
				(anchor circle)
			)
			(primitives
				(gr_poly
					(pts
						(arc
							(start -0.1778 -0.2794)
							(mid -0.249642 -0.249642)
							(end -0.2794 -0.1778)
						)
						(arc
							(start -0.2794 0.1778)
							(mid -0.249642 0.249642)
							(end -0.1778 0.2794)
						)
						(arc
							(start 0.1778 0.2794)
							(mid 0.249642 0.249642)
							(end 0.2794 0.1778)
						)
						(arc
							(start 0.2794 -0.1778)
							(mid 0.249642 -0.249642)
							(end 0.1778 -0.2794)
						)
					)
					(width 0)
					(fill yes)
				)
			)
		)
		(pad "2" smd custom
			(at 0 0.4445)
			(size 0.1397 0.1397)
			(layers "F.Cu" "F.Mask" "F.Paste")
			(net "GND")
			(options
				(clearance outline)
				(anchor circle)
			)
			(primitives
				(gr_poly
					(pts
						(arc
							(start -0.1778 -0.2794)
							(mid -0.249642 -0.249642)
							(end -0.2794 -0.1778)
						)
						(arc
							(start -0.2794 0.1778)
							(mid -0.249642 0.249642)
							(end -0.1778 0.2794)
						)
						(arc
							(start 0.1778 0.2794)
							(mid 0.249642 0.249642)
							(end 0.2794 0.1778)
						)
						(arc
							(start 0.2794 -0.1778)
							(mid 0.249642 -0.249642)
							(end 0.1778 -0.2794)
						)
					)
					(width 0)
					(fill yes)
				)
			)
		)
	)
	(footprint ""
		(layer "F.Cu")
		(at 97.6122 -139.7254)
		(property "Reference" "R276"
			(at 0 0 0)
			(layer "F.SilkS")
			(hide yes)
			(effects
				(font
					(size 1.27 1.27)
				)
			)
		)
		(property "Value" "4K7R2F-GP"
			(at 0.064008 -3.993896 0)
			(unlocked yes)
			(layer "F.Fab")
			(hide yes)
			(effects
				(font
					(size 1.016 1.016)
					(thickness 0.1524)
				)
			)
		)
		(property "Device Type" "R402H16"
			(at 0.064008 -5.517896 0)
			(unlocked yes)
			(layer "F.Fab")
			(hide yes)
			(effects
				(font
					(size 1.016 1.016)
					(thickness 0.1524)
				)
			)
		)
		(duplicate_pad_numbers_are_jumpers no)
		(fp_line
			(start -0.508 -0.9398)
			(end -0.508 0.9398)
			(stroke
				(width 0.1524)
				(type default)
			)
			(layer "F.SilkS")
		)
		(fp_line
			(start 0.508 -0.9398)
			(end -0.508 -0.9398)
			(stroke
				(width 0.1524)
				(type default)
			)
			(layer "F.SilkS")
		)
		(fp_rect
			(start -0.508 0.9398)
			(end 0.508 -0.9398)
			(stroke
				(width 0)
				(type default)
			)
			(fill no)
			(layer "F.CrtYd")
		)
		(fp_rect
			(start -0.508 0.9398)
			(end 0.508 -0.9398)
			(stroke
				(width 0)
				(type default)
			)
			(fill no)
			(layer "F.Fab")
		)
		(pad "1" smd custom
			(at 0 -0.4445)
			(size 0.1397 0.1397)
			(layers "F.Cu" "F.Mask" "F.Paste")
			(net "P3V3_STBY")
			(options
				(clearance outline)
				(anchor circle)
			)
			(primitives
				(gr_poly
					(pts
						(arc
							(start -0.1778 -0.2794)
							(mid -0.249642 -0.249642)
							(end -0.2794 -0.1778)
						)
						(arc
							(start -0.2794 0.1778)
							(mid -0.249642 0.249642)
							(end -0.1778 0.2794)
						)
						(arc
							(start 0.1778 0.2794)
							(mid 0.249642 0.249642)
							(end 0.2794 0.1778)
						)
						(arc
							(start 0.2794 -0.1778)
							(mid 0.249642 -0.249642)
							(end 0.1778 -0.2794)
						)
					)
					(width 0)
					(fill yes)
				)
			)
		)
		(pad "2" smd custom
			(at 0 0.4445)
			(size 0.1397 0.1397)
			(layers "F.Cu" "F.Mask" "F.Paste")
			(net "DEBUG_RST_BTN_N")
			(options
				(clearance outline)
				(anchor circle)
			)
			(primitives
				(gr_poly
					(pts
						(arc
							(start -0.1778 -0.2794)
							(mid -0.249642 -0.249642)
							(end -0.2794 -0.1778)
						)
						(arc
							(start -0.2794 0.1778)
							(mid -0.249642 0.249642)
							(end -0.1778 0.2794)
						)
						(arc
							(start 0.1778 0.2794)
							(mid 0.249642 0.249642)
							(end 0.2794 0.1778)
						)
						(arc
							(start 0.2794 -0.1778)
							(mid 0.249642 -0.249642)
							(end 0.1778 -0.2794)
						)
					)
					(width 0)
					(fill yes)
				)
			)
		)
	)
	(footprint ""
		(layer "F.Cu")
		(at 63.6016 -146.8882 90)
		(property "Reference" "R190"
			(at 0 0 90)
			(layer "F.SilkS")
			(hide yes)
			(effects
				(font
					(size 1.27 1.27)
				)
			)
		)
		(property "Value" "499R2F-2-GP"
			(at 0.064008 -3.993896 90)
			(unlocked yes)
			(layer "F.Fab")
			(hide yes)
			(effects
				(font
					(size 1.016 1.016)
					(thickness 0.1524)
				)
			)
		)
		(property "Device Type" "R402H16"
			(at 0.064008 -5.517896 90)
			(unlocked yes)
			(layer "F.Fab")
			(hide yes)
			(effects
				(font
					(size 1.016 1.016)
					(thickness 0.1524)
				)
			)
		)
		(duplicate_pad_numbers_are_jumpers no)
		(fp_line
			(start 0.508 -0.9398)
			(end -0.508 -0.9398)
			(stroke
				(width 0.1524)
				(type default)
			)
			(layer "F.SilkS")
		)
		(fp_line
			(start -0.508 -0.9398)
			(end -0.508 0.9398)
			(stroke
				(width 0.1524)
				(type default)
			)
			(layer "F.SilkS")
		)
		(fp_rect
			(start -0.508 0.9398)
			(end 0.508 -0.9398)
			(stroke
				(width 0)
				(type default)
			)
			(fill no)
			(layer "F.CrtYd")
		)
		(fp_rect
			(start -0.508 0.9398)
			(end 0.508 -0.9398)
			(stroke
				(width 0)
				(type default)
			)
			(fill no)
			(layer "F.Fab")
		)
		(pad "1" smd custom
			(at 0 -0.4445 90)
			(size 0.1397 0.1397)
			(layers "F.Cu" "F.Mask" "F.Paste")
			(net "I2C_BMC_COMP_SDA_OUT")
			(options
				(clearance outline)
				(anchor circle)
			)
			(primitives
				(gr_poly
					(pts
						(arc
							(start -0.1778 -0.2794)
							(mid -0.249642 -0.249642)
							(end -0.2794 -0.1778)
						)
						(arc
							(start -0.2794 0.1778)
							(mid -0.249642 0.249642)
							(end -0.1778 0.2794)
						)
						(arc
							(start 0.1778 0.2794)
							(mid 0.249642 0.249642)
							(end 0.2794 0.1778)
						)
						(arc
							(start 0.2794 -0.1778)
							(mid 0.249642 -0.249642)
							(end 0.1778 -0.2794)
						)
					)
					(width 0)
					(fill yes)
				)
			)
		)
		(pad "2" smd custom
			(at 0 0.4445 90)
			(size 0.1397 0.1397)
			(layers "F.Cu" "F.Mask" "F.Paste")
			(net "P3V3_STBY")
			(options
				(clearance outline)
				(anchor circle)
			)
			(primitives
				(gr_poly
					(pts
						(arc
							(start -0.1778 -0.2794)
							(mid -0.249642 -0.249642)
							(end -0.2794 -0.1778)
						)
						(arc
							(start -0.2794 0.1778)
							(mid -0.249642 0.249642)
							(end -0.1778 0.2794)
						)
						(arc
							(start 0.1778 0.2794)
							(mid 0.249642 0.249642)
							(end 0.2794 0.1778)
						)
						(arc
							(start 0.2794 -0.1778)
							(mid 0.249642 -0.249642)
							(end 0.1778 -0.2794)
						)
					)
					(width 0)
					(fill yes)
				)
			)
		)
	)
	(footprint ""
		(layer "F.Cu")
		(at 83.82 -147.674076 90)
		(property "Reference" "C135"
			(at 0 0 90)
			(layer "F.SilkS")
			(hide yes)
			(effects
				(font
					(size 1.27 1.27)
				)
			)
		)
		(property "Value" "SCD1U16V2KX-3GP"
			(at 1.1811 -2.7051 90)
			(unlocked yes)
			(layer "F.Fab")
			(hide yes)
			(effects
				(font
					(size 1.016 1.016)
					(thickness 0.1524)
				)
			)
		)
		(property "Device Type" "C402H22"
			(at 1.1811 -4.2291 90)
			(unlocked yes)
			(layer "F.Fab")
			(hide yes)
			(effects
				(font
					(size 1.016 1.016)
					(thickness 0.1524)
				)
			)
		)
		(duplicate_pad_numbers_are_jumpers no)
		(fp_rect
			(start -0.4318 0.9525)
			(end 0.4318 -0.9525)
			(stroke
				(width 0)
				(type default)
			)
			(fill no)
			(layer "F.CrtYd")
		)
		(fp_rect
			(start -0.4318 0.9525)
			(end 0.4318 -0.9525)
			(stroke
				(width 0)
				(type default)
			)
			(fill no)
			(layer "F.Fab")
		)
		(pad "1" smd custom
			(at 0 -0.4445 90)
			(size 0.1524 0.1524)
			(layers "F.Cu" "F.Mask" "F.Paste")
			(net "P3V3_STBY")
			(options
				(clearance outline)
				(anchor circle)
			)
			(primitives
				(gr_poly
					(pts
						(arc
							(start 0.3048 -0.2032)
							(mid 0.275042 -0.275042)
							(end 0.2032 -0.3048)
						)
						(arc
							(start -0.2032 -0.3048)
							(mid -0.275042 -0.275042)
							(end -0.3048 -0.2032)
						)
						(arc
							(start -0.3048 0.2032)
							(mid -0.275042 0.275042)
							(end -0.2032 0.3048)
						)
						(arc
							(start 0.2032 0.3048)
							(mid 0.275042 0.275042)
							(end 0.3048 0.2032)
						)
					)
					(width 0)
					(fill yes)
				)
			)
		)
		(pad "2" smd custom
			(at 0 0.4445 90)
			(size 0.1524 0.1524)
			(layers "F.Cu" "F.Mask" "F.Paste")
			(net "GND")
			(options
				(clearance outline)
				(anchor circle)
			)
			(primitives
				(gr_poly
					(pts
						(arc
							(start 0.3048 -0.2032)
							(mid 0.275042 -0.275042)
							(end 0.2032 -0.3048)
						)
						(arc
							(start -0.2032 -0.3048)
							(mid -0.275042 -0.275042)
							(end -0.3048 -0.2032)
						)
						(arc
							(start -0.3048 0.2032)
							(mid -0.275042 0.275042)
							(end -0.2032 0.3048)
						)
						(arc
							(start 0.2032 0.3048)
							(mid 0.275042 0.275042)
							(end 0.3048 0.2032)
						)
					)
					(width 0)
					(fill yes)
				)
			)
		)
	)
	(footprint ""
		(layer "F.Cu")
		(at 228.470714 -102.168706 180)
		(property "Reference" "C636"
			(at 0 0 180)
			(layer "F.SilkS")
			(hide yes)
			(effects
				(font
					(size 1.27 1.27)
				)
			)
		)
		(property "Value" "SC10U16V5KX-7-GP-U"
			(at -0.076454 -6.1214 180)
			(unlocked yes)
			(layer "F.Fab")
			(hide yes)
			(effects
				(font
					(size 1.016 1.016)
					(thickness 0.1524)
				)
			)
		)
		(property "Device Type" "C805H58"
			(at -0.076454 -8.153654 180)
			(unlocked yes)
			(layer "F.Fab")
			(hide yes)
			(effects
				(font
					(size 1.016 1.016)
					(thickness 0.1524)
				)
			)
		)
		(duplicate_pad_numbers_are_jumpers no)
		(fp_line
			(start 0.635 0)
			(end -0.635 0)
			(stroke
				(width 0.508)
				(type default)
			)
			(layer "F.SilkS")
		)
		(fp_rect
			(start -0.9652 1.778)
			(end 0.9652 -1.778)
			(stroke
				(width 0)
				(type default)
			)
			(fill no)
			(layer "F.CrtYd")
		)
		(fp_poly
			(pts
				(xy -0.9652 -1.778254) (xy 0.9652 -1.778254) (xy 0.9652 1.778) (xy -0.9652 1.778)
			)
			(stroke
				(width 0)
				(type default)
			)
			(fill no)
			(layer "F.Fab")
		)
		(pad "1" smd rect
			(at 0 -0.9652 180)
			(size 1.397 1.143)
			(layers "F.Cu" "F.Mask" "F.Paste")
			(net "P12V_STBY_VIN_U81")
		)
		(pad "2" smd rect
			(at 0 0.9652 180)
			(size 1.397 1.143)
			(layers "F.Cu" "F.Mask" "F.Paste")
			(net "GND")
		)
	)
	(footprint ""
		(layer "F.Cu")
		(at 88.813894 -62.739016 -90)
		(property "Reference" "R7"
			(at 0 0 270)
			(layer "F.SilkS")
			(hide yes)
			(effects
				(font
					(size 1.27 1.27)
				)
			)
		)
		(property "Value" "0R2J-2-GP"
			(at 0.064008 -3.993896 270)
			(unlocked yes)
			(layer "F.Fab")
			(hide yes)
			(effects
				(font
					(size 1.016 1.016)
					(thickness 0.1524)
				)
			)
		)
		(property "Device Type" "R402H16"
			(at 0.064008 -5.517896 270)
			(unlocked yes)
			(layer "F.Fab")
			(hide yes)
			(effects
				(font
					(size 1.016 1.016)
					(thickness 0.1524)
				)
			)
		)
		(duplicate_pad_numbers_are_jumpers no)
		(fp_line
			(start -0.508 -0.9398)
			(end -0.508 0.9398)
			(stroke
				(width 0.1524)
				(type default)
			)
			(layer "F.SilkS")
		)
		(fp_line
			(start 0.508 -0.9398)
			(end -0.508 -0.9398)
			(stroke
				(width 0.1524)
				(type default)
			)
			(layer "F.SilkS")
		)
		(fp_rect
			(start -0.508 0.9398)
			(end 0.508 -0.9398)
			(stroke
				(width 0)
				(type default)
			)
			(fill no)
			(layer "F.CrtYd")
		)
		(fp_rect
			(start -0.508 0.9398)
			(end 0.508 -0.9398)
			(stroke
				(width 0)
				(type default)
			)
			(fill no)
			(layer "F.Fab")
		)
		(pad "1" smd custom
			(at 0 -0.4445 270)
			(size 0.1397 0.1397)
			(layers "F.Cu" "F.Mask" "F.Paste")
			(net "NCSI_TXEN")
			(options
				(clearance outline)
				(anchor circle)
			)
			(primitives
				(gr_poly
					(pts
						(arc
							(start -0.1778 -0.2794)
							(mid -0.249642 -0.249642)
							(end -0.2794 -0.1778)
						)
						(arc
							(start -0.2794 0.1778)
							(mid -0.249642 0.249642)
							(end -0.1778 0.2794)
						)
						(arc
							(start 0.1778 0.2794)
							(mid 0.249642 0.249642)
							(end 0.2794 0.1778)
						)
						(arc
							(start 0.2794 -0.1778)
							(mid 0.249642 -0.249642)
							(end 0.1778 -0.2794)
						)
					)
					(width 0)
					(fill yes)
				)
			)
		)
		(pad "2" smd custom
			(at 0 0.4445 270)
			(size 0.1397 0.1397)
			(layers "F.Cu" "F.Mask" "F.Paste")
			(net "NCSI_TXEN_R")
			(options
				(clearance outline)
				(anchor circle)
			)
			(primitives
				(gr_poly
					(pts
						(arc
							(start -0.1778 -0.2794)
							(mid -0.249642 -0.249642)
							(end -0.2794 -0.1778)
						)
						(arc
							(start -0.2794 0.1778)
							(mid -0.249642 0.249642)
							(end -0.1778 0.2794)
						)
						(arc
							(start 0.1778 0.2794)
							(mid 0.249642 0.249642)
							(end 0.2794 0.1778)
						)
						(arc
							(start 0.2794 -0.1778)
							(mid 0.249642 -0.249642)
							(end 0.1778 -0.2794)
						)
					)
					(width 0)
					(fill yes)
				)
			)
		)
	)
	(footprint ""
		(layer "F.Cu")
		(at 149.008338 -14.987778)
		(property "Reference" "C206"
			(at 0 0 0)
			(layer "F.SilkS")
			(hide yes)
			(effects
				(font
					(size 1.27 1.27)
				)
			)
		)
		(property "Value" "SC100P50V2JN-3GP"
			(at 1.1811 -2.7051 0)
			(unlocked yes)
			(layer "F.Fab")
			(hide yes)
			(effects
				(font
					(size 1.016 1.016)
					(thickness 0.1524)
				)
			)
		)
		(property "Device Type" "C402H22"
			(at 1.1811 -4.2291 0)
			(unlocked yes)
			(layer "F.Fab")
			(hide yes)
			(effects
				(font
					(size 1.016 1.016)
					(thickness 0.1524)
				)
			)
		)
		(duplicate_pad_numbers_are_jumpers no)
		(fp_rect
			(start -0.4318 0.9525)
			(end 0.4318 -0.9525)
			(stroke
				(width 0)
				(type default)
			)
			(fill no)
			(layer "F.CrtYd")
		)
		(fp_rect
			(start -0.4318 0.9525)
			(end 0.4318 -0.9525)
			(stroke
				(width 0)
				(type default)
			)
			(fill no)
			(layer "F.Fab")
		)
		(pad "1" smd custom
			(at 0 -0.4445)
			(size 0.1524 0.1524)
			(layers "F.Cu" "F.Mask" "F.Paste")
			(net "P1V8_STBY_CC_R")
			(options
				(clearance outline)
				(anchor circle)
			)
			(primitives
				(gr_poly
					(pts
						(arc
							(start 0.3048 -0.2032)
							(mid 0.275042 -0.275042)
							(end 0.2032 -0.3048)
						)
						(arc
							(start -0.2032 -0.3048)
							(mid -0.275042 -0.275042)
							(end -0.3048 -0.2032)
						)
						(arc
							(start -0.3048 0.2032)
							(mid -0.275042 0.275042)
							(end -0.2032 0.3048)
						)
						(arc
							(start 0.2032 0.3048)
							(mid 0.275042 0.275042)
							(end 0.3048 0.2032)
						)
					)
					(width 0)
					(fill yes)
				)
			)
		)
		(pad "2" smd custom
			(at 0 0.4445)
			(size 0.1524 0.1524)
			(layers "F.Cu" "F.Mask" "F.Paste")
			(net "P1V8_STBY_VFB")
			(options
				(clearance outline)
				(anchor circle)
			)
			(primitives
				(gr_poly
					(pts
						(arc
							(start 0.3048 -0.2032)
							(mid 0.275042 -0.275042)
							(end 0.2032 -0.3048)
						)
						(arc
							(start -0.2032 -0.3048)
							(mid -0.275042 -0.275042)
							(end -0.3048 -0.2032)
						)
						(arc
							(start -0.3048 0.2032)
							(mid -0.275042 0.275042)
							(end -0.2032 0.3048)
						)
						(arc
							(start 0.2032 0.3048)
							(mid 0.275042 0.275042)
							(end 0.3048 0.2032)
						)
					)
					(width 0)
					(fill yes)
				)
			)
		)
	)
	(footprint ""
		(layer "F.Cu")
		(at 93.8276 -29.8958)
		(property "Reference" "C1"
			(at 0 0 0)
			(layer "F.SilkS")
			(hide yes)
			(effects
				(font
					(size 1.27 1.27)
				)
			)
		)
		(property "Value" "SCD1U16V2KX-3GP"
			(at 1.1811 -2.7051 0)
			(unlocked yes)
			(layer "F.Fab")
			(hide yes)
			(effects
				(font
					(size 1.016 1.016)
					(thickness 0.1524)
				)
			)
		)
		(property "Device Type" "C402H22"
			(at 1.1811 -4.2291 0)
			(unlocked yes)
			(layer "F.Fab")
			(hide yes)
			(effects
				(font
					(size 1.016 1.016)
					(thickness 0.1524)
				)
			)
		)
		(duplicate_pad_numbers_are_jumpers no)
		(fp_rect
			(start -0.4318 0.9525)
			(end 0.4318 -0.9525)
			(stroke
				(width 0)
				(type default)
			)
			(fill no)
			(layer "F.CrtYd")
		)
		(fp_rect
			(start -0.4318 0.9525)
			(end 0.4318 -0.9525)
			(stroke
				(width 0)
				(type default)
			)
			(fill no)
			(layer "F.Fab")
		)
		(pad "1" smd custom
			(at 0 -0.4445)
			(size 0.1524 0.1524)
			(layers "F.Cu" "F.Mask" "F.Paste")
			(net "P5V_STBY")
			(options
				(clearance outline)
				(anchor circle)
			)
			(primitives
				(gr_poly
					(pts
						(arc
							(start 0.3048 -0.2032)
							(mid 0.275042 -0.275042)
							(end 0.2032 -0.3048)
						)
						(arc
							(start -0.2032 -0.3048)
							(mid -0.275042 -0.275042)
							(end -0.3048 -0.2032)
						)
						(arc
							(start -0.3048 0.2032)
							(mid -0.275042 0.275042)
							(end -0.2032 0.3048)
						)
						(arc
							(start 0.2032 0.3048)
							(mid 0.275042 0.275042)
							(end 0.3048 0.2032)
						)
					)
					(width 0)
					(fill yes)
				)
			)
		)
		(pad "2" smd custom
			(at 0 0.4445)
			(size 0.1524 0.1524)
			(layers "F.Cu" "F.Mask" "F.Paste")
			(net "GND")
			(options
				(clearance outline)
				(anchor circle)
			)
			(primitives
				(gr_poly
					(pts
						(arc
							(start 0.3048 -0.2032)
							(mid 0.275042 -0.275042)
							(end 0.2032 -0.3048)
						)
						(arc
							(start -0.2032 -0.3048)
							(mid -0.275042 -0.275042)
							(end -0.3048 -0.2032)
						)
						(arc
							(start -0.3048 0.2032)
							(mid -0.275042 0.275042)
							(end -0.2032 0.3048)
						)
						(arc
							(start 0.2032 0.3048)
							(mid 0.275042 0.275042)
							(end 0.3048 0.2032)
						)
					)
					(width 0)
					(fill yes)
				)
			)
		)
	)
	(footprint ""
		(layer "F.Cu")
		(at 141.299946 -44.200064 180)
		(property "Reference" "CN1"
			(at 0 0 180)
			(layer "F.SilkS")
			(hide yes)
			(effects
				(font
					(size 1.27 1.27)
				)
			)
		)
		(property "Value" "AMP-CONN200-13R-4-GP"
			(at 30.332934 43.515534 180)
			(unlocked yes)
			(layer "F.Fab")
			(hide yes)
			(effects
				(font
					(size 1.016 1.016)
					(thickness 0.1524)
				)
			)
		)
		(property "Device Type" "PREFIT-200P-360520-1H542"
			(at 30.332934 41.991534 180)
			(unlocked yes)
			(layer "F.Fab")
			(hide yes)
			(effects
				(font
					(size 1.016 1.016)
					(thickness 0.1524)
				)
			)
		)
		(duplicate_pad_numbers_are_jumpers no)
		(fp_line
			(start 35.56 3.800094)
			(end -0.9398 3.800094)
			(stroke
				(width 0.1524)
				(type default)
			)
			(layer "F.SilkS")
		)
		(fp_line
			(start 35.56 -15.7226)
			(end 35.56 3.800094)
			(stroke
				(width 0.1524)
				(type default)
			)
			(layer "F.SilkS")
		)
		(fp_line
			(start -0.9398 3.800094)
			(end -0.9398 -15.7226)
			(stroke
				(width 0.1524)
				(type default)
			)
			(layer "F.SilkS")
		)
		(fp_line
			(start -0.9398 -15.7226)
			(end 35.56 -15.7226)
			(stroke
				(width 0.1524)
				(type default)
			)
			(layer "F.SilkS")
		)
		(fp_poly
			(pts
				(xy -0.9398 3.800094) (xy -0.9398 -7.80034) (xy -0.635 -7.80034) (xy -0.635 2.93497) (xy 34.835084 2.93497)
				(xy 34.835084 -13.934948) (xy 34.8361 -13.934948) (xy 34.8361 -14.478) (xy 22.1488 -14.478) (xy 22.1488 -15.5321)
				(xy 11.684 -15.5321) (xy 11.684 -14.478) (xy -0.635 -14.478) (xy -0.635 -7.801356) (xy -0.9398 -7.801356)
				(xy -0.9398 -15.7226) (xy 35.56 -15.7226) (xy 35.56 3.800094)
			)
			(stroke
				(width 0)
				(type default)
			)
			(fill yes)
			(layer "F.SilkS")
		)
		(fp_poly
			(pts
				(arc
					(start 34.453576 -13.208)
					(mid 34.199576 -12.954)
					(end 33.945576 -13.208)
				)
				(arc
					(start 33.945576 -13.716)
					(mid 34.199576 -13.97)
					(end 34.453576 -13.716)
				)
			)
			(stroke
				(width 0)
				(type default)
			)
			(fill yes)
			(layer "F.SilkS")
		)
		(fp_poly
			(pts
				(arc
					(start 32.653478 2.032)
					(mid 32.399478 2.286)
					(end 32.145478 2.032)
				)
				(arc
					(start 32.145478 1.524)
					(mid 32.399478 1.27)
					(end 32.653478 1.524)
				)
			)
			(stroke
				(width 0)
				(type default)
			)
			(fill yes)
			(layer "F.SilkS")
		)
		(fp_poly
			(pts
				(arc
					(start 30.853634 -13.208)
					(mid 30.599634 -12.954)
					(end 30.345634 -13.208)
				)
				(arc
					(start 30.345634 -13.716)
					(mid 30.599634 -13.97)
					(end 30.853634 -13.716)
				)
			)
			(stroke
				(width 0)
				(type default)
			)
			(fill yes)
			(layer "F.SilkS")
		)
		(fp_poly
			(pts
				(arc
					(start 29.053536 2.032)
					(mid 28.799536 2.286)
					(end 28.545536 2.032)
				)
				(arc
					(start 28.545536 1.524)
					(mid 28.799536 1.27)
					(end 29.053536 1.524)
				)
			)
			(stroke
				(width 0)
				(type default)
			)
			(fill yes)
			(layer "F.SilkS")
		)
		(fp_poly
			(pts
				(arc
					(start 27.253692 -13.208)
					(mid 26.999692 -12.954)
					(end 26.745692 -13.208)
				)
				(arc
					(start 26.745692 -13.716)
					(mid 26.999692 -13.97)
					(end 27.253692 -13.716)
				)
			)
			(stroke
				(width 0)
				(type default)
			)
			(fill yes)
			(layer "F.SilkS")
		)
		(fp_poly
			(pts
				(arc
					(start 25.453594 2.032)
					(mid 25.199594 2.286)
					(end 24.945594 2.032)
				)
				(arc
					(start 24.945594 1.524)
					(mid 25.199594 1.27)
					(end 25.453594 1.524)
				)
			)
			(stroke
				(width 0)
				(type default)
			)
			(fill yes)
			(layer "F.SilkS")
		)
		(fp_poly
			(pts
				(arc
					(start 23.65375 -13.208)
					(mid 23.39975 -12.954)
					(end 23.14575 -13.208)
				)
				(arc
					(start 23.14575 -13.716)
					(mid 23.39975 -13.97)
					(end 23.65375 -13.716)
				)
			)
			(stroke
				(width 0)
				(type default)
			)
			(fill yes)
			(layer "F.SilkS")
		)
		(fp_poly
			(pts
				(arc
					(start 21.853652 2.032)
					(mid 21.599652 2.286)
					(end 21.345652 2.032)
				)
				(arc
					(start 21.345652 1.524)
					(mid 21.599652 1.27)
					(end 21.853652 1.524)
				)
			)
			(stroke
				(width 0)
				(type default)
			)
			(fill yes)
			(layer "F.SilkS")
		)
		(fp_poly
			(pts
				(arc
					(start 12.853924 -13.208)
					(mid 12.599924 -12.954)
					(end 12.345924 -13.208)
				)
				(arc
					(start 12.345924 -13.716)
					(mid 12.599924 -13.97)
					(end 12.853924 -13.716)
				)
			)
			(stroke
				(width 0)
				(type default)
			)
			(fill yes)
			(layer "F.SilkS")
		)
		(fp_poly
			(pts
				(arc
					(start 11.053826 2.032)
					(mid 10.799826 2.286)
					(end 10.545826 2.032)
				)
				(arc
					(start 10.545826 1.524)
					(mid 10.799826 1.27)
					(end 11.053826 1.524)
				)
			)
			(stroke
				(width 0)
				(type default)
			)
			(fill yes)
			(layer "F.SilkS")
		)
		(fp_poly
			(pts
				(arc
					(start 9.253982 -13.208)
					(mid 8.999982 -12.954)
					(end 8.745982 -13.208)
				)
				(arc
					(start 8.745982 -13.716)
					(mid 8.999982 -13.97)
					(end 9.253982 -13.716)
				)
			)
			(stroke
				(width 0)
				(type default)
			)
			(fill yes)
			(layer "F.SilkS")
		)
		(fp_poly
			(pts
				(arc
					(start 7.453884 2.032)
					(mid 7.199884 2.286)
					(end 6.945884 2.032)
				)
				(arc
					(start 6.945884 1.524)
					(mid 7.199884 1.27)
					(end 7.453884 1.524)
				)
			)
			(stroke
				(width 0)
				(type default)
			)
			(fill yes)
			(layer "F.SilkS")
		)
		(fp_poly
			(pts
				(arc
					(start 5.65404 -13.208)
					(mid 5.40004 -12.954)
					(end 5.14604 -13.208)
				)
				(arc
					(start 5.14604 -13.716)
					(mid 5.40004 -13.97)
					(end 5.65404 -13.716)
				)
			)
			(stroke
				(width 0)
				(type default)
			)
			(fill yes)
			(layer "F.SilkS")
		)
		(fp_poly
			(pts
				(arc
					(start 3.853942 2.032)
					(mid 3.599942 2.286)
					(end 3.345942 2.032)
				)
				(arc
					(start 3.345942 1.524)
					(mid 3.599942 1.27)
					(end 3.853942 1.524)
				)
			)
			(stroke
				(width 0)
				(type default)
			)
			(fill yes)
			(layer "F.SilkS")
		)
		(fp_poly
			(pts
				(arc
					(start 2.054098 -13.208)
					(mid 1.800098 -12.954)
					(end 1.546098 -13.208)
				)
				(arc
					(start 1.546098 -13.716)
					(mid 1.800098 -13.97)
					(end 2.054098 -13.716)
				)
			)
			(stroke
				(width 0)
				(type default)
			)
			(fill yes)
			(layer "F.SilkS")
		)
		(fp_poly
			(pts
				(arc
					(start 0.254 2.032)
					(mid 0 2.286)
					(end -0.254 2.032)
				)
				(arc
					(start -0.254 1.524)
					(mid 0 1.27)
					(end 0.254 1.524)
				)
			)
			(stroke
				(width 0)
				(type default)
			)
			(fill yes)
			(layer "F.SilkS")
		)
		(fp_rect
			(start -5.3848 7.6962)
			(end 39.5732 -18.6944)
			(stroke
				(width 0)
				(type default)
			)
			(fill no)
			(layer "B.CrtYd")
		)
		(fp_poly
			(pts
				(xy 15.2908 36.5506) (xy 15.2908 14.5542) (xy -0.6858 14.5542) (xy -0.6858 -15.4686) (xy 35.306 -15.4686)
				(xy 35.306 14.5542) (xy 18.9738 14.5542) (xy 18.9738 36.5506)
			)
			(stroke
				(width 0)
				(type default)
			)
			(fill no)
			(layer "F.CrtYd")
		)
		(fp_poly
			(pts
				(xy 14.7828 37.0586) (xy 14.7828 15.0622) (xy -1.1938 15.0622) (xy -1.1938 -15.9766) (xy 35.814 -15.9766)
				(xy 35.814 0) (xy 35.306 0) (xy 35.306 -15.4686) (xy -0.6858 -15.4686) (xy -0.6858 14.5542) (xy 15.2908 14.5542)
				(xy 15.2908 36.5506) (xy 18.9738 36.5506) (xy 18.9738 14.5542) (xy 35.306 14.5542) (xy 35.306 0.0127)
				(xy 35.814 0.0127) (xy 35.814 15.0622) (xy 19.4818 15.0622) (xy 19.4818 37.0586)
			)
			(stroke
				(width 0)
				(type default)
			)
			(fill no)
			(layer "F.CrtYd")
		)
		(fp_poly
			(pts
				(xy 10.287 41.5544) (xy 10.287 19.558) (xy -5.6896 19.558) (xy -5.6896 -20.4724) (xy 40.3098 -20.4724)
				(xy 40.3098 0) (xy 35.814 0) (xy 35.814 -15.9766) (xy -1.1938 -15.9766) (xy -1.1938 15.0622) (xy 14.7828 15.0622)
				(xy 14.7828 37.0586) (xy 19.4818 37.0586) (xy 19.4818 15.0622) (xy 35.814 15.0622) (xy 35.814 0.0127)
				(xy 40.3098 0.0127) (xy 40.3098 19.558) (xy 23.9776 19.558) (xy 23.9776 41.5544)
			)
			(stroke
				(width 0)
				(type default)
			)
			(fill no)
			(layer "F.CrtYd")
		)
		(fp_rect
			(start -5.3848 7.6962)
			(end 39.5732 -18.6944)
			(stroke
				(width 0)
				(type default)
			)
			(fill no)
			(layer "B.Fab")
		)
		(fp_rect
			(start -10.3886 12.7)
			(end 44.577 -23.6982)
			(stroke
				(width 0)
				(type default)
			)
			(fill no)
			(layer "B.Fab")
		)
		(fp_poly
			(pts
				(xy 14.7828 37.0586) (xy 14.7828 15.0622) (xy -1.1938 15.0622) (xy -1.1938 -15.9766) (xy 35.814 -15.9766)
				(xy 35.814 15.0622) (xy 19.4818 15.0622) (xy 19.4818 37.0586)
			)
			(stroke
				(width 0)
				(type default)
			)
			(fill no)
			(layer "F.Fab")
		)
		(fp_poly
			(pts
				(xy 10.287 41.5544) (xy 10.287 19.558) (xy -5.6896 19.558) (xy -5.6896 -20.4724) (xy 40.3098 -20.4724)
				(xy 40.3098 19.558) (xy 23.9776 19.558) (xy 23.9776 41.5544)
			)
			(stroke
				(width 0)
				(type default)
			)
			(fill no)
			(layer "F.Fab")
		)
		(fp_poly
			(pts
				(xy 5.2832 46.5582) (xy 5.2832 24.5618) (xy -10.6934 24.5618) (xy -10.6934 -25.4762) (xy 45.3136 -25.4762)
				(xy 45.3136 24.5618) (xy 28.9814 24.5618) (xy 28.9814 46.5582)
			)
			(stroke
				(width 0)
				(type default)
			)
			(fill no)
			(layer "F.Fab")
		)
		(fp_text user "Press Fit"
			(at 11.7856 -14.70533 180)
			(unlocked yes)
			(layer "F.SilkS")
			(effects
				(font
					(size 1.016 1.016)
					(thickness 0.1524)
				)
				(justify left)
			)
		)
		(fp_text user "Slit"
			(at 3.37947 7.258304 180)
			(unlocked yes)
			(layer "F.SilkS")
			(effects
				(font
					(size 1.016 1.016)
					(thickness 0.1524)
				)
				(justify left)
			)
		)
		(fp_text user "Can not place BGA,CSP,Wave Solder Component"
			(at -7.4168 10.2108 180)
			(unlocked yes)
			(layer "B.Fab")
			(effects
				(font
					(size 1.016 1.016)
					(thickness 0.1524)
				)
				(justify left)
			)
		)
		(fp_text user "High Limit 2mm"
			(at 8.0518 18.1229 180)
			(unlocked yes)
			(layer "F.Fab")
			(effects
				(font
					(size 1.016 1.016)
					(thickness 0.1524)
				)
				(justify left)
			)
		)
		(fp_text user "Can not place BGA,CSP,Wave Solder Component"
			(at -7.9756 21.9964 180)
			(unlocked yes)
			(layer "F.Fab")
			(effects
				(font
					(size 1.016 1.016)
					(thickness 0.1524)
				)
				(justify left)
			)
		)
		(pad "" np_thru_hole circle
			(at 17.135094 -9.344914 180)
			(size 0.254 0.254)
			(drill 2.4638)
			(layers "*.Cu" "*.Mask")
			(clearance 1.4605)
			(thermal_gap 1.4605)
		)
		(pad "" np_thru_hole circle
			(at 17.135094 -2.355088 180)
			(size 0.254 0.254)
			(drill 2.3876)
			(layers "*.Cu" "*.Mask")
			(clearance 1.4224)
			(thermal_gap 1.4224)
		)
		(pad "A1" thru_hole circle
			(at 0 0 180)
			(size 0.762 0.762)
			(drill 0.359918)
			(layers "*.Cu" "*.Mask")
			(remove_unused_layers no)
			(net "PCIE_COMP_TO_IOM_CLK_2_DN")
			(clearance 0.1651)
			(thermal_gap 0.1651)
		)
		(pad "A2" thru_hole circle
			(at 1.800098 1.199896 180)
			(size 0.762 0.762)
			(drill 0.359918)
			(layers "*.Cu" "*.Mask")
			(remove_unused_layers no)
			(net "I2C_DPB_MISC_SDA")
			(clearance 0.1651)
			(thermal_gap 0.1651)
		)
		(pad "A3" thru_hole circle
			(at 3.599942 0 180)
			(size 0.762 0.762)
			(drill 0.359918)
			(layers "*.Cu" "*.Mask")
			(remove_unused_layers no)
			(net "BMC_LOC_HEARTBEAT")
			(clearance 0.1651)
			(thermal_gap 0.1651)
		)
		(pad "A4" thru_hole circle
			(at 5.40004 1.199896 180)
			(size 0.762 0.762)
			(drill 0.359918)
			(layers "*.Cu" "*.Mask")
			(remove_unused_layers no)
			(net "SCC_RMT_FULL_PWR_EN")
			(clearance 0.1651)
			(thermal_gap 0.1651)
		)
		(pad "A5" thru_hole circle
			(at 7.199884 0 180)
			(size 0.762 0.762)
			(drill 0.359918)
			(layers "*.Cu" "*.Mask")
			(remove_unused_layers no)
			(net "PCIE_COMP_TO_IOM_CLK_3_DN")
			(clearance 0.1651)
			(thermal_gap 0.1651)
		)
		(pad "A6" thru_hole circle
			(at 8.999982 1.199896 180)
			(size 0.762 0.762)
			(drill 0.359918)
			(layers "*.Cu" "*.Mask")
			(remove_unused_layers no)
			(net "I2C_EXP_LOC_SDA")
			(clearance 0.1651)
			(thermal_gap 0.1651)
		)
		(pad "A7" thru_hole circle
			(at 10.80008 0 180)
			(size 0.762 0.762)
			(drill 0.359918)
			(layers "*.Cu" "*.Mask")
			(remove_unused_layers no)
			(net "P12V_IOM")
			(clearance 0.1651)
			(thermal_gap 0.1651)
		)
		(pad "A8" thru_hole circle
			(at 12.599924 1.199896 180)
			(size 0.762 0.762)
			(drill 0.359918)
			(layers "*.Cu" "*.Mask")
			(remove_unused_layers no)
			(net "P12V_IOM")
			(clearance 0.1651)
			(thermal_gap 0.1651)
		)
		(pad "A9" thru_hole circle
			(at 21.599906 0 180)
			(size 0.762 0.762)
			(drill 0.359918)
			(layers "*.Cu" "*.Mask")
			(remove_unused_layers no)
			(net "PCIE_COMP_TO_IOM_CLK_4_DN")
			(clearance 0.1651)
			(thermal_gap 0.1651)
		)
		(pad "A10" thru_hole circle
			(at 23.400004 1.199896 180)
			(size 0.762 0.762)
			(drill 0.359918)
			(layers "*.Cu" "*.Mask")
			(remove_unused_layers no)
			(net "SLOTID_1")
			(clearance 0.1651)
			(thermal_gap 0.1651)
		)
		(pad "A11" thru_hole circle
			(at 25.200102 0 180)
			(size 0.762 0.762)
			(drill 0.359918)
			(layers "*.Cu" "*.Mask")
			(remove_unused_layers no)
			(net "BMC_TO_EXP_RESET_N")
			(clearance 0.1651)
			(thermal_gap 0.1651)
		)
		(pad "A12" thru_hole circle
			(at 26.999946 1.199896 180)
			(size 0.762 0.762)
			(drill 0.359918)
			(layers "*.Cu" "*.Mask")
			(remove_unused_layers no)
			(net "USB_COMP_DN")
			(clearance 0.1651)
			(thermal_gap 0.1651)
		)
		(pad "A13" thru_hole circle
			(at 28.800044 0 180)
			(size 0.762 0.762)
			(drill 0.359918)
			(layers "*.Cu" "*.Mask")
			(remove_unused_layers no)
			(net "COMP_TO_BMC_RESET")
			(clearance 0.1651)
			(thermal_gap 0.1651)
		)
		(pad "A14" thru_hole circle
			(at 30.599888 1.199896 180)
			(size 0.762 0.762)
			(drill 0.359918)
			(layers "*.Cu" "*.Mask")
			(remove_unused_layers no)
			(net "I2C_DPB_SDA")
			(clearance 0.1651)
			(thermal_gap 0.1651)
		)
		(pad "A15" thru_hole circle
			(at 32.399986 0 180)
			(size 0.762 0.762)
			(drill 0.359918)
			(layers "*.Cu" "*.Mask")
			(remove_unused_layers no)
			(net "EXP_SPARE_1")
			(clearance 0.1651)
			(thermal_gap 0.1651)
		)
		(pad "A16" thru_hole circle
			(at 34.200084 1.199896 180)
			(size 0.762 0.762)
			(drill 0.359918)
			(layers "*.Cu" "*.Mask")
			(remove_unused_layers no)
			(net "COMP_SPARE_1")
			(clearance 0.1651)
			(thermal_gap 0.1651)
		)
		(pad "B1" thru_hole circle
			(at 0 -1.400048 180)
			(size 0.762 0.762)
			(drill 0.359918)
			(layers "*.Cu" "*.Mask")
			(remove_unused_layers no)
			(net "PCIE_COMP_TO_IOM_CLK_2_DP")
			(clearance 0.1651)
			(thermal_gap 0.1651)
		)
		(pad "B2" thru_hole circle
			(at 1.800098 -0.199898 180)
			(size 0.762 0.762)
			(drill 0.359918)
			(layers "*.Cu" "*.Mask")
			(remove_unused_layers no)
			(net "I2C_DPB_MISC_SCL")
			(clearance 0.1651)
			(thermal_gap 0.1651)
		)
		(pad "B3" thru_hole circle
			(at 3.599942 -1.400048 180)
			(size 0.762 0.762)
			(drill 0.359918)
			(layers "*.Cu" "*.Mask")
			(remove_unused_layers no)
			(net "BMC_RMT_HEARTBEAT")
			(clearance 0.1651)
			(thermal_gap 0.1651)
		)
		(pad "B4" thru_hole circle
			(at 5.40004 -0.199898 180)
			(size 0.762 0.762)
			(drill 0.359918)
			(layers "*.Cu" "*.Mask")
			(remove_unused_layers no)
			(net "SCC_LOC_FULL_PWR_EN")
			(clearance 0.1651)
			(thermal_gap 0.1651)
		)
		(pad "B5" thru_hole circle
			(at 7.199884 -1.400048 180)
			(size 0.762 0.762)
			(drill 0.359918)
			(layers "*.Cu" "*.Mask")
			(remove_unused_layers no)
			(net "PCIE_COMP_TO_IOM_CLK_3_DP")
			(clearance 0.1651)
			(thermal_gap 0.1651)
		)
		(pad "B6" thru_hole circle
			(at 8.999982 -0.199898 180)
			(size 0.762 0.762)
			(drill 0.359918)
			(layers "*.Cu" "*.Mask")
			(remove_unused_layers no)
			(net "I2C_EXP_LOC_SCL")
			(clearance 0.1651)
			(thermal_gap 0.1651)
		)
		(pad "B7" thru_hole circle
			(at 10.80008 -1.400048 180)
			(size 0.762 0.762)
			(drill 0.359918)
			(layers "*.Cu" "*.Mask")
			(remove_unused_layers no)
			(net "P12V_A_PGOOD")
			(clearance 0.1651)
			(thermal_gap 0.1651)
		)
		(pad "B8" thru_hole circle
			(at 12.599924 -0.199898 180)
			(size 0.762 0.762)
			(drill 0.359918)
			(layers "*.Cu" "*.Mask")
			(remove_unused_layers no)
			(net "P12V_IOM")
			(clearance 0.1651)
			(thermal_gap 0.1651)
		)
		(pad "B9" thru_hole circle
			(at 21.599906 -1.400048 180)
			(size 0.762 0.762)
			(drill 0.359918)
			(layers "*.Cu" "*.Mask")
			(remove_unused_layers no)
			(net "PCIE_COMP_TO_IOM_CLK_4_DP")
			(clearance 0.1651)
			(thermal_gap 0.1651)
		)
		(pad "B10" thru_hole circle
			(at 23.400004 -0.199898 180)
			(size 0.762 0.762)
			(drill 0.359918)
			(layers "*.Cu" "*.Mask")
			(remove_unused_layers no)
			(net "SLOTID_0")
			(clearance 0.1651)
			(thermal_gap 0.1651)
		)
		(pad "B11" thru_hole circle
			(at 25.200102 -1.400048 180)
			(size 0.762 0.762)
			(drill 0.359918)
			(layers "*.Cu" "*.Mask")
			(remove_unused_layers no)
			(net "DPB_MISC_ALERT")
			(clearance 0.1651)
			(thermal_gap 0.1651)
		)
		(pad "B12" thru_hole circle
			(at 26.999946 -0.199898 180)
			(size 0.762 0.762)
			(drill 0.359918)
			(layers "*.Cu" "*.Mask")
			(remove_unused_layers no)
			(net "USB_COMP_DP")
			(clearance 0.1651)
			(thermal_gap 0.1651)
		)
		(pad "B13" thru_hole circle
			(at 28.800044 -1.400048 180)
			(size 0.762 0.762)
			(drill 0.359918)
			(layers "*.Cu" "*.Mask")
			(remove_unused_layers no)
			(net "SYS_RESET_N")
			(clearance 0.1651)
			(thermal_gap 0.1651)
		)
		(pad "B14" thru_hole circle
			(at 30.599888 -0.199898 180)
			(size 0.762 0.762)
			(drill 0.359918)
			(layers "*.Cu" "*.Mask")
			(remove_unused_layers no)
			(net "I2C_DPB_SCL")
			(clearance 0.1651)
			(thermal_gap 0.1651)
		)
		(pad "B15" thru_hole circle
			(at 32.399986 -1.400048 180)
			(size 0.762 0.762)
			(drill 0.359918)
			(layers "*.Cu" "*.Mask")
			(remove_unused_layers no)
			(net "EXP_SPARE_0")
			(clearance 0.1651)
			(thermal_gap 0.1651)
		)
		(pad "B16" thru_hole circle
			(at 34.200084 -0.199898 180)
			(size 0.762 0.762)
			(drill 0.359918)
			(layers "*.Cu" "*.Mask")
			(remove_unused_layers no)
			(net "COMP_SPARE_0")
			(clearance 0.1651)
			(thermal_gap 0.1651)
		)
		(pad "C1" thru_hole circle
			(at 0 -3.599942 180)
			(size 0.762 0.762)
			(drill 0.359918)
			(layers "*.Cu" "*.Mask")
			(remove_unused_layers no)
			(net "IOM_MATED_N")
			(clearance 0.1651)
			(thermal_gap 0.1651)
		)
		(pad "C2" thru_hole circle
			(at 1.800098 -2.400046 180)
			(size 0.762 0.762)
			(drill 0.359918)
			(layers "*.Cu" "*.Mask")
			(remove_unused_layers no)
			(net "I2C_SCC_SDA")
			(clearance 0.1651)
			(thermal_gap 0.1651)
		)
		(pad "C3" thru_hole circle
			(at 3.599942 -3.599942 180)
			(size 0.762 0.762)
			(drill 0.359918)
			(layers "*.Cu" "*.Mask")
			(remove_unused_layers no)
			(net "SCC_RMT_HEARTBEAT")
			(clearance 0.1651)
			(thermal_gap 0.1651)
		)
		(pad "C4" thru_hole circle
			(at 5.40004 -2.400046 180)
			(size 0.762 0.762)
			(drill 0.359918)
			(layers "*.Cu" "*.Mask")
			(remove_unused_layers no)
			(net "SYS_PWR_LED")
			(clearance 0.1651)
			(thermal_gap 0.1651)
		)
		(pad "C5" thru_hole circle
			(at 7.199884 -3.599942 180)
			(size 0.762 0.762)
			(drill 0.359918)
			(layers "*.Cu" "*.Mask")
			(remove_unused_layers no)
			(net "IOM_LOC_INS_N")
			(clearance 0.1651)
			(thermal_gap 0.1651)
		)
		(pad "C6" thru_hole circle
			(at 8.999982 -2.400046 180)
			(size 0.762 0.762)
			(drill 0.359918)
			(layers "*.Cu" "*.Mask")
			(remove_unused_layers no)
			(net "I2C_EXP_RMT_SDA")
			(clearance 0.1651)
			(thermal_gap 0.1651)
		)
		(pad "C7" thru_hole circle
			(at 10.80008 -3.599942 180)
			(size 0.762 0.762)
			(drill 0.359918)
			(layers "*.Cu" "*.Mask")
			(remove_unused_layers no)
			(net "UART_SDB_RX")
			(clearance 0.1651)
			(thermal_gap 0.1651)
		)
		(pad "C8" thru_hole circle
			(at 12.599924 -2.400046 180)
			(size 0.762 0.762)
			(drill 0.359918)
			(layers "*.Cu" "*.Mask")
			(remove_unused_layers no)
			(net "P12V_IOM")
			(clearance 0.1651)
			(thermal_gap 0.1651)
		)
		(pad "C9" thru_hole circle
			(at 21.599906 -3.599942 180)
			(size 0.762 0.762)
			(drill 0.359918)
			(layers "*.Cu" "*.Mask")
			(remove_unused_layers no)
			(net "I2C_BMC_COMP_ALERT_N")
			(clearance 0.1651)
			(thermal_gap 0.1651)
		)
		(pad "C10" thru_hole circle
			(at 23.400004 -2.400046 180)
			(size 0.762 0.762)
			(drill 0.359918)
			(layers "*.Cu" "*.Mask")
			(remove_unused_layers no)
			(net "I2C_BMC_COMP_SDA")
			(clearance 0.1651)
			(thermal_gap 0.1651)
		)
		(pad "C11" thru_hole circle
			(at 25.200102 -3.599942 180)
			(size 0.762 0.762)
			(drill 0.359918)
			(layers "*.Cu" "*.Mask")
			(remove_unused_layers no)
			(net "UART_COMP_RX")
			(clearance 0.1651)
			(thermal_gap 0.1651)
		)
		(pad "C12" thru_hole circle
			(at 26.999946 -2.400046 180)
			(size 0.762 0.762)
			(drill 0.359918)
			(layers "*.Cu" "*.Mask")
			(remove_unused_layers no)
			(net "COMP_PWR_EN")
			(clearance 0.1651)
			(thermal_gap 0.1651)
		)
		(pad "C13" thru_hole circle
			(at 28.800044 -3.599942 180)
			(size 0.762 0.762)
			(drill 0.359918)
			(layers "*.Cu" "*.Mask")
			(remove_unused_layers no)
			(net "COMP_POWER_FAIL_N")
			(clearance 0.1651)
			(thermal_gap 0.1651)
		)
		(pad "C14" thru_hole circle
			(at 30.599888 -2.400046 180)
			(size 0.762 0.762)
			(drill 0.359918)
			(layers "*.Cu" "*.Mask")
			(remove_unused_layers no)
			(net "Net_79")
			(clearance 0.1651)
			(thermal_gap 0.1651)
		)
		(pad "C15" thru_hole circle
			(at 32.399986 -3.599942 180)
			(size 0.762 0.762)
			(drill 0.359918)
			(layers "*.Cu" "*.Mask")
			(remove_unused_layers no)
			(net "Net_190")
			(clearance 0.1651)
			(thermal_gap 0.1651)
		)
		(pad "C16" thru_hole circle
			(at 34.200084 -2.400046 180)
			(size 0.762 0.762)
			(drill 0.359918)
			(layers "*.Cu" "*.Mask")
			(remove_unused_layers no)
			(net "PWM_OUT_ZONE_C")
			(clearance 0.1651)
			(thermal_gap 0.1651)
		)
		(pad "D1" thru_hole circle
			(at 0 -4.99999 180)
			(size 0.762 0.762)
			(drill 0.359918)
			(layers "*.Cu" "*.Mask")
			(remove_unused_layers no)
			(net "PCIE_COMP_TO_IOM_RST_2")
			(clearance 0.1651)
			(thermal_gap 0.1651)
		)
		(pad "D2" thru_hole circle
			(at 1.800098 -3.800094 180)
			(size 0.762 0.762)
			(drill 0.359918)
			(layers "*.Cu" "*.Mask")
			(remove_unused_layers no)
			(net "I2C_SCC_SCL")
			(clearance 0.1651)
			(thermal_gap 0.1651)
		)
		(pad "D3" thru_hole circle
			(at 3.599942 -4.99999 180)
			(size 0.762 0.762)
			(drill 0.359918)
			(layers "*.Cu" "*.Mask")
			(remove_unused_layers no)
			(net "SCC_LOC_HEARTBEAT")
			(clearance 0.1651)
			(thermal_gap 0.1651)
		)
		(pad "D4" thru_hole circle
			(at 5.40004 -3.800094 180)
			(size 0.762 0.762)
			(drill 0.359918)
			(layers "*.Cu" "*.Mask")
			(remove_unused_layers no)
			(net "SCC_STBY_PWR_EN")
			(clearance 0.1651)
			(thermal_gap 0.1651)
		)
		(pad "D5" thru_hole circle
			(at 7.199884 -4.99999 180)
			(size 0.762 0.762)
			(drill 0.359918)
			(layers "*.Cu" "*.Mask")
			(remove_unused_layers no)
			(net "PCIE_COMP_TO_IOM_RST_3")
			(clearance 0.1651)
			(thermal_gap 0.1651)
		)
		(pad "D6" thru_hole circle
			(at 8.999982 -3.800094 180)
			(size 0.762 0.762)
			(drill 0.359918)
			(layers "*.Cu" "*.Mask")
			(remove_unused_layers no)
			(net "I2C_EXP_RMT_SCL")
			(clearance 0.1651)
			(thermal_gap 0.1651)
		)
		(pad "D7" thru_hole circle
			(at 10.80008 -4.99999 180)
			(size 0.762 0.762)
			(drill 0.359918)
			(layers "*.Cu" "*.Mask")
			(remove_unused_layers no)
			(net "UART_SDB_TX")
			(clearance 0.1651)
			(thermal_gap 0.1651)
		)
		(pad "D8" thru_hole circle
			(at 12.599924 -3.800094 180)
			(size 0.762 0.762)
			(drill 0.359918)
			(layers "*.Cu" "*.Mask")
			(remove_unused_layers no)
			(net "P12V_IOM")
			(clearance 0.1651)
			(thermal_gap 0.1651)
		)
		(pad "D9" thru_hole circle
			(at 21.599906 -4.99999 180)
			(size 0.762 0.762)
			(drill 0.359918)
			(layers "*.Cu" "*.Mask")
			(remove_unused_layers no)
			(net "PCIE_COMP_TO_IOM_RST_4")
			(clearance 0.1651)
			(thermal_gap 0.1651)
		)
		(pad "D10" thru_hole circle
			(at 23.400004 -3.800094 180)
			(size 0.762 0.762)
			(drill 0.359918)
			(layers "*.Cu" "*.Mask")
			(remove_unused_layers no)
			(net "I2C_BMC_COMP_SCL")
			(clearance 0.1651)
			(thermal_gap 0.1651)
		)
		(pad "D11" thru_hole circle
			(at 25.200102 -4.99999 180)
			(size 0.762 0.762)
			(drill 0.359918)
			(layers "*.Cu" "*.Mask")
			(remove_unused_layers no)
			(net "UART_COMP_TX")
			(clearance 0.1651)
			(thermal_gap 0.1651)
		)
		(pad "D12" thru_hole circle
			(at 26.999946 -3.800094 180)
			(size 0.762 0.762)
			(drill 0.359918)
			(layers "*.Cu" "*.Mask")
			(remove_unused_layers no)
			(net "SCC_RMT_TYPE_0")
			(clearance 0.1651)
			(thermal_gap 0.1651)
		)
		(pad "D13" thru_hole circle
			(at 28.800044 -4.99999 180)
			(size 0.762 0.762)
			(drill 0.359918)
			(layers "*.Cu" "*.Mask")
			(remove_unused_layers no)
			(net "COMP_FAST_THROTTLE_N")
			(clearance 0.1651)
			(thermal_gap 0.1651)
		)
		(pad "D14" thru_hole circle
			(at 30.599888 -3.800094 180)
			(size 0.762 0.762)
			(drill 0.359918)
			(layers "*.Cu" "*.Mask")
			(remove_unused_layers no)
			(net "COMP_PWR_BTN_N")
			(clearance 0.1651)
			(thermal_gap 0.1651)
		)
		(pad "D15" thru_hole circle
			(at 32.399986 -4.99999 180)
			(size 0.762 0.762)
			(drill 0.359918)
			(layers "*.Cu" "*.Mask")
			(remove_unused_layers no)
			(net "ENCL_FAULT_LED")
			(clearance 0.1651)
			(thermal_gap 0.1651)
		)
		(pad "D16" thru_hole circle
			(at 34.200084 -3.800094 180)
			(size 0.762 0.762)
			(drill 0.359918)
			(layers "*.Cu" "*.Mask")
			(remove_unused_layers no)
			(net "PWM_OUT_ZONE_D")
			(clearance 0.1651)
			(thermal_gap 0.1651)
		)
		(pad "E1" thru_hole circle
			(at 0 -7.199884 180)
			(size 0.762 0.762)
			(drill 0.359918)
			(layers "*.Cu" "*.Mask")
			(remove_unused_layers no)
			(net "PCIE_IOM_TO_COMP_8_DN")
			(clearance 0.1651)
			(thermal_gap 0.1651)
		)
		(pad "E2" thru_hole circle
			(at 1.800098 -5.999988 180)
			(size 0.762 0.762)
			(drill 0.359918)
			(layers "*.Cu" "*.Mask")
			(remove_unused_layers no)
			(net "PCIE_IOM_TO_COMP_9_DN")
			(clearance 0.1651)
			(thermal_gap 0.1651)
		)
		(pad "E3" thru_hole circle
			(at 3.599942 -7.199884 180)
			(size 0.762 0.762)
			(drill 0.359918)
			(layers "*.Cu" "*.Mask")
			(remove_unused_layers no)
			(net "PCIE_IOM_TO_COMP_10_DN")
			(clearance 0.1651)
			(thermal_gap 0.1651)
		)
		(pad "E4" thru_hole circle
			(at 5.40004 -5.999988 180)
			(size 0.762 0.762)
			(drill 0.359918)
			(layers "*.Cu" "*.Mask")
			(remove_unused_layers no)
			(net "PCIE_IOM_TO_COMP_11_DN")
			(clearance 0.1651)
			(thermal_gap 0.1651)
		)
		(pad "E5" thru_hole circle
			(at 7.199884 -7.199884 180)
			(size 0.762 0.762)
			(drill 0.359918)
			(layers "*.Cu" "*.Mask")
			(remove_unused_layers no)
			(net "PCIE_IOM_TO_COMP_12_DN")
			(clearance 0.1651)
			(thermal_gap 0.1651)
		)
		(pad "E6" thru_hole circle
			(at 8.999982 -5.999988 180)
			(size 0.762 0.762)
			(drill 0.359918)
			(layers "*.Cu" "*.Mask")
			(remove_unused_layers no)
			(net "PCIE_IOM_TO_COMP_13_DN")
			(clearance 0.1651)
			(thermal_gap 0.1651)
		)
		(pad "E7" thru_hole circle
			(at 10.80008 -7.199884 180)
			(size 0.762 0.762)
			(drill 0.359918)
			(layers "*.Cu" "*.Mask")
			(remove_unused_layers no)
			(net "PCIE_IOM_TO_COMP_14_DN")
			(clearance 0.1651)
			(thermal_gap 0.1651)
		)
		(pad "E8" thru_hole circle
			(at 12.599924 -5.999988 180)
			(size 0.762 0.762)
			(drill 0.359918)
			(layers "*.Cu" "*.Mask")
			(remove_unused_layers no)
			(net "PCIE_IOM_TO_COMP_15_DN")
			(clearance 0.1651)
			(thermal_gap 0.1651)
		)
		(pad "E9" thru_hole circle
			(at 21.599906 -7.199884 180)
			(size 0.762 0.762)
			(drill 0.359918)
			(layers "*.Cu" "*.Mask")
			(remove_unused_layers no)
			(net "PCIE_IOM_TO_COMP_16_DN")
			(clearance 0.1651)
			(thermal_gap 0.1651)
		)
		(pad "E10" thru_hole circle
			(at 23.400004 -5.999988 180)
			(size 0.762 0.762)
			(drill 0.359918)
			(layers "*.Cu" "*.Mask")
			(remove_unused_layers no)
			(net "PCIE_IOM_TO_COMP_17_DN")
			(clearance 0.1651)
			(thermal_gap 0.1651)
		)
		(pad "E11" thru_hole circle
			(at 25.200102 -7.199884 180)
			(size 0.762 0.762)
			(drill 0.359918)
			(layers "*.Cu" "*.Mask")
			(remove_unused_layers no)
			(net "PCIE_IOM_TO_COMP_18_DN")
			(clearance 0.1651)
			(thermal_gap 0.1651)
		)
		(pad "E12" thru_hole circle
			(at 26.999946 -5.999988 180)
			(size 0.762 0.762)
			(drill 0.359918)
			(layers "*.Cu" "*.Mask")
			(remove_unused_layers no)
			(net "PCIE_IOM_TO_COMP_19_DN")
			(clearance 0.1651)
			(thermal_gap 0.1651)
		)
		(pad "E13" thru_hole circle
			(at 28.800044 -7.199884 180)
			(size 0.762 0.762)
			(drill 0.359918)
			(layers "*.Cu" "*.Mask")
			(remove_unused_layers no)
			(net "PCIE_IOM_TO_COMP_20_DN")
			(clearance 0.1651)
			(thermal_gap 0.1651)
		)
		(pad "E14" thru_hole circle
			(at 30.599888 -5.999988 180)
			(size 0.762 0.762)
			(drill 0.359918)
			(layers "*.Cu" "*.Mask")
			(remove_unused_layers no)
			(net "PCIE_IOM_TO_COMP_21_DN")
			(clearance 0.1651)
			(thermal_gap 0.1651)
		)
		(pad "E15" thru_hole circle
			(at 32.399986 -7.199884 180)
			(size 0.762 0.762)
			(drill 0.359918)
			(layers "*.Cu" "*.Mask")
			(remove_unused_layers no)
			(net "PCIE_IOM_TO_COMP_22_DN")
			(clearance 0.1651)
			(thermal_gap 0.1651)
		)
		(pad "E16" thru_hole circle
			(at 34.200084 -5.999988 180)
			(size 0.762 0.762)
			(drill 0.359918)
			(layers "*.Cu" "*.Mask")
			(remove_unused_layers no)
			(net "PCIE_IOM_TO_COMP_23_DN")
			(clearance 0.1651)
			(thermal_gap 0.1651)
		)
		(pad "F1" thru_hole circle
			(at 0 -8.599932 180)
			(size 0.762 0.762)
			(drill 0.359918)
			(layers "*.Cu" "*.Mask")
			(remove_unused_layers no)
			(net "PCIE_IOM_TO_COMP_8_DP")
			(clearance 0.1651)
			(thermal_gap 0.1651)
		)
		(pad "F2" thru_hole circle
			(at 1.800098 -7.400036 180)
			(size 0.762 0.762)
			(drill 0.359918)
			(layers "*.Cu" "*.Mask")
			(remove_unused_layers no)
			(net "PCIE_IOM_TO_COMP_9_DP")
			(clearance 0.1651)
			(thermal_gap 0.1651)
		)
		(pad "F3" thru_hole circle
			(at 3.599942 -8.599932 180)
			(size 0.762 0.762)
			(drill 0.359918)
			(layers "*.Cu" "*.Mask")
			(remove_unused_layers no)
			(net "PCIE_IOM_TO_COMP_10_DP")
			(clearance 0.1651)
			(thermal_gap 0.1651)
		)
		(pad "F4" thru_hole circle
			(at 5.40004 -7.400036 180)
			(size 0.762 0.762)
			(drill 0.359918)
			(layers "*.Cu" "*.Mask")
			(remove_unused_layers no)
			(net "PCIE_IOM_TO_COMP_11_DP")
			(clearance 0.1651)
			(thermal_gap 0.1651)
		)
		(pad "F5" thru_hole circle
			(at 7.199884 -8.599932 180)
			(size 0.762 0.762)
			(drill 0.359918)
			(layers "*.Cu" "*.Mask")
			(remove_unused_layers no)
			(net "PCIE_IOM_TO_COMP_12_DP")
			(clearance 0.1651)
			(thermal_gap 0.1651)
		)
		(pad "F6" thru_hole circle
			(at 8.999982 -7.400036 180)
			(size 0.762 0.762)
			(drill 0.359918)
			(layers "*.Cu" "*.Mask")
			(remove_unused_layers no)
			(net "PCIE_IOM_TO_COMP_13_DP")
			(clearance 0.1651)
			(thermal_gap 0.1651)
		)
		(pad "F7" thru_hole circle
			(at 10.80008 -8.599932 180)
			(size 0.762 0.762)
			(drill 0.359918)
			(layers "*.Cu" "*.Mask")
			(remove_unused_layers no)
			(net "PCIE_IOM_TO_COMP_14_DP")
			(clearance 0.1651)
			(thermal_gap 0.1651)
		)
		(pad "F8" thru_hole circle
			(at 12.599924 -7.400036 180)
			(size 0.762 0.762)
			(drill 0.359918)
			(layers "*.Cu" "*.Mask")
			(remove_unused_layers no)
			(net "PCIE_IOM_TO_COMP_15_DP")
			(clearance 0.1651)
			(thermal_gap 0.1651)
		)
		(pad "F9" thru_hole circle
			(at 21.599906 -8.599932 180)
			(size 0.762 0.762)
			(drill 0.359918)
			(layers "*.Cu" "*.Mask")
			(remove_unused_layers no)
			(net "PCIE_IOM_TO_COMP_16_DP")
			(clearance 0.1651)
			(thermal_gap 0.1651)
		)
		(pad "F10" thru_hole circle
			(at 23.400004 -7.400036 180)
			(size 0.762 0.762)
			(drill 0.359918)
			(layers "*.Cu" "*.Mask")
			(remove_unused_layers no)
			(net "PCIE_IOM_TO_COMP_17_DP")
			(clearance 0.1651)
			(thermal_gap 0.1651)
		)
		(pad "F11" thru_hole circle
			(at 25.200102 -8.599932 180)
			(size 0.762 0.762)
			(drill 0.359918)
			(layers "*.Cu" "*.Mask")
			(remove_unused_layers no)
			(net "PCIE_IOM_TO_COMP_18_DP")
			(clearance 0.1651)
			(thermal_gap 0.1651)
		)
		(pad "F12" thru_hole circle
			(at 26.999946 -7.400036 180)
			(size 0.762 0.762)
			(drill 0.359918)
			(layers "*.Cu" "*.Mask")
			(remove_unused_layers no)
			(net "PCIE_IOM_TO_COMP_19_DP")
			(clearance 0.1651)
			(thermal_gap 0.1651)
		)
		(pad "F13" thru_hole circle
			(at 28.800044 -8.599932 180)
			(size 0.762 0.762)
			(drill 0.359918)
			(layers "*.Cu" "*.Mask")
			(remove_unused_layers no)
			(net "PCIE_IOM_TO_COMP_20_DP")
			(clearance 0.1651)
			(thermal_gap 0.1651)
		)
		(pad "F14" thru_hole circle
			(at 30.599888 -7.400036 180)
			(size 0.762 0.762)
			(drill 0.359918)
			(layers "*.Cu" "*.Mask")
			(remove_unused_layers no)
			(net "PCIE_IOM_TO_COMP_21_DP")
			(clearance 0.1651)
			(thermal_gap 0.1651)
		)
		(pad "F15" thru_hole circle
			(at 32.399986 -8.599932 180)
			(size 0.762 0.762)
			(drill 0.359918)
			(layers "*.Cu" "*.Mask")
			(remove_unused_layers no)
			(net "PCIE_IOM_TO_COMP_22_DP")
			(clearance 0.1651)
			(thermal_gap 0.1651)
		)
		(pad "F16" thru_hole circle
			(at 34.200084 -7.400036 180)
			(size 0.762 0.762)
			(drill 0.359918)
			(layers "*.Cu" "*.Mask")
			(remove_unused_layers no)
			(net "PCIE_IOM_TO_COMP_23_DP")
			(clearance 0.1651)
			(thermal_gap 0.1651)
		)
		(pad "G1" thru_hole circle
			(at 0 -10.80008 180)
			(size 0.762 0.762)
			(drill 0.359918)
			(layers "*.Cu" "*.Mask")
			(remove_unused_layers no)
			(net "PCIE_COMP_TO_IOM_8_DN")
			(clearance 0.1651)
			(thermal_gap 0.1651)
		)
		(pad "G2" thru_hole circle
			(at 1.800098 -9.59993 180)
			(size 0.762 0.762)
			(drill 0.359918)
			(layers "*.Cu" "*.Mask")
			(remove_unused_layers no)
			(net "PCIE_COMP_TO_IOM_9_DN")
			(clearance 0.1651)
			(thermal_gap 0.1651)
		)
		(pad "G3" thru_hole circle
			(at 3.599942 -10.80008 180)
			(size 0.762 0.762)
			(drill 0.359918)
			(layers "*.Cu" "*.Mask")
			(remove_unused_layers no)
			(net "PCIE_COMP_TO_IOM_10_DN")
			(clearance 0.1651)
			(thermal_gap 0.1651)
		)
		(pad "G4" thru_hole circle
			(at 5.40004 -9.59993 180)
			(size 0.762 0.762)
			(drill 0.359918)
			(layers "*.Cu" "*.Mask")
			(remove_unused_layers no)
			(net "PCIE_COMP_TO_IOM_11_DN")
			(clearance 0.1651)
			(thermal_gap 0.1651)
		)
		(pad "G5" thru_hole circle
			(at 7.199884 -10.80008 180)
			(size 0.762 0.762)
			(drill 0.359918)
			(layers "*.Cu" "*.Mask")
			(remove_unused_layers no)
			(net "PCIE_COMP_TO_IOM_12_DN")
			(clearance 0.1651)
			(thermal_gap 0.1651)
		)
		(pad "G6" thru_hole circle
			(at 8.999982 -9.59993 180)
			(size 0.762 0.762)
			(drill 0.359918)
			(layers "*.Cu" "*.Mask")
			(remove_unused_layers no)
			(net "PCIE_COMP_TO_IOM_13_DN")
			(clearance 0.1651)
			(thermal_gap 0.1651)
		)
		(pad "G7" thru_hole circle
			(at 10.80008 -10.80008 180)
			(size 0.762 0.762)
			(drill 0.359918)
			(layers "*.Cu" "*.Mask")
			(remove_unused_layers no)
			(net "PCIE_COMP_TO_IOM_14_DN")
			(clearance 0.1651)
			(thermal_gap 0.1651)
		)
		(pad "G8" thru_hole circle
			(at 12.599924 -9.59993 180)
			(size 0.762 0.762)
			(drill 0.359918)
			(layers "*.Cu" "*.Mask")
			(remove_unused_layers no)
			(net "PCIE_COMP_TO_IOM_15_DN")
			(clearance 0.1651)
			(thermal_gap 0.1651)
		)
		(pad "G9" thru_hole circle
			(at 21.599906 -10.80008 180)
			(size 0.762 0.762)
			(drill 0.359918)
			(layers "*.Cu" "*.Mask")
			(remove_unused_layers no)
			(net "PCIE_COMP_TO_IOM_16_DN")
			(clearance 0.1651)
			(thermal_gap 0.1651)
		)
		(pad "G10" thru_hole circle
			(at 23.400004 -9.59993 180)
			(size 0.762 0.762)
			(drill 0.359918)
			(layers "*.Cu" "*.Mask")
			(remove_unused_layers no)
			(net "PCIE_COMP_TO_IOM_17_DN")
			(clearance 0.1651)
			(thermal_gap 0.1651)
		)
		(pad "G11" thru_hole circle
			(at 25.200102 -10.80008 180)
			(size 0.762 0.762)
			(drill 0.359918)
			(layers "*.Cu" "*.Mask")
			(remove_unused_layers no)
			(net "PCIE_COMP_TO_IOM_18_DN")
			(clearance 0.1651)
			(thermal_gap 0.1651)
		)
		(pad "G12" thru_hole circle
			(at 26.999946 -9.59993 180)
			(size 0.762 0.762)
			(drill 0.359918)
			(layers "*.Cu" "*.Mask")
			(remove_unused_layers no)
			(net "PCIE_COMP_TO_IOM_19_DN")
			(clearance 0.1651)
			(thermal_gap 0.1651)
		)
		(pad "G13" thru_hole circle
			(at 28.800044 -10.80008 180)
			(size 0.762 0.762)
			(drill 0.359918)
			(layers "*.Cu" "*.Mask")
			(remove_unused_layers no)
			(net "PCIE_COMP_TO_IOM_20_DN")
			(clearance 0.1651)
			(thermal_gap 0.1651)
		)
		(pad "G14" thru_hole circle
			(at 30.599888 -9.59993 180)
			(size 0.762 0.762)
			(drill 0.359918)
			(layers "*.Cu" "*.Mask")
			(remove_unused_layers no)
			(net "PCIE_COMP_TO_IOM_21_DN")
			(clearance 0.1651)
			(thermal_gap 0.1651)
		)
		(pad "G15" thru_hole circle
			(at 32.399986 -10.80008 180)
			(size 0.762 0.762)
			(drill 0.359918)
			(layers "*.Cu" "*.Mask")
			(remove_unused_layers no)
			(net "PCIE_COMP_TO_IOM_22_DN")
			(clearance 0.1651)
			(thermal_gap 0.1651)
		)
		(pad "G16" thru_hole circle
			(at 34.200084 -9.59993 180)
			(size 0.762 0.762)
			(drill 0.359918)
			(layers "*.Cu" "*.Mask")
			(remove_unused_layers no)
			(net "PCIE_COMP_TO_IOM_23_DN")
			(clearance 0.1651)
			(thermal_gap 0.1651)
		)
		(pad "GND1" thru_hole circle
			(at 0 -2.500122 180)
			(size 0.762 0.762)
			(drill 0.359918)
			(layers "*.Cu" "*.Mask")
			(remove_unused_layers no)
			(net "GND")
			(clearance 0.1651)
			(thermal_gap 0.1651)
		)
		(pad "GND2" thru_hole circle
			(at 0 -6.100064 180)
			(size 0.762 0.762)
			(drill 0.359918)
			(layers "*.Cu" "*.Mask")
			(remove_unused_layers no)
			(net "GND")
			(clearance 0.1651)
			(thermal_gap 0.1651)
		)
		(pad "GND3" thru_hole circle
			(at 0 -9.700006 180)
			(size 0.762 0.762)
			(drill 0.359918)
			(layers "*.Cu" "*.Mask")
			(remove_unused_layers no)
			(net "GND")
			(clearance 0.1651)
			(thermal_gap 0.1651)
		)
		(pad "GND4" thru_hole circle
			(at 0 -13.299948 180)
			(size 0.762 0.762)
			(drill 0.359918)
			(layers "*.Cu" "*.Mask")
			(remove_unused_layers no)
			(net "GND")
			(clearance 0.1651)
			(thermal_gap 0.1651)
		)
		(pad "GND5" thru_hole circle
			(at 1.800098 2.29997 180)
			(size 0.762 0.762)
			(drill 0.359918)
			(layers "*.Cu" "*.Mask")
			(remove_unused_layers no)
			(net "GND")
			(clearance 0.1651)
			(thermal_gap 0.1651)
		)
		(pad "GND6" thru_hole circle
			(at 1.800098 -1.299972 180)
			(size 0.762 0.762)
			(drill 0.359918)
			(layers "*.Cu" "*.Mask")
			(remove_unused_layers no)
			(net "GND")
			(clearance 0.1651)
			(thermal_gap 0.1651)
		)
		(pad "GND7" thru_hole circle
			(at 1.800098 -4.899914 180)
			(size 0.762 0.762)
			(drill 0.359918)
			(layers "*.Cu" "*.Mask")
			(remove_unused_layers no)
			(net "GND")
			(clearance 0.1651)
			(thermal_gap 0.1651)
		)
		(pad "GND8" thru_hole circle
			(at 1.800098 -8.50011 180)
			(size 0.762 0.762)
			(drill 0.359918)
			(layers "*.Cu" "*.Mask")
			(remove_unused_layers no)
			(net "GND")
			(clearance 0.1651)
			(thermal_gap 0.1651)
		)
		(pad "GND9" thru_hole circle
			(at 1.800098 -12.100052 180)
			(size 0.762 0.762)
			(drill 0.359918)
			(layers "*.Cu" "*.Mask")
			(remove_unused_layers no)
			(net "GND")
			(clearance 0.1651)
			(thermal_gap 0.1651)
		)
		(pad "GND10" thru_hole circle
			(at 3.599942 -2.500122 180)
			(size 0.762 0.762)
			(drill 0.359918)
			(layers "*.Cu" "*.Mask")
			(remove_unused_layers no)
			(net "GND")
			(clearance 0.1651)
			(thermal_gap 0.1651)
		)
		(pad "GND11" thru_hole circle
			(at 3.599942 -6.100064 180)
			(size 0.762 0.762)
			(drill 0.359918)
			(layers "*.Cu" "*.Mask")
			(remove_unused_layers no)
			(net "GND")
			(clearance 0.1651)
			(thermal_gap 0.1651)
		)
		(pad "GND12" thru_hole circle
			(at 3.599942 -9.700006 180)
			(size 0.762 0.762)
			(drill 0.359918)
			(layers "*.Cu" "*.Mask")
			(remove_unused_layers no)
			(net "GND")
			(clearance 0.1651)
			(thermal_gap 0.1651)
		)
		(pad "GND13" thru_hole circle
			(at 3.599942 -13.299948 180)
			(size 0.762 0.762)
			(drill 0.359918)
			(layers "*.Cu" "*.Mask")
			(remove_unused_layers no)
			(net "GND")
			(clearance 0.1651)
			(thermal_gap 0.1651)
		)
		(pad "GND14" thru_hole circle
			(at 5.40004 2.29997 180)
			(size 0.762 0.762)
			(drill 0.359918)
			(layers "*.Cu" "*.Mask")
			(remove_unused_layers no)
			(net "GND")
			(clearance 0.1651)
			(thermal_gap 0.1651)
		)
		(pad "GND15" thru_hole circle
			(at 5.40004 -1.299972 180)
			(size 0.762 0.762)
			(drill 0.359918)
			(layers "*.Cu" "*.Mask")
			(remove_unused_layers no)
			(net "GND")
			(clearance 0.1651)
			(thermal_gap 0.1651)
		)
		(pad "GND16" thru_hole circle
			(at 5.40004 -4.899914 180)
			(size 0.762 0.762)
			(drill 0.359918)
			(layers "*.Cu" "*.Mask")
			(remove_unused_layers no)
			(net "GND")
			(clearance 0.1651)
			(thermal_gap 0.1651)
		)
		(pad "GND17" thru_hole circle
			(at 5.40004 -8.50011 180)
			(size 0.762 0.762)
			(drill 0.359918)
			(layers "*.Cu" "*.Mask")
			(remove_unused_layers no)
			(net "GND")
			(clearance 0.1651)
			(thermal_gap 0.1651)
		)
		(pad "GND18" thru_hole circle
			(at 5.40004 -12.100052 180)
			(size 0.762 0.762)
			(drill 0.359918)
			(layers "*.Cu" "*.Mask")
			(remove_unused_layers no)
			(net "GND")
			(clearance 0.1651)
			(thermal_gap 0.1651)
		)
		(pad "GND19" thru_hole circle
			(at 7.199884 -2.500122 180)
			(size 0.762 0.762)
			(drill 0.359918)
			(layers "*.Cu" "*.Mask")
			(remove_unused_layers no)
			(net "GND")
			(clearance 0.1651)
			(thermal_gap 0.1651)
		)
		(pad "GND20" thru_hole circle
			(at 7.199884 -6.100064 180)
			(size 0.762 0.762)
			(drill 0.359918)
			(layers "*.Cu" "*.Mask")
			(remove_unused_layers no)
			(net "GND")
			(clearance 0.1651)
			(thermal_gap 0.1651)
		)
		(pad "GND21" thru_hole circle
			(at 7.199884 -9.700006 180)
			(size 0.762 0.762)
			(drill 0.359918)
			(layers "*.Cu" "*.Mask")
			(remove_unused_layers no)
			(net "GND")
			(clearance 0.1651)
			(thermal_gap 0.1651)
		)
		(pad "GND22" thru_hole circle
			(at 7.199884 -13.299948 180)
			(size 0.762 0.762)
			(drill 0.359918)
			(layers "*.Cu" "*.Mask")
			(remove_unused_layers no)
			(net "GND")
			(clearance 0.1651)
			(thermal_gap 0.1651)
		)
		(pad "GND23" thru_hole circle
			(at 8.999982 2.29997 180)
			(size 0.762 0.762)
			(drill 0.359918)
			(layers "*.Cu" "*.Mask")
			(remove_unused_layers no)
			(net "GND")
			(clearance 0.1651)
			(thermal_gap 0.1651)
		)
		(pad "GND24" thru_hole circle
			(at 8.999982 -1.299972 180)
			(size 0.762 0.762)
			(drill 0.359918)
			(layers "*.Cu" "*.Mask")
			(remove_unused_layers no)
			(net "GND")
			(clearance 0.1651)
			(thermal_gap 0.1651)
		)
		(pad "GND25" thru_hole circle
			(at 8.999982 -4.899914 180)
			(size 0.762 0.762)
			(drill 0.359918)
			(layers "*.Cu" "*.Mask")
			(remove_unused_layers no)
			(net "GND")
			(clearance 0.1651)
			(thermal_gap 0.1651)
		)
		(pad "GND26" thru_hole circle
			(at 8.999982 -8.50011 180)
			(size 0.762 0.762)
			(drill 0.359918)
			(layers "*.Cu" "*.Mask")
			(remove_unused_layers no)
			(net "GND")
			(clearance 0.1651)
			(thermal_gap 0.1651)
		)
		(pad "GND27" thru_hole circle
			(at 8.999982 -12.100052 180)
			(size 0.762 0.762)
			(drill 0.359918)
			(layers "*.Cu" "*.Mask")
			(remove_unused_layers no)
			(net "GND")
			(clearance 0.1651)
			(thermal_gap 0.1651)
		)
		(pad "GND28" thru_hole circle
			(at 10.80008 -2.500122 180)
			(size 0.762 0.762)
			(drill 0.359918)
			(layers "*.Cu" "*.Mask")
			(remove_unused_layers no)
			(net "GND")
			(clearance 0.1651)
			(thermal_gap 0.1651)
		)
		(pad "GND29" thru_hole circle
			(at 10.80008 -6.100064 180)
			(size 0.762 0.762)
			(drill 0.359918)
			(layers "*.Cu" "*.Mask")
			(remove_unused_layers no)
			(net "GND")
			(clearance 0.1651)
			(thermal_gap 0.1651)
		)
		(pad "GND30" thru_hole circle
			(at 10.80008 -9.700006 180)
			(size 0.762 0.762)
			(drill 0.359918)
			(layers "*.Cu" "*.Mask")
			(remove_unused_layers no)
			(net "GND")
			(clearance 0.1651)
			(thermal_gap 0.1651)
		)
		(pad "GND31" thru_hole circle
			(at 10.80008 -13.299948 180)
			(size 0.762 0.762)
			(drill 0.359918)
			(layers "*.Cu" "*.Mask")
			(remove_unused_layers no)
			(net "GND")
			(clearance 0.1651)
			(thermal_gap 0.1651)
		)
		(pad "GND32" thru_hole circle
			(at 12.599924 2.29997 180)
			(size 0.762 0.762)
			(drill 0.359918)
			(layers "*.Cu" "*.Mask")
			(remove_unused_layers no)
			(net "GND")
			(clearance 0.1651)
			(thermal_gap 0.1651)
		)
		(pad "GND33" thru_hole circle
			(at 12.599924 -1.299972 180)
			(size 0.762 0.762)
			(drill 0.359918)
			(layers "*.Cu" "*.Mask")
			(remove_unused_layers no)
			(net "GND")
			(clearance 0.1651)
			(thermal_gap 0.1651)
		)
		(pad "GND34" thru_hole circle
			(at 12.599924 -4.899914 180)
			(size 0.762 0.762)
			(drill 0.359918)
			(layers "*.Cu" "*.Mask")
			(remove_unused_layers no)
			(net "GND")
			(clearance 0.1651)
			(thermal_gap 0.1651)
		)
		(pad "GND35" thru_hole circle
			(at 12.599924 -8.50011 180)
			(size 0.762 0.762)
			(drill 0.359918)
			(layers "*.Cu" "*.Mask")
			(remove_unused_layers no)
			(net "GND")
			(clearance 0.1651)
			(thermal_gap 0.1651)
		)
		(pad "GND36" thru_hole circle
			(at 12.599924 -12.100052 180)
			(size 0.762 0.762)
			(drill 0.359918)
			(layers "*.Cu" "*.Mask")
			(remove_unused_layers no)
			(net "GND")
			(clearance 0.1651)
			(thermal_gap 0.1651)
		)
		(pad "GND37" thru_hole circle
			(at 21.599906 -2.500122 180)
			(size 0.762 0.762)
			(drill 0.359918)
			(layers "*.Cu" "*.Mask")
			(remove_unused_layers no)
			(net "GND")
			(clearance 0.1651)
			(thermal_gap 0.1651)
		)
		(pad "GND38" thru_hole circle
			(at 21.599906 -6.100064 180)
			(size 0.762 0.762)
			(drill 0.359918)
			(layers "*.Cu" "*.Mask")
			(remove_unused_layers no)
			(net "GND")
			(clearance 0.1651)
			(thermal_gap 0.1651)
		)
		(pad "GND39" thru_hole circle
			(at 21.599906 -9.700006 180)
			(size 0.762 0.762)
			(drill 0.359918)
			(layers "*.Cu" "*.Mask")
			(remove_unused_layers no)
			(net "GND")
			(clearance 0.1651)
			(thermal_gap 0.1651)
		)
		(pad "GND40" thru_hole circle
			(at 21.599906 -13.299948 180)
			(size 0.762 0.762)
			(drill 0.359918)
			(layers "*.Cu" "*.Mask")
			(remove_unused_layers no)
			(net "GND")
			(clearance 0.1651)
			(thermal_gap 0.1651)
		)
		(pad "GND41" thru_hole circle
			(at 23.400004 2.29997 180)
			(size 0.762 0.762)
			(drill 0.359918)
			(layers "*.Cu" "*.Mask")
			(remove_unused_layers no)
			(net "GND")
			(clearance 0.1651)
			(thermal_gap 0.1651)
		)
		(pad "GND42" thru_hole circle
			(at 23.400004 -1.299972 180)
			(size 0.762 0.762)
			(drill 0.359918)
			(layers "*.Cu" "*.Mask")
			(remove_unused_layers no)
			(net "GND")
			(clearance 0.1651)
			(thermal_gap 0.1651)
		)
		(pad "GND43" thru_hole circle
			(at 23.400004 -4.899914 180)
			(size 0.762 0.762)
			(drill 0.359918)
			(layers "*.Cu" "*.Mask")
			(remove_unused_layers no)
			(net "GND")
			(clearance 0.1651)
			(thermal_gap 0.1651)
		)
		(pad "GND44" thru_hole circle
			(at 23.400004 -8.50011 180)
			(size 0.762 0.762)
			(drill 0.359918)
			(layers "*.Cu" "*.Mask")
			(remove_unused_layers no)
			(net "GND")
			(clearance 0.1651)
			(thermal_gap 0.1651)
		)
		(pad "GND45" thru_hole circle
			(at 23.400004 -12.100052 180)
			(size 0.762 0.762)
			(drill 0.359918)
			(layers "*.Cu" "*.Mask")
			(remove_unused_layers no)
			(net "GND")
			(clearance 0.1651)
			(thermal_gap 0.1651)
		)
		(pad "GND46" thru_hole circle
			(at 25.200102 -2.500122 180)
			(size 0.762 0.762)
			(drill 0.359918)
			(layers "*.Cu" "*.Mask")
			(remove_unused_layers no)
			(net "GND")
			(clearance 0.1651)
			(thermal_gap 0.1651)
		)
		(pad "GND47" thru_hole circle
			(at 25.200102 -6.100064 180)
			(size 0.762 0.762)
			(drill 0.359918)
			(layers "*.Cu" "*.Mask")
			(remove_unused_layers no)
			(net "GND")
			(clearance 0.1651)
			(thermal_gap 0.1651)
		)
		(pad "GND48" thru_hole circle
			(at 25.200102 -9.700006 180)
			(size 0.762 0.762)
			(drill 0.359918)
			(layers "*.Cu" "*.Mask")
			(remove_unused_layers no)
			(net "GND")
			(clearance 0.1651)
			(thermal_gap 0.1651)
		)
		(pad "GND49" thru_hole circle
			(at 25.200102 -13.299948 180)
			(size 0.762 0.762)
			(drill 0.359918)
			(layers "*.Cu" "*.Mask")
			(remove_unused_layers no)
			(net "GND")
			(clearance 0.1651)
			(thermal_gap 0.1651)
		)
		(pad "GND50" thru_hole circle
			(at 26.999946 2.29997 180)
			(size 0.762 0.762)
			(drill 0.359918)
			(layers "*.Cu" "*.Mask")
			(remove_unused_layers no)
			(net "GND")
			(clearance 0.1651)
			(thermal_gap 0.1651)
		)
		(pad "GND51" thru_hole circle
			(at 26.999946 -1.299972 180)
			(size 0.762 0.762)
			(drill 0.359918)
			(layers "*.Cu" "*.Mask")
			(remove_unused_layers no)
			(net "GND")
			(clearance 0.1651)
			(thermal_gap 0.1651)
		)
		(pad "GND52" thru_hole circle
			(at 26.999946 -4.899914 180)
			(size 0.762 0.762)
			(drill 0.359918)
			(layers "*.Cu" "*.Mask")
			(remove_unused_layers no)
			(net "GND")
			(clearance 0.1651)
			(thermal_gap 0.1651)
		)
		(pad "GND53" thru_hole circle
			(at 26.999946 -8.50011 180)
			(size 0.762 0.762)
			(drill 0.359918)
			(layers "*.Cu" "*.Mask")
			(remove_unused_layers no)
			(net "GND")
			(clearance 0.1651)
			(thermal_gap 0.1651)
		)
		(pad "GND54" thru_hole circle
			(at 26.999946 -12.100052 180)
			(size 0.762 0.762)
			(drill 0.359918)
			(layers "*.Cu" "*.Mask")
			(remove_unused_layers no)
			(net "GND")
			(clearance 0.1651)
			(thermal_gap 0.1651)
		)
		(pad "GND55" thru_hole circle
			(at 28.800044 -2.500122 180)
			(size 0.762 0.762)
			(drill 0.359918)
			(layers "*.Cu" "*.Mask")
			(remove_unused_layers no)
			(net "GND")
			(clearance 0.1651)
			(thermal_gap 0.1651)
		)
		(pad "GND56" thru_hole circle
			(at 28.800044 -6.100064 180)
			(size 0.762 0.762)
			(drill 0.359918)
			(layers "*.Cu" "*.Mask")
			(remove_unused_layers no)
			(net "GND")
			(clearance 0.1651)
			(thermal_gap 0.1651)
		)
		(pad "GND57" thru_hole circle
			(at 28.800044 -9.700006 180)
			(size 0.762 0.762)
			(drill 0.359918)
			(layers "*.Cu" "*.Mask")
			(remove_unused_layers no)
			(net "GND")
			(clearance 0.1651)
			(thermal_gap 0.1651)
		)
		(pad "GND58" thru_hole circle
			(at 28.800044 -13.299948 180)
			(size 0.762 0.762)
			(drill 0.359918)
			(layers "*.Cu" "*.Mask")
			(remove_unused_layers no)
			(net "GND")
			(clearance 0.1651)
			(thermal_gap 0.1651)
		)
		(pad "GND59" thru_hole circle
			(at 30.599888 2.29997 180)
			(size 0.762 0.762)
			(drill 0.359918)
			(layers "*.Cu" "*.Mask")
			(remove_unused_layers no)
			(net "GND")
			(clearance 0.1651)
			(thermal_gap 0.1651)
		)
		(pad "GND60" thru_hole circle
			(at 30.599888 -1.299972 180)
			(size 0.762 0.762)
			(drill 0.359918)
			(layers "*.Cu" "*.Mask")
			(remove_unused_layers no)
			(net "GND")
			(clearance 0.1651)
			(thermal_gap 0.1651)
		)
		(pad "GND61" thru_hole circle
			(at 30.599888 -4.899914 180)
			(size 0.762 0.762)
			(drill 0.359918)
			(layers "*.Cu" "*.Mask")
			(remove_unused_layers no)
			(net "GND")
			(clearance 0.1651)
			(thermal_gap 0.1651)
		)
		(pad "GND62" thru_hole circle
			(at 30.599888 -8.50011 180)
			(size 0.762 0.762)
			(drill 0.359918)
			(layers "*.Cu" "*.Mask")
			(remove_unused_layers no)
			(net "GND")
			(clearance 0.1651)
			(thermal_gap 0.1651)
		)
		(pad "GND63" thru_hole circle
			(at 30.599888 -12.100052 180)
			(size 0.762 0.762)
			(drill 0.359918)
			(layers "*.Cu" "*.Mask")
			(remove_unused_layers no)
			(net "GND")
			(clearance 0.1651)
			(thermal_gap 0.1651)
		)
		(pad "GND64" thru_hole circle
			(at 32.399986 -2.500122 180)
			(size 0.762 0.762)
			(drill 0.359918)
			(layers "*.Cu" "*.Mask")
			(remove_unused_layers no)
			(net "GND")
			(clearance 0.1651)
			(thermal_gap 0.1651)
		)
		(pad "GND65" thru_hole circle
			(at 32.399986 -6.100064 180)
			(size 0.762 0.762)
			(drill 0.359918)
			(layers "*.Cu" "*.Mask")
			(remove_unused_layers no)
			(net "GND")
			(clearance 0.1651)
			(thermal_gap 0.1651)
		)
		(pad "GND66" thru_hole circle
			(at 32.399986 -9.700006 180)
			(size 0.762 0.762)
			(drill 0.359918)
			(layers "*.Cu" "*.Mask")
			(remove_unused_layers no)
			(net "GND")
			(clearance 0.1651)
			(thermal_gap 0.1651)
		)
		(pad "GND67" thru_hole circle
			(at 32.399986 -13.299948 180)
			(size 0.762 0.762)
			(drill 0.359918)
			(layers "*.Cu" "*.Mask")
			(remove_unused_layers no)
			(net "GND")
			(clearance 0.1651)
			(thermal_gap 0.1651)
		)
		(pad "GND68" thru_hole circle
			(at 34.200084 2.29997 180)
			(size 0.762 0.762)
			(drill 0.359918)
			(layers "*.Cu" "*.Mask")
			(remove_unused_layers no)
			(net "GND")
			(clearance 0.1651)
			(thermal_gap 0.1651)
		)
		(pad "GND69" thru_hole circle
			(at 34.200084 -1.299972 180)
			(size 0.762 0.762)
			(drill 0.359918)
			(layers "*.Cu" "*.Mask")
			(remove_unused_layers no)
			(net "GND")
			(clearance 0.1651)
			(thermal_gap 0.1651)
		)
		(pad "GND70" thru_hole circle
			(at 34.200084 -4.899914 180)
			(size 0.762 0.762)
			(drill 0.359918)
			(layers "*.Cu" "*.Mask")
			(remove_unused_layers no)
			(net "GND")
			(clearance 0.1651)
			(thermal_gap 0.1651)
		)
		(pad "GND71" thru_hole circle
			(at 34.200084 -8.50011 180)
			(size 0.762 0.762)
			(drill 0.359918)
			(layers "*.Cu" "*.Mask")
			(remove_unused_layers no)
			(net "GND")
			(clearance 0.1651)
			(thermal_gap 0.1651)
		)
		(pad "GND72" thru_hole circle
			(at 34.200084 -12.100052 180)
			(size 0.762 0.762)
			(drill 0.359918)
			(layers "*.Cu" "*.Mask")
			(remove_unused_layers no)
			(net "GND")
			(clearance 0.1651)
			(thermal_gap 0.1651)
		)
		(pad "H1" thru_hole circle
			(at 0 -12.199874 180)
			(size 0.762 0.762)
			(drill 0.359918)
			(layers "*.Cu" "*.Mask")
			(remove_unused_layers no)
			(net "PCIE_COMP_TO_IOM_8_DP")
			(clearance 0.1651)
			(thermal_gap 0.1651)
		)
		(pad "H2" thru_hole circle
			(at 1.800098 -10.999978 180)
			(size 0.762 0.762)
			(drill 0.359918)
			(layers "*.Cu" "*.Mask")
			(remove_unused_layers no)
			(net "PCIE_COMP_TO_IOM_9_DP")
			(clearance 0.1651)
			(thermal_gap 0.1651)
		)
		(pad "H3" thru_hole circle
			(at 3.599942 -12.199874 180)
			(size 0.762 0.762)
			(drill 0.359918)
			(layers "*.Cu" "*.Mask")
			(remove_unused_layers no)
			(net "PCIE_COMP_TO_IOM_10_DP")
			(clearance 0.1651)
			(thermal_gap 0.1651)
		)
		(pad "H4" thru_hole circle
			(at 5.40004 -10.999978 180)
			(size 0.762 0.762)
			(drill 0.359918)
			(layers "*.Cu" "*.Mask")
			(remove_unused_layers no)
			(net "PCIE_COMP_TO_IOM_11_DP")
			(clearance 0.1651)
			(thermal_gap 0.1651)
		)
		(pad "H5" thru_hole circle
			(at 7.199884 -12.199874 180)
			(size 0.762 0.762)
			(drill 0.359918)
			(layers "*.Cu" "*.Mask")
			(remove_unused_layers no)
			(net "PCIE_COMP_TO_IOM_12_DP")
			(clearance 0.1651)
			(thermal_gap 0.1651)
		)
		(pad "H6" thru_hole circle
			(at 8.999982 -10.999978 180)
			(size 0.762 0.762)
			(drill 0.359918)
			(layers "*.Cu" "*.Mask")
			(remove_unused_layers no)
			(net "PCIE_COMP_TO_IOM_13_DP")
			(clearance 0.1651)
			(thermal_gap 0.1651)
		)
		(pad "H7" thru_hole circle
			(at 10.80008 -12.199874 180)
			(size 0.762 0.762)
			(drill 0.359918)
			(layers "*.Cu" "*.Mask")
			(remove_unused_layers no)
			(net "PCIE_COMP_TO_IOM_14_DP")
			(clearance 0.1651)
			(thermal_gap 0.1651)
		)
		(pad "H8" thru_hole circle
			(at 12.599924 -10.999978 180)
			(size 0.762 0.762)
			(drill 0.359918)
			(layers "*.Cu" "*.Mask")
			(remove_unused_layers no)
			(net "PCIE_COMP_TO_IOM_15_DP")
			(clearance 0.1651)
			(thermal_gap 0.1651)
		)
		(pad "H9" thru_hole circle
			(at 21.599906 -12.199874 180)
			(size 0.762 0.762)
			(drill 0.359918)
			(layers "*.Cu" "*.Mask")
			(remove_unused_layers no)
			(net "PCIE_COMP_TO_IOM_16_DP")
			(clearance 0.1651)
			(thermal_gap 0.1651)
		)
		(pad "H10" thru_hole circle
			(at 23.400004 -10.999978 180)
			(size 0.762 0.762)
			(drill 0.359918)
			(layers "*.Cu" "*.Mask")
			(remove_unused_layers no)
			(net "PCIE_COMP_TO_IOM_17_DP")
			(clearance 0.1651)
			(thermal_gap 0.1651)
		)
		(pad "H11" thru_hole circle
			(at 25.200102 -12.199874 180)
			(size 0.762 0.762)
			(drill 0.359918)
			(layers "*.Cu" "*.Mask")
			(remove_unused_layers no)
			(net "PCIE_COMP_TO_IOM_18_DP")
			(clearance 0.1651)
			(thermal_gap 0.1651)
		)
		(pad "H12" thru_hole circle
			(at 26.999946 -10.999978 180)
			(size 0.762 0.762)
			(drill 0.359918)
			(layers "*.Cu" "*.Mask")
			(remove_unused_layers no)
			(net "PCIE_COMP_TO_IOM_19_DP")
			(clearance 0.1651)
			(thermal_gap 0.1651)
		)
		(pad "H13" thru_hole circle
			(at 28.800044 -12.199874 180)
			(size 0.762 0.762)
			(drill 0.359918)
			(layers "*.Cu" "*.Mask")
			(remove_unused_layers no)
			(net "PCIE_COMP_TO_IOM_20_DP")
			(clearance 0.1651)
			(thermal_gap 0.1651)
		)
		(pad "H14" thru_hole circle
			(at 30.599888 -10.999978 180)
			(size 0.762 0.762)
			(drill 0.359918)
			(layers "*.Cu" "*.Mask")
			(remove_unused_layers no)
			(net "PCIE_COMP_TO_IOM_21_DP")
			(clearance 0.1651)
			(thermal_gap 0.1651)
		)
		(pad "H15" thru_hole circle
			(at 32.399986 -12.199874 180)
			(size 0.762 0.762)
			(drill 0.359918)
			(layers "*.Cu" "*.Mask")
			(remove_unused_layers no)
			(net "PCIE_COMP_TO_IOM_22_DP")
			(clearance 0.1651)
			(thermal_gap 0.1651)
		)
		(pad "H16" thru_hole circle
			(at 34.200084 -10.999978 180)
			(size 0.762 0.762)
			(drill 0.359918)
			(layers "*.Cu" "*.Mask")
			(remove_unused_layers no)
			(net "PCIE_COMP_TO_IOM_23_DP")
			(clearance 0.1651)
			(thermal_gap 0.1651)
		)
		(zone
			(layer "F.Cu")
			(hatch none 0.5)
			(connect_pads
				(clearance 0)
			)
			(min_thickness 0.25)
			(keepout
				(tracks allowed)
				(vias not_allowed)
				(pads allowed)
				(copperpour not_allowed)
				(footprints allowed)
			)
			(placement
				(enabled no)
				(sheetname "")
			)
			(fill
				(thermal_gap 0.5)
				(thermal_bridge_width 0.5)
				(island_removal_mode 0)
			)
			(polygon
				(pts
					(xy 127.294894 -48.000158) (xy 120.685052 -48.000158) (xy 120.685052 -28.720034) (xy 127.294894 -28.720034)
				)
			)
		)
		(zone
			(layer "F.Cu")
			(hatch none 0.5)
			(connect_pads
				(clearance 0)
			)
			(min_thickness 0.25)
			(keepout
				(tracks not_allowed)
				(vias allowed)
				(pads allowed)
				(copperpour not_allowed)
				(footprints allowed)
			)
			(placement
				(enabled no)
				(sheetname "")
			)
			(fill
				(thermal_gap 0.5)
				(thermal_bridge_width 0.5)
				(island_removal_mode 0)
			)
			(polygon
				(pts
					(xy 127.294894 -28.720034) (xy 127.294894 -48.000158) (xy 120.685052 -48.000158) (xy 120.685052 -28.720034)
				)
			)
		)
		(zone
			(layers "F.Cu" "B.Cu" "In1.Cu" "In2.Cu" "In3.Cu" "In4.Cu" "In5.Cu" "In6.Cu")
			(hatch none 0.5)
			(connect_pads
				(clearance 0)
			)
			(min_thickness 0.25)
			(keepout
				(tracks not_allowed)
				(vias allowed)
				(pads allowed)
				(copperpour not_allowed)
				(footprints allowed)
			)
			(placement
				(enabled no)
				(sheetname "")
			)
			(fill
				(thermal_gap 0.5)
				(thermal_bridge_width 0.5)
				(island_removal_mode 0)
			)
			(polygon
				(pts
					(arc
						(start 125.663452 -41.844976)
						(mid 122.666252 -41.844976)
						(end 125.663452 -41.844976)
					)
				)
			)
		)
		(zone
			(layers "F.Cu" "B.Cu" "In1.Cu" "In2.Cu" "In3.Cu" "In4.Cu" "In5.Cu" "In6.Cu")
			(hatch none 0.5)
			(connect_pads
				(clearance 0)
			)
			(min_thickness 0.25)
			(keepout
				(tracks not_allowed)
				(vias allowed)
				(pads allowed)
				(copperpour not_allowed)
				(footprints allowed)
			)
			(placement
				(enabled no)
				(sheetname "")
			)
			(fill
				(thermal_gap 0.5)
				(thermal_bridge_width 0.5)
				(island_removal_mode 0)
			)
			(polygon
				(pts
					(arc
						(start 125.701552 -34.85515)
						(mid 122.628152 -34.85515)
						(end 125.701552 -34.85515)
					)
				)
			)
		)
	)
	(footprint ""
		(layer "F.Cu")
		(at 72.22998 -163.6141 -90)
		(property "Reference" "C245"
			(at 0 0 270)
			(layer "F.SilkS")
			(hide yes)
			(effects
				(font
					(size 1.27 1.27)
				)
			)
		)
		(property "Value" "SCD1U16V2KX-3GP"
			(at 1.1811 -2.7051 270)
			(unlocked yes)
			(layer "F.Fab")
			(hide yes)
			(effects
				(font
					(size 1.016 1.016)
					(thickness 0.1524)
				)
			)
		)
		(property "Device Type" "C402H22"
			(at 1.1811 -4.2291 270)
			(unlocked yes)
			(layer "F.Fab")
			(hide yes)
			(effects
				(font
					(size 1.016 1.016)
					(thickness 0.1524)
				)
			)
		)
		(duplicate_pad_numbers_are_jumpers no)
		(fp_rect
			(start -0.4318 0.9525)
			(end 0.4318 -0.9525)
			(stroke
				(width 0)
				(type default)
			)
			(fill no)
			(layer "F.CrtYd")
		)
		(fp_rect
			(start -0.4318 0.9525)
			(end 0.4318 -0.9525)
			(stroke
				(width 0)
				(type default)
			)
			(fill no)
			(layer "F.Fab")
		)
		(pad "1" smd custom
			(at 0 -0.4445 270)
			(size 0.1524 0.1524)
			(layers "F.Cu" "F.Mask" "F.Paste")
			(net "TPS74801_P1V15_STBY_EN")
			(options
				(clearance outline)
				(anchor circle)
			)
			(primitives
				(gr_poly
					(pts
						(arc
							(start 0.3048 -0.2032)
							(mid 0.275042 -0.275042)
							(end 0.2032 -0.3048)
						)
						(arc
							(start -0.2032 -0.3048)
							(mid -0.275042 -0.275042)
							(end -0.3048 -0.2032)
						)
						(arc
							(start -0.3048 0.2032)
							(mid -0.275042 0.275042)
							(end -0.2032 0.3048)
						)
						(arc
							(start 0.2032 0.3048)
							(mid 0.275042 0.275042)
							(end 0.3048 0.2032)
						)
					)
					(width 0)
					(fill yes)
				)
			)
		)
		(pad "2" smd custom
			(at 0 0.4445 270)
			(size 0.1524 0.1524)
			(layers "F.Cu" "F.Mask" "F.Paste")
			(net "GND")
			(options
				(clearance outline)
				(anchor circle)
			)
			(primitives
				(gr_poly
					(pts
						(arc
							(start 0.3048 -0.2032)
							(mid 0.275042 -0.275042)
							(end 0.2032 -0.3048)
						)
						(arc
							(start -0.2032 -0.3048)
							(mid -0.275042 -0.275042)
							(end -0.3048 -0.2032)
						)
						(arc
							(start -0.3048 0.2032)
							(mid -0.275042 0.275042)
							(end -0.2032 0.3048)
						)
						(arc
							(start 0.2032 0.3048)
							(mid 0.275042 0.275042)
							(end 0.3048 0.2032)
						)
					)
					(width 0)
					(fill yes)
				)
			)
		)
	)
	(footprint ""
		(layer "F.Cu")
		(at 209.226912 -120.7262 180)
		(property "Reference" "R812"
			(at 0 0 180)
			(layer "F.SilkS")
			(hide yes)
			(effects
				(font
					(size 1.27 1.27)
				)
			)
		)
		(property "Value" "4K7R2F-GP"
			(at 0.064008 -3.993896 180)
			(unlocked yes)
			(layer "F.Fab")
			(hide yes)
			(effects
				(font
					(size 1.016 1.016)
					(thickness 0.1524)
				)
			)
		)
		(property "Device Type" "R402H16"
			(at 0.064008 -5.517896 180)
			(unlocked yes)
			(layer "F.Fab")
			(hide yes)
			(effects
				(font
					(size 1.016 1.016)
					(thickness 0.1524)
				)
			)
		)
		(duplicate_pad_numbers_are_jumpers no)
		(fp_line
			(start 0.508 -0.9398)
			(end -0.508 -0.9398)
			(stroke
				(width 0.1524)
				(type default)
			)
			(layer "F.SilkS")
		)
		(fp_line
			(start -0.508 -0.9398)
			(end -0.508 0.9398)
			(stroke
				(width 0.1524)
				(type default)
			)
			(layer "F.SilkS")
		)
		(fp_rect
			(start -0.508 0.9398)
			(end 0.508 -0.9398)
			(stroke
				(width 0)
				(type default)
			)
			(fill no)
			(layer "F.CrtYd")
		)
		(fp_rect
			(start -0.508 0.9398)
			(end 0.508 -0.9398)
			(stroke
				(width 0)
				(type default)
			)
			(fill no)
			(layer "F.Fab")
		)
		(pad "1" smd custom
			(at 0 -0.4445 180)
			(size 0.1397 0.1397)
			(layers "F.Cu" "F.Mask" "F.Paste")
			(net "P3V3_M2")
			(options
				(clearance outline)
				(anchor circle)
			)
			(primitives
				(gr_poly
					(pts
						(arc
							(start -0.1778 -0.2794)
							(mid -0.249642 -0.249642)
							(end -0.2794 -0.1778)
						)
						(arc
							(start -0.2794 0.1778)
							(mid -0.249642 0.249642)
							(end -0.1778 0.2794)
						)
						(arc
							(start 0.1778 0.2794)
							(mid 0.249642 0.249642)
							(end 0.2794 0.1778)
						)
						(arc
							(start 0.2794 -0.1778)
							(mid 0.249642 -0.249642)
							(end 0.1778 -0.2794)
						)
					)
					(width 0)
					(fill yes)
				)
			)
		)
		(pad "2" smd custom
			(at 0 0.4445 180)
			(size 0.1397 0.1397)
			(layers "F.Cu" "F.Mask" "F.Paste")
			(net "M2_1_CLKREQ#")
			(options
				(clearance outline)
				(anchor circle)
			)
			(primitives
				(gr_poly
					(pts
						(arc
							(start -0.1778 -0.2794)
							(mid -0.249642 -0.249642)
							(end -0.2794 -0.1778)
						)
						(arc
							(start -0.2794 0.1778)
							(mid -0.249642 0.249642)
							(end -0.1778 0.2794)
						)
						(arc
							(start 0.1778 0.2794)
							(mid 0.249642 0.249642)
							(end 0.2794 0.1778)
						)
						(arc
							(start 0.2794 -0.1778)
							(mid 0.249642 -0.249642)
							(end 0.1778 -0.2794)
						)
					)
					(width 0)
					(fill yes)
				)
			)
		)
	)
	(footprint ""
		(layer "F.Cu")
		(at 27.419046 -157.547056 -90)
		(property "Reference" "R786"
			(at 0 0 270)
			(layer "F.SilkS")
			(hide yes)
			(effects
				(font
					(size 1.27 1.27)
				)
			)
		)
		(property "Value" "0R2J-2-GP"
			(at 0.064008 -3.993896 270)
			(unlocked yes)
			(layer "F.Fab")
			(hide yes)
			(effects
				(font
					(size 1.016 1.016)
					(thickness 0.1524)
				)
			)
		)
		(property "Device Type" "R402H16"
			(at 0.064008 -5.517896 270)
			(unlocked yes)
			(layer "F.Fab")
			(hide yes)
			(effects
				(font
					(size 1.016 1.016)
					(thickness 0.1524)
				)
			)
		)
		(duplicate_pad_numbers_are_jumpers no)
		(fp_line
			(start -0.508 -0.9398)
			(end -0.508 0.9398)
			(stroke
				(width 0.1524)
				(type default)
			)
			(layer "F.SilkS")
		)
		(fp_line
			(start 0.508 -0.9398)
			(end -0.508 -0.9398)
			(stroke
				(width 0.1524)
				(type default)
			)
			(layer "F.SilkS")
		)
		(fp_rect
			(start -0.508 0.9398)
			(end 0.508 -0.9398)
			(stroke
				(width 0)
				(type default)
			)
			(fill no)
			(layer "F.CrtYd")
		)
		(fp_rect
			(start -0.508 0.9398)
			(end 0.508 -0.9398)
			(stroke
				(width 0)
				(type default)
			)
			(fill no)
			(layer "F.Fab")
		)
		(pad "1" smd custom
			(at 0 -0.4445 270)
			(size 0.1397 0.1397)
			(layers "F.Cu" "F.Mask" "F.Paste")
			(net "FLA0_WP_N_R")
			(options
				(clearance outline)
				(anchor circle)
			)
			(primitives
				(gr_poly
					(pts
						(arc
							(start -0.1778 -0.2794)
							(mid -0.249642 -0.249642)
							(end -0.2794 -0.1778)
						)
						(arc
							(start -0.2794 0.1778)
							(mid -0.249642 0.249642)
							(end -0.1778 0.2794)
						)
						(arc
							(start 0.1778 0.2794)
							(mid 0.249642 0.249642)
							(end 0.2794 0.1778)
						)
						(arc
							(start 0.2794 -0.1778)
							(mid 0.249642 -0.249642)
							(end 0.1778 -0.2794)
						)
					)
					(width 0)
					(fill yes)
				)
			)
		)
		(pad "2" smd custom
			(at 0 0.4445 270)
			(size 0.1397 0.1397)
			(layers "F.Cu" "F.Mask" "F.Paste")
			(net "FLA0_WP_N")
			(options
				(clearance outline)
				(anchor circle)
			)
			(primitives
				(gr_poly
					(pts
						(arc
							(start -0.1778 -0.2794)
							(mid -0.249642 -0.249642)
							(end -0.2794 -0.1778)
						)
						(arc
							(start -0.2794 0.1778)
							(mid -0.249642 0.249642)
							(end -0.1778 0.2794)
						)
						(arc
							(start 0.1778 0.2794)
							(mid 0.249642 0.249642)
							(end 0.2794 0.1778)
						)
						(arc
							(start 0.2794 -0.1778)
							(mid 0.249642 -0.249642)
							(end 0.1778 -0.2794)
						)
					)
					(width 0)
					(fill yes)
				)
			)
		)
	)
	(footprint ""
		(layer "F.Cu")
		(at 78.545944 -168.199816 180)
		(property "Reference" "C244"
			(at 0 0 180)
			(layer "F.SilkS")
			(hide yes)
			(effects
				(font
					(size 1.27 1.27)
				)
			)
		)
		(property "Value" "SC10U6D3V5KX-4GP"
			(at -0.0762 -6.1214 180)
			(unlocked yes)
			(layer "F.Fab")
			(hide yes)
			(effects
				(font
					(size 1.016 1.016)
					(thickness 0.1524)
				)
			)
		)
		(property "Device Type" "C805H58"
			(at -0.0762 -8.1534 180)
			(unlocked yes)
			(layer "F.Fab")
			(hide yes)
			(effects
				(font
					(size 1.016 1.016)
					(thickness 0.1524)
				)
			)
		)
		(duplicate_pad_numbers_are_jumpers no)
		(fp_line
			(start 0.635 0)
			(end -0.635 0)
			(stroke
				(width 0.508)
				(type default)
			)
			(layer "F.SilkS")
		)
		(fp_rect
			(start -0.9652 1.778)
			(end 0.9652 -1.778)
			(stroke
				(width 0)
				(type default)
			)
			(fill no)
			(layer "F.CrtYd")
		)
		(fp_poly
			(pts
				(xy -0.9652 -1.778) (xy 0.9652 -1.778) (xy 0.9652 1.778) (xy -0.9652 1.778)
			)
			(stroke
				(width 0)
				(type default)
			)
			(fill no)
			(layer "F.Fab")
		)
		(pad "1" smd rect
			(at 0 -0.9652 180)
			(size 1.397 1.143)
			(layers "F.Cu" "F.Mask" "F.Paste")
			(net "P1V8_STBY")
		)
		(pad "2" smd rect
			(at 0 0.9652 180)
			(size 1.397 1.143)
			(layers "F.Cu" "F.Mask" "F.Paste")
			(net "GND")
		)
	)
	(footprint ""
		(layer "F.Cu")
		(at 224.561908 -102.173024 180)
		(property "Reference" "C671"
			(at 0 0 180)
			(layer "F.SilkS")
			(hide yes)
			(effects
				(font
					(size 1.27 1.27)
				)
			)
		)
		(property "Value" "SC10U16V5KX-7-GP-U"
			(at -0.0762 -6.1214 180)
			(unlocked yes)
			(layer "F.Fab")
			(hide yes)
			(effects
				(font
					(size 1.016 1.016)
					(thickness 0.1524)
				)
			)
		)
		(property "Device Type" "C805H58"
			(at -0.0762 -8.1534 180)
			(unlocked yes)
			(layer "F.Fab")
			(hide yes)
			(effects
				(font
					(size 1.016 1.016)
					(thickness 0.1524)
				)
			)
		)
		(duplicate_pad_numbers_are_jumpers no)
		(fp_line
			(start 0.635 0)
			(end -0.635 0)
			(stroke
				(width 0.508)
				(type default)
			)
			(layer "F.SilkS")
		)
		(fp_rect
			(start -0.9652 1.778)
			(end 0.9652 -1.778)
			(stroke
				(width 0)
				(type default)
			)
			(fill no)
			(layer "F.CrtYd")
		)
		(fp_poly
			(pts
				(xy -0.9652 -1.778) (xy 0.9652 -1.778) (xy 0.9652 1.778) (xy -0.9652 1.778)
			)
			(stroke
				(width 0)
				(type default)
			)
			(fill no)
			(layer "F.Fab")
		)
		(pad "1" smd rect
			(at 0 -0.9652 180)
			(size 1.397 1.143)
			(layers "F.Cu" "F.Mask" "F.Paste")
			(net "P12V_STBY_VIN_U81")
		)
		(pad "2" smd rect
			(at 0 0.9652 180)
			(size 1.397 1.143)
			(layers "F.Cu" "F.Mask" "F.Paste")
			(net "GND")
		)
	)
	(footprint ""
		(layer "F.Cu")
		(at 31.9024 -159.258)
		(property "Reference" "C89"
			(at 0 0 0)
			(layer "F.SilkS")
			(hide yes)
			(effects
				(font
					(size 1.27 1.27)
				)
			)
		)
		(property "Value" "SC4D7U25V5KX-1-GP"
			(at -0.0762 -6.1214 0)
			(unlocked yes)
			(layer "F.Fab")
			(hide yes)
			(effects
				(font
					(size 1.016 1.016)
					(thickness 0.1524)
				)
			)
		)
		(property "Device Type" "C805H58"
			(at -0.0762 -8.1534 0)
			(unlocked yes)
			(layer "F.Fab")
			(hide yes)
			(effects
				(font
					(size 1.016 1.016)
					(thickness 0.1524)
				)
			)
		)
		(duplicate_pad_numbers_are_jumpers no)
		(fp_line
			(start 0.635 0)
			(end -0.635 0)
			(stroke
				(width 0.508)
				(type default)
			)
			(layer "F.SilkS")
		)
		(fp_rect
			(start -0.9652 1.778)
			(end 0.9652 -1.778)
			(stroke
				(width 0)
				(type default)
			)
			(fill no)
			(layer "F.CrtYd")
		)
		(fp_poly
			(pts
				(xy -0.9652 -1.778) (xy 0.9652 -1.778) (xy 0.9652 1.778) (xy -0.9652 1.778)
			)
			(stroke
				(width 0)
				(type default)
			)
			(fill no)
			(layer "F.Fab")
		)
		(pad "1" smd rect
			(at 0 -0.9652)
			(size 1.397 1.143)
			(layers "F.Cu" "F.Mask" "F.Paste")
			(net "DACAV33")
		)
		(pad "2" smd rect
			(at 0 0.9652)
			(size 1.397 1.143)
			(layers "F.Cu" "F.Mask" "F.Paste")
			(net "GND")
		)
	)
	(footprint ""
		(layer "F.Cu")
		(at 98.933 -155.9306 90)
		(property "Reference" "R23"
			(at 0 0 90)
			(layer "F.SilkS")
			(hide yes)
			(effects
				(font
					(size 1.27 1.27)
				)
			)
		)
		(property "Value" "4K7R2F-GP"
			(at 0.064008 -3.993896 90)
			(unlocked yes)
			(layer "F.Fab")
			(hide yes)
			(effects
				(font
					(size 1.016 1.016)
					(thickness 0.1524)
				)
			)
		)
		(property "Device Type" "R402H16"
			(at 0.064008 -5.517896 90)
			(unlocked yes)
			(layer "F.Fab")
			(hide yes)
			(effects
				(font
					(size 1.016 1.016)
					(thickness 0.1524)
				)
			)
		)
		(duplicate_pad_numbers_are_jumpers no)
		(fp_line
			(start 0.508 -0.9398)
			(end -0.508 -0.9398)
			(stroke
				(width 0.1524)
				(type default)
			)
			(layer "F.SilkS")
		)
		(fp_line
			(start -0.508 -0.9398)
			(end -0.508 0.9398)
			(stroke
				(width 0.1524)
				(type default)
			)
			(layer "F.SilkS")
		)
		(fp_rect
			(start -0.508 0.9398)
			(end 0.508 -0.9398)
			(stroke
				(width 0)
				(type default)
			)
			(fill no)
			(layer "F.CrtYd")
		)
		(fp_rect
			(start -0.508 0.9398)
			(end 0.508 -0.9398)
			(stroke
				(width 0)
				(type default)
			)
			(fill no)
			(layer "F.Fab")
		)
		(pad "1" smd custom
			(at 0 -0.4445 90)
			(size 0.1397 0.1397)
			(layers "F.Cu" "F.Mask" "F.Paste")
			(net "CFG_SEL0")
			(options
				(clearance outline)
				(anchor circle)
			)
			(primitives
				(gr_poly
					(pts
						(arc
							(start -0.1778 -0.2794)
							(mid -0.249642 -0.249642)
							(end -0.2794 -0.1778)
						)
						(arc
							(start -0.2794 0.1778)
							(mid -0.249642 0.249642)
							(end -0.1778 0.2794)
						)
						(arc
							(start 0.1778 0.2794)
							(mid 0.249642 0.249642)
							(end 0.2794 0.1778)
						)
						(arc
							(start 0.2794 -0.1778)
							(mid 0.249642 -0.249642)
							(end 0.1778 -0.2794)
						)
					)
					(width 0)
					(fill yes)
				)
			)
		)
		(pad "2" smd custom
			(at 0 0.4445 90)
			(size 0.1397 0.1397)
			(layers "F.Cu" "F.Mask" "F.Paste")
			(net "GND")
			(options
				(clearance outline)
				(anchor circle)
			)
			(primitives
				(gr_poly
					(pts
						(arc
							(start -0.1778 -0.2794)
							(mid -0.249642 -0.249642)
							(end -0.2794 -0.1778)
						)
						(arc
							(start -0.2794 0.1778)
							(mid -0.249642 0.249642)
							(end -0.1778 0.2794)
						)
						(arc
							(start 0.1778 0.2794)
							(mid 0.249642 0.249642)
							(end 0.2794 0.1778)
						)
						(arc
							(start 0.2794 -0.1778)
							(mid 0.249642 -0.249642)
							(end 0.1778 -0.2794)
						)
					)
					(width 0)
					(fill yes)
				)
			)
		)
	)
	(footprint ""
		(layer "F.Cu")
		(at 36.986718 -187.972192 -90)
		(property "Reference" "C180"
			(at 0 0 270)
			(layer "F.SilkS")
			(hide yes)
			(effects
				(font
					(size 1.27 1.27)
				)
			)
		)
		(property "Value" "SC2200P50V2KX-2GP"
			(at 1.1811 -2.7051 270)
			(unlocked yes)
			(layer "F.Fab")
			(hide yes)
			(effects
				(font
					(size 1.016 1.016)
					(thickness 0.1524)
				)
			)
		)
		(property "Device Type" "C402H22"
			(at 1.1811 -4.2291 270)
			(unlocked yes)
			(layer "F.Fab")
			(hide yes)
			(effects
				(font
					(size 1.016 1.016)
					(thickness 0.1524)
				)
			)
		)
		(duplicate_pad_numbers_are_jumpers no)
		(fp_rect
			(start -0.4318 0.9525)
			(end 0.4318 -0.9525)
			(stroke
				(width 0)
				(type default)
			)
			(fill no)
			(layer "F.CrtYd")
		)
		(fp_rect
			(start -0.4318 0.9525)
			(end 0.4318 -0.9525)
			(stroke
				(width 0)
				(type default)
			)
			(fill no)
			(layer "F.Fab")
		)
		(pad "1" smd custom
			(at 0 -0.4445 270)
			(size 0.1524 0.1524)
			(layers "F.Cu" "F.Mask" "F.Paste")
			(net "P3V3_STBY_LL")
			(options
				(clearance outline)
				(anchor circle)
			)
			(primitives
				(gr_poly
					(pts
						(arc
							(start 0.3048 -0.2032)
							(mid 0.275042 -0.275042)
							(end 0.2032 -0.3048)
						)
						(arc
							(start -0.2032 -0.3048)
							(mid -0.275042 -0.275042)
							(end -0.3048 -0.2032)
						)
						(arc
							(start -0.3048 0.2032)
							(mid -0.275042 0.275042)
							(end -0.2032 0.3048)
						)
						(arc
							(start 0.2032 0.3048)
							(mid 0.275042 0.275042)
							(end 0.3048 0.2032)
						)
					)
					(width 0)
					(fill yes)
				)
			)
		)
		(pad "2" smd custom
			(at 0 0.4445 270)
			(size 0.1524 0.1524)
			(layers "F.Cu" "F.Mask" "F.Paste")
			(net "P3V3_SNB")
			(options
				(clearance outline)
				(anchor circle)
			)
			(primitives
				(gr_poly
					(pts
						(arc
							(start 0.3048 -0.2032)
							(mid 0.275042 -0.275042)
							(end 0.2032 -0.3048)
						)
						(arc
							(start -0.2032 -0.3048)
							(mid -0.275042 -0.275042)
							(end -0.3048 -0.2032)
						)
						(arc
							(start -0.3048 0.2032)
							(mid -0.275042 0.275042)
							(end -0.2032 0.3048)
						)
						(arc
							(start 0.2032 0.3048)
							(mid 0.275042 0.275042)
							(end 0.3048 0.2032)
						)
					)
					(width 0)
					(fill yes)
				)
			)
		)
	)
	(footprint ""
		(layer "F.Cu")
		(at 88.768428 -48.203612 90)
		(property "Reference" "C189"
			(at 0 0 90)
			(layer "F.SilkS")
			(hide yes)
			(effects
				(font
					(size 1.27 1.27)
				)
			)
		)
		(property "Value" "SCD1U25V2KX-2-GP"
			(at 1.1811 -2.7051 90)
			(unlocked yes)
			(layer "F.Fab")
			(hide yes)
			(effects
				(font
					(size 1.016 1.016)
					(thickness 0.1524)
				)
			)
		)
		(property "Device Type" "C402H22"
			(at 1.1811 -4.2291 90)
			(unlocked yes)
			(layer "F.Fab")
			(hide yes)
			(effects
				(font
					(size 1.016 1.016)
					(thickness 0.1524)
				)
			)
		)
		(duplicate_pad_numbers_are_jumpers no)
		(fp_rect
			(start -0.4318 0.9525)
			(end 0.4318 -0.9525)
			(stroke
				(width 0)
				(type default)
			)
			(fill no)
			(layer "F.CrtYd")
		)
		(fp_rect
			(start -0.4318 0.9525)
			(end 0.4318 -0.9525)
			(stroke
				(width 0)
				(type default)
			)
			(fill no)
			(layer "F.Fab")
		)
		(pad "1" smd custom
			(at 0 -0.4445 90)
			(size 0.1524 0.1524)
			(layers "F.Cu" "F.Mask" "F.Paste")
			(net "P3V3")
			(options
				(clearance outline)
				(anchor circle)
			)
			(primitives
				(gr_poly
					(pts
						(arc
							(start 0.3048 -0.2032)
							(mid 0.275042 -0.275042)
							(end 0.2032 -0.3048)
						)
						(arc
							(start -0.2032 -0.3048)
							(mid -0.275042 -0.275042)
							(end -0.3048 -0.2032)
						)
						(arc
							(start -0.3048 0.2032)
							(mid -0.275042 0.275042)
							(end -0.2032 0.3048)
						)
						(arc
							(start 0.2032 0.3048)
							(mid 0.275042 0.275042)
							(end 0.3048 0.2032)
						)
					)
					(width 0)
					(fill yes)
				)
			)
		)
		(pad "2" smd custom
			(at 0 0.4445 90)
			(size 0.1524 0.1524)
			(layers "F.Cu" "F.Mask" "F.Paste")
			(net "GND")
			(options
				(clearance outline)
				(anchor circle)
			)
			(primitives
				(gr_poly
					(pts
						(arc
							(start 0.3048 -0.2032)
							(mid 0.275042 -0.275042)
							(end 0.2032 -0.3048)
						)
						(arc
							(start -0.2032 -0.3048)
							(mid -0.275042 -0.275042)
							(end -0.3048 -0.2032)
						)
						(arc
							(start -0.3048 0.2032)
							(mid -0.275042 0.275042)
							(end -0.2032 0.3048)
						)
						(arc
							(start 0.2032 0.3048)
							(mid 0.275042 0.275042)
							(end 0.3048 0.2032)
						)
					)
					(width 0)
					(fill yes)
				)
			)
		)
	)
	(footprint ""
		(layer "F.Cu")
		(at 65.532 -166.497 180)
		(property "Reference" "C50"
			(at 0 0 180)
			(layer "F.SilkS")
			(hide yes)
			(effects
				(font
					(size 1.27 1.27)
				)
			)
		)
		(property "Value" "SCD1U16V2KX-3GP"
			(at 1.1811 -2.7051 180)
			(unlocked yes)
			(layer "F.Fab")
			(hide yes)
			(effects
				(font
					(size 1.016 1.016)
					(thickness 0.1524)
				)
			)
		)
		(property "Device Type" "C402H22"
			(at 1.1811 -4.2291 180)
			(unlocked yes)
			(layer "F.Fab")
			(hide yes)
			(effects
				(font
					(size 1.016 1.016)
					(thickness 0.1524)
				)
			)
		)
		(duplicate_pad_numbers_are_jumpers no)
		(fp_rect
			(start -0.4318 0.9525)
			(end 0.4318 -0.9525)
			(stroke
				(width 0)
				(type default)
			)
			(fill no)
			(layer "F.CrtYd")
		)
		(fp_rect
			(start -0.4318 0.9525)
			(end 0.4318 -0.9525)
			(stroke
				(width 0)
				(type default)
			)
			(fill no)
			(layer "F.Fab")
		)
		(pad "1" smd custom
			(at 0 -0.4445 180)
			(size 0.1524 0.1524)
			(layers "F.Cu" "F.Mask" "F.Paste")
			(net "FM_TPM_PRSNT_RST")
			(options
				(clearance outline)
				(anchor circle)
			)
			(primitives
				(gr_poly
					(pts
						(arc
							(start 0.3048 -0.2032)
							(mid 0.275042 -0.275042)
							(end 0.2032 -0.3048)
						)
						(arc
							(start -0.2032 -0.3048)
							(mid -0.275042 -0.275042)
							(end -0.3048 -0.2032)
						)
						(arc
							(start -0.3048 0.2032)
							(mid -0.275042 0.275042)
							(end -0.2032 0.3048)
						)
						(arc
							(start 0.2032 0.3048)
							(mid 0.275042 0.275042)
							(end 0.3048 0.2032)
						)
					)
					(width 0)
					(fill yes)
				)
			)
		)
		(pad "2" smd custom
			(at 0 0.4445 180)
			(size 0.1524 0.1524)
			(layers "F.Cu" "F.Mask" "F.Paste")
			(net "GND")
			(options
				(clearance outline)
				(anchor circle)
			)
			(primitives
				(gr_poly
					(pts
						(arc
							(start 0.3048 -0.2032)
							(mid 0.275042 -0.275042)
							(end 0.2032 -0.3048)
						)
						(arc
							(start -0.2032 -0.3048)
							(mid -0.275042 -0.275042)
							(end -0.3048 -0.2032)
						)
						(arc
							(start -0.3048 0.2032)
							(mid -0.275042 0.275042)
							(end -0.2032 0.3048)
						)
						(arc
							(start 0.2032 0.3048)
							(mid 0.275042 0.275042)
							(end 0.3048 0.2032)
						)
					)
					(width 0)
					(fill yes)
				)
			)
		)
	)
	(footprint ""
		(layer "F.Cu")
		(at 59.5376 -161.1122 90)
		(property "Reference" "R392"
			(at 0 0 90)
			(layer "F.SilkS")
			(hide yes)
			(effects
				(font
					(size 1.27 1.27)
				)
			)
		)
		(property "Value" "4K7R2F-GP"
			(at 0.064008 -3.993896 90)
			(unlocked yes)
			(layer "F.Fab")
			(hide yes)
			(effects
				(font
					(size 1.016 1.016)
					(thickness 0.1524)
				)
			)
		)
		(property "Device Type" "R402H16"
			(at 0.064008 -5.517896 90)
			(unlocked yes)
			(layer "F.Fab")
			(hide yes)
			(effects
				(font
					(size 1.016 1.016)
					(thickness 0.1524)
				)
			)
		)
		(duplicate_pad_numbers_are_jumpers no)
		(fp_line
			(start 0.508 -0.9398)
			(end -0.508 -0.9398)
			(stroke
				(width 0.1524)
				(type default)
			)
			(layer "F.SilkS")
		)
		(fp_line
			(start -0.508 -0.9398)
			(end -0.508 0.9398)
			(stroke
				(width 0.1524)
				(type default)
			)
			(layer "F.SilkS")
		)
		(fp_rect
			(start -0.508 0.9398)
			(end 0.508 -0.9398)
			(stroke
				(width 0)
				(type default)
			)
			(fill no)
			(layer "F.CrtYd")
		)
		(fp_rect
			(start -0.508 0.9398)
			(end 0.508 -0.9398)
			(stroke
				(width 0)
				(type default)
			)
			(fill no)
			(layer "F.Fab")
		)
		(pad "1" smd custom
			(at 0 -0.4445 90)
			(size 0.1397 0.1397)
			(layers "F.Cu" "F.Mask" "F.Paste")
			(net "P3V3_STBY")
			(options
				(clearance outline)
				(anchor circle)
			)
			(primitives
				(gr_poly
					(pts
						(arc
							(start -0.1778 -0.2794)
							(mid -0.249642 -0.249642)
							(end -0.2794 -0.1778)
						)
						(arc
							(start -0.2794 0.1778)
							(mid -0.249642 0.249642)
							(end -0.1778 0.2794)
						)
						(arc
							(start 0.1778 0.2794)
							(mid 0.249642 0.249642)
							(end 0.2794 0.1778)
						)
						(arc
							(start 0.2794 -0.1778)
							(mid 0.249642 -0.249642)
							(end 0.1778 -0.2794)
						)
					)
					(width 0)
					(fill yes)
				)
			)
		)
		(pad "2" smd custom
			(at 0 0.4445 90)
			(size 0.1397 0.1397)
			(layers "F.Cu" "F.Mask" "F.Paste")
			(net "MAC2_TXD1")
			(options
				(clearance outline)
				(anchor circle)
			)
			(primitives
				(gr_poly
					(pts
						(arc
							(start -0.1778 -0.2794)
							(mid -0.249642 -0.249642)
							(end -0.2794 -0.1778)
						)
						(arc
							(start -0.2794 0.1778)
							(mid -0.249642 0.249642)
							(end -0.1778 0.2794)
						)
						(arc
							(start 0.1778 0.2794)
							(mid 0.249642 0.249642)
							(end 0.2794 0.1778)
						)
						(arc
							(start 0.2794 -0.1778)
							(mid 0.249642 -0.249642)
							(end 0.1778 -0.2794)
						)
					)
					(width 0)
					(fill yes)
				)
			)
		)
	)
	(footprint ""
		(layer "F.Cu")
		(at 60.375546 -187.438538 -90)
		(property "Reference" "R479"
			(at 0 0 270)
			(layer "F.SilkS")
			(hide yes)
			(effects
				(font
					(size 1.27 1.27)
				)
			)
		)
		(property "Value" "0R6J-3-GP"
			(at -0.0508 -4.8514 270)
			(unlocked yes)
			(layer "F.Fab")
			(hide yes)
			(effects
				(font
					(size 1.016 1.016)
					(thickness 0.1524)
				)
			)
		)
		(property "Device Type" "R1206H28"
			(at 0 -6.3754 270)
			(unlocked yes)
			(layer "F.Fab")
			(hide yes)
			(effects
				(font
					(size 1.016 1.016)
					(thickness 0.1524)
				)
			)
		)
		(duplicate_pad_numbers_are_jumpers no)
		(fp_line
			(start -1.016 2.2352)
			(end -1.016 -2.2352)
			(stroke
				(width 0.1524)
				(type default)
			)
			(layer "F.SilkS")
		)
		(fp_line
			(start 1.016 2.2352)
			(end -1.016 2.2352)
			(stroke
				(width 0.1524)
				(type default)
			)
			(layer "F.SilkS")
		)
		(fp_line
			(start -1.016 -2.2352)
			(end 1.016 -2.2352)
			(stroke
				(width 0.1524)
				(type default)
			)
			(layer "F.SilkS")
		)
		(fp_line
			(start 1.016 -2.2352)
			(end 1.016 2.2352)
			(stroke
				(width 0.1524)
				(type default)
			)
			(layer "F.SilkS")
		)
		(fp_rect
			(start -1.0922 2.3114)
			(end 1.0922 -2.3114)
			(stroke
				(width 0)
				(type default)
			)
			(fill no)
			(layer "F.CrtYd")
		)
		(fp_poly
			(pts
				(xy -1.0922 -2.3114) (xy 1.0922 -2.3114) (xy 1.0922 2.3114) (xy -1.0922 2.3114)
			)
			(stroke
				(width 0)
				(type default)
			)
			(fill no)
			(layer "F.Fab")
		)
		(pad "1" smd rect
			(at 0 -1.397 270)
			(size 1.651 1.27)
			(layers "F.Cu" "F.Mask" "F.Paste")
			(net "P3V3_STBY")
		)
		(pad "2" smd rect
			(at 0 1.397 270)
			(size 1.651 1.27)
			(layers "F.Cu" "F.Mask" "F.Paste")
			(net "P3V3_STBY_OUT")
		)
	)
	(footprint ""
		(layer "F.Cu")
		(at 218.089988 -40.846756 180)
		(property "Reference" "R467"
			(at 0 0 180)
			(layer "F.SilkS")
			(hide yes)
			(effects
				(font
					(size 1.27 1.27)
				)
			)
		)
		(property "Value" "10KR2F-2-GP"
			(at 0.064008 -3.993896 180)
			(unlocked yes)
			(layer "F.Fab")
			(hide yes)
			(effects
				(font
					(size 1.016 1.016)
					(thickness 0.1524)
				)
			)
		)
		(property "Device Type" "R402H16"
			(at 0.064008 -5.517896 180)
			(unlocked yes)
			(layer "F.Fab")
			(hide yes)
			(effects
				(font
					(size 1.016 1.016)
					(thickness 0.1524)
				)
			)
		)
		(duplicate_pad_numbers_are_jumpers no)
		(fp_line
			(start 0.508 -0.9398)
			(end -0.508 -0.9398)
			(stroke
				(width 0.1524)
				(type default)
			)
			(layer "F.SilkS")
		)
		(fp_line
			(start -0.508 -0.9398)
			(end -0.508 0.9398)
			(stroke
				(width 0.1524)
				(type default)
			)
			(layer "F.SilkS")
		)
		(fp_rect
			(start -0.508 0.9398)
			(end 0.508 -0.9398)
			(stroke
				(width 0)
				(type default)
			)
			(fill no)
			(layer "F.CrtYd")
		)
		(fp_rect
			(start -0.508 0.9398)
			(end 0.508 -0.9398)
			(stroke
				(width 0)
				(type default)
			)
			(fill no)
			(layer "F.Fab")
		)
		(pad "1" smd custom
			(at 0 -0.4445 180)
			(size 0.1397 0.1397)
			(layers "F.Cu" "F.Mask" "F.Paste")
			(net "P5V_STBY_VREG")
			(options
				(clearance outline)
				(anchor circle)
			)
			(primitives
				(gr_poly
					(pts
						(arc
							(start -0.1778 -0.2794)
							(mid -0.249642 -0.249642)
							(end -0.2794 -0.1778)
						)
						(arc
							(start -0.2794 0.1778)
							(mid -0.249642 0.249642)
							(end -0.1778 0.2794)
						)
						(arc
							(start 0.1778 0.2794)
							(mid 0.249642 0.249642)
							(end 0.2794 0.1778)
						)
						(arc
							(start 0.2794 -0.1778)
							(mid 0.249642 -0.249642)
							(end 0.1778 -0.2794)
						)
					)
					(width 0)
					(fill yes)
				)
			)
		)
		(pad "2" smd custom
			(at 0 0.4445 180)
			(size 0.1397 0.1397)
			(layers "F.Cu" "F.Mask" "F.Paste")
			(net "PWRGD_P5V_STBY")
			(options
				(clearance outline)
				(anchor circle)
			)
			(primitives
				(gr_poly
					(pts
						(arc
							(start -0.1778 -0.2794)
							(mid -0.249642 -0.249642)
							(end -0.2794 -0.1778)
						)
						(arc
							(start -0.2794 0.1778)
							(mid -0.249642 0.249642)
							(end -0.1778 0.2794)
						)
						(arc
							(start 0.1778 0.2794)
							(mid 0.249642 0.249642)
							(end 0.2794 0.1778)
						)
						(arc
							(start 0.2794 -0.1778)
							(mid 0.249642 -0.249642)
							(end 0.1778 -0.2794)
						)
					)
					(width 0)
					(fill yes)
				)
			)
		)
	)
	(footprint ""
		(layer "F.Cu")
		(at 94.565216 -50.111914 -90)
		(property "Reference" "C186"
			(at 0 0 270)
			(layer "F.SilkS")
			(hide yes)
			(effects
				(font
					(size 1.27 1.27)
				)
			)
		)
		(property "Value" "SCD1U16V2KX-3GP"
			(at 1.1811 -2.7051 270)
			(unlocked yes)
			(layer "F.Fab")
			(hide yes)
			(effects
				(font
					(size 1.016 1.016)
					(thickness 0.1524)
				)
			)
		)
		(property "Device Type" "C402H22"
			(at 1.1811 -4.2291 270)
			(unlocked yes)
			(layer "F.Fab")
			(hide yes)
			(effects
				(font
					(size 1.016 1.016)
					(thickness 0.1524)
				)
			)
		)
		(duplicate_pad_numbers_are_jumpers no)
		(fp_rect
			(start -0.4318 0.9525)
			(end 0.4318 -0.9525)
			(stroke
				(width 0)
				(type default)
			)
			(fill no)
			(layer "F.CrtYd")
		)
		(fp_rect
			(start -0.4318 0.9525)
			(end 0.4318 -0.9525)
			(stroke
				(width 0)
				(type default)
			)
			(fill no)
			(layer "F.Fab")
		)
		(pad "1" smd custom
			(at 0 -0.4445 270)
			(size 0.1524 0.1524)
			(layers "F.Cu" "F.Mask" "F.Paste")
			(net "P3V3_STBY")
			(options
				(clearance outline)
				(anchor circle)
			)
			(primitives
				(gr_poly
					(pts
						(arc
							(start 0.3048 -0.2032)
							(mid 0.275042 -0.275042)
							(end 0.2032 -0.3048)
						)
						(arc
							(start -0.2032 -0.3048)
							(mid -0.275042 -0.275042)
							(end -0.3048 -0.2032)
						)
						(arc
							(start -0.3048 0.2032)
							(mid -0.275042 0.275042)
							(end -0.2032 0.3048)
						)
						(arc
							(start 0.2032 0.3048)
							(mid 0.275042 0.275042)
							(end 0.3048 0.2032)
						)
					)
					(width 0)
					(fill yes)
				)
			)
		)
		(pad "2" smd custom
			(at 0 0.4445 270)
			(size 0.1524 0.1524)
			(layers "F.Cu" "F.Mask" "F.Paste")
			(net "GND")
			(options
				(clearance outline)
				(anchor circle)
			)
			(primitives
				(gr_poly
					(pts
						(arc
							(start 0.3048 -0.2032)
							(mid 0.275042 -0.275042)
							(end 0.2032 -0.3048)
						)
						(arc
							(start -0.2032 -0.3048)
							(mid -0.275042 -0.275042)
							(end -0.3048 -0.2032)
						)
						(arc
							(start -0.3048 0.2032)
							(mid -0.275042 0.275042)
							(end -0.2032 0.3048)
						)
						(arc
							(start 0.2032 0.3048)
							(mid 0.275042 0.275042)
							(end 0.3048 0.2032)
						)
					)
					(width 0)
					(fill yes)
				)
			)
		)
	)
	(footprint ""
		(layer "F.Cu")
		(at 215.17864 -101.599492 90)
		(property "Reference" "R843"
			(at 0 0 90)
			(layer "F.SilkS")
			(hide yes)
			(effects
				(font
					(size 1.27 1.27)
				)
			)
		)
		(property "Value" "147KR2F-L-GP"
			(at 0.064008 -3.993896 90)
			(unlocked yes)
			(layer "F.Fab")
			(hide yes)
			(effects
				(font
					(size 1.016 1.016)
					(thickness 0.1524)
				)
			)
		)
		(property "Device Type" "R402H16"
			(at 0.064008 -5.517896 90)
			(unlocked yes)
			(layer "F.Fab")
			(hide yes)
			(effects
				(font
					(size 1.016 1.016)
					(thickness 0.1524)
				)
			)
		)
		(duplicate_pad_numbers_are_jumpers no)
		(fp_line
			(start 0.508 -0.9398)
			(end -0.508 -0.9398)
			(stroke
				(width 0.1524)
				(type default)
			)
			(layer "F.SilkS")
		)
		(fp_line
			(start -0.508 -0.9398)
			(end -0.508 0.9398)
			(stroke
				(width 0.1524)
				(type default)
			)
			(layer "F.SilkS")
		)
		(fp_rect
			(start -0.508 0.9398)
			(end 0.508 -0.9398)
			(stroke
				(width 0)
				(type default)
			)
			(fill no)
			(layer "F.CrtYd")
		)
		(fp_rect
			(start -0.508 0.9398)
			(end 0.508 -0.9398)
			(stroke
				(width 0)
				(type default)
			)
			(fill no)
			(layer "F.Fab")
		)
		(pad "1" smd custom
			(at 0 -0.4445 90)
			(size 0.1397 0.1397)
			(layers "F.Cu" "F.Mask" "F.Paste")
			(net "AGND_P3V3_M2")
			(options
				(clearance outline)
				(anchor circle)
			)
			(primitives
				(gr_poly
					(pts
						(arc
							(start -0.1778 -0.2794)
							(mid -0.249642 -0.249642)
							(end -0.2794 -0.1778)
						)
						(arc
							(start -0.2794 0.1778)
							(mid -0.249642 0.249642)
							(end -0.1778 0.2794)
						)
						(arc
							(start 0.1778 0.2794)
							(mid 0.249642 0.249642)
							(end 0.2794 0.1778)
						)
						(arc
							(start 0.2794 -0.1778)
							(mid 0.249642 -0.249642)
							(end 0.1778 -0.2794)
						)
					)
					(width 0)
					(fill yes)
				)
			)
		)
		(pad "2" smd custom
			(at 0 0.4445 90)
			(size 0.1397 0.1397)
			(layers "F.Cu" "F.Mask" "F.Paste")
			(net "P3V3_M2_TRIP")
			(options
				(clearance outline)
				(anchor circle)
			)
			(primitives
				(gr_poly
					(pts
						(arc
							(start -0.1778 -0.2794)
							(mid -0.249642 -0.249642)
							(end -0.2794 -0.1778)
						)
						(arc
							(start -0.2794 0.1778)
							(mid -0.249642 0.249642)
							(end -0.1778 0.2794)
						)
						(arc
							(start 0.1778 0.2794)
							(mid 0.249642 0.249642)
							(end 0.2794 0.1778)
						)
						(arc
							(start 0.2794 -0.1778)
							(mid 0.249642 -0.249642)
							(end 0.1778 -0.2794)
						)
					)
					(width 0)
					(fill yes)
				)
			)
		)
	)
	(footprint ""
		(layer "F.Cu")
		(at 47.01159 -158.5976)
		(property "Reference" "R171"
			(at 0 0 0)
			(layer "F.SilkS")
			(hide yes)
			(effects
				(font
					(size 1.27 1.27)
				)
			)
		)
		(property "Value" "0R2J-2-GP"
			(at 0.064008 -3.993896 0)
			(unlocked yes)
			(layer "F.Fab")
			(hide yes)
			(effects
				(font
					(size 1.016 1.016)
					(thickness 0.1524)
				)
			)
		)
		(property "Device Type" "R402H16"
			(at 0.064008 -5.517896 0)
			(unlocked yes)
			(layer "F.Fab")
			(hide yes)
			(effects
				(font
					(size 1.016 1.016)
					(thickness 0.1524)
				)
			)
		)
		(duplicate_pad_numbers_are_jumpers no)
		(fp_line
			(start -0.508 -0.9398)
			(end -0.508 0.9398)
			(stroke
				(width 0.1524)
				(type default)
			)
			(layer "F.SilkS")
		)
		(fp_line
			(start 0.508 -0.9398)
			(end -0.508 -0.9398)
			(stroke
				(width 0.1524)
				(type default)
			)
			(layer "F.SilkS")
		)
		(fp_rect
			(start -0.508 0.9398)
			(end 0.508 -0.9398)
			(stroke
				(width 0)
				(type default)
			)
			(fill no)
			(layer "F.CrtYd")
		)
		(fp_rect
			(start -0.508 0.9398)
			(end 0.508 -0.9398)
			(stroke
				(width 0)
				(type default)
			)
			(fill no)
			(layer "F.Fab")
		)
		(pad "1" smd custom
			(at 0 -0.4445)
			(size 0.1397 0.1397)
			(layers "F.Cu" "F.Mask" "F.Paste")
			(net "I2C_DPB_SCL_OUT")
			(options
				(clearance outline)
				(anchor circle)
			)
			(primitives
				(gr_poly
					(pts
						(arc
							(start -0.1778 -0.2794)
							(mid -0.249642 -0.249642)
							(end -0.2794 -0.1778)
						)
						(arc
							(start -0.2794 0.1778)
							(mid -0.249642 0.249642)
							(end -0.1778 0.2794)
						)
						(arc
							(start 0.1778 0.2794)
							(mid 0.249642 0.249642)
							(end 0.2794 0.1778)
						)
						(arc
							(start 0.2794 -0.1778)
							(mid 0.249642 -0.249642)
							(end 0.1778 -0.2794)
						)
					)
					(width 0)
					(fill yes)
				)
			)
		)
		(pad "2" smd custom
			(at 0 0.4445)
			(size 0.1397 0.1397)
			(layers "F.Cu" "F.Mask" "F.Paste")
			(net "BMC_SMB7_CLK")
			(options
				(clearance outline)
				(anchor circle)
			)
			(primitives
				(gr_poly
					(pts
						(arc
							(start -0.1778 -0.2794)
							(mid -0.249642 -0.249642)
							(end -0.2794 -0.1778)
						)
						(arc
							(start -0.2794 0.1778)
							(mid -0.249642 0.249642)
							(end -0.1778 0.2794)
						)
						(arc
							(start 0.1778 0.2794)
							(mid 0.249642 0.249642)
							(end 0.2794 0.1778)
						)
						(arc
							(start 0.2794 -0.1778)
							(mid 0.249642 -0.249642)
							(end 0.1778 -0.2794)
						)
					)
					(width 0)
					(fill yes)
				)
			)
		)
	)
	(footprint ""
		(layer "F.Cu")
		(at 81.70418 -178.529996 180)
		(property "Reference" "C192"
			(at 0 0 180)
			(layer "F.SilkS")
			(hide yes)
			(effects
				(font
					(size 1.27 1.27)
				)
			)
		)
		(property "Value" "SC10U6D3V5KX-4GP"
			(at -0.0762 -6.1214 180)
			(unlocked yes)
			(layer "F.Fab")
			(hide yes)
			(effects
				(font
					(size 1.016 1.016)
					(thickness 0.1524)
				)
			)
		)
		(property "Device Type" "C805H58"
			(at -0.0762 -8.1534 180)
			(unlocked yes)
			(layer "F.Fab")
			(hide yes)
			(effects
				(font
					(size 1.016 1.016)
					(thickness 0.1524)
				)
			)
		)
		(duplicate_pad_numbers_are_jumpers no)
		(fp_line
			(start 0.635 0)
			(end -0.635 0)
			(stroke
				(width 0.508)
				(type default)
			)
			(layer "F.SilkS")
		)
		(fp_rect
			(start -0.9652 1.778)
			(end 0.9652 -1.778)
			(stroke
				(width 0)
				(type default)
			)
			(fill no)
			(layer "F.CrtYd")
		)
		(fp_poly
			(pts
				(xy -0.9652 -1.778) (xy 0.9652 -1.778) (xy 0.9652 1.778) (xy -0.9652 1.778)
			)
			(stroke
				(width 0)
				(type default)
			)
			(fill no)
			(layer "F.Fab")
		)
		(pad "1" smd rect
			(at 0 -0.9652 180)
			(size 1.397 1.143)
			(layers "F.Cu" "F.Mask" "F.Paste")
			(net "TPS74801_P2V5_STBY_OUT")
		)
		(pad "2" smd rect
			(at 0 0.9652 180)
			(size 1.397 1.143)
			(layers "F.Cu" "F.Mask" "F.Paste")
			(net "GND")
		)
	)
	(footprint ""
		(layer "F.Cu")
		(at 92.751656 -155.60548 90)
		(property "Reference" "U99"
			(at 0 0 90)
			(layer "F.SilkS")
			(hide yes)
			(effects
				(font
					(size 1.27 1.27)
				)
			)
		)
		(property "Value" "USB2514B-AEZC-TR-GP-U"
			(at -5.5372 -5.2832 90)
			(unlocked yes)
			(layer "F.Fab")
			(hide yes)
			(effects
				(font
					(size 1.016 1.016)
					(thickness 0.1524)
				)
			)
		)
		(property "Device Type" "QFN36-G3D85H40"
			(at -5.5372 -6.8072 90)
			(unlocked yes)
			(layer "F.Fab")
			(hide yes)
			(effects
				(font
					(size 1.016 1.016)
					(thickness 0.1524)
				)
			)
		)
		(duplicate_pad_numbers_are_jumpers no)
		(fp_line
			(start -4.0132 -4.0132)
			(end -2.7432 -4.0132)
			(stroke
				(width 0.1524)
				(type default)
			)
			(layer "F.SilkS")
		)
		(fp_line
			(start -0.0254 -3.7846)
			(end -0.0254 -4.2926)
			(stroke
				(width 0.1524)
				(type default)
			)
			(layer "F.SilkS")
		)
		(fp_line
			(start -4.0132 -2.7432)
			(end -4.0132 -4.0132)
			(stroke
				(width 0.1524)
				(type default)
			)
			(layer "F.SilkS")
		)
		(fp_line
			(start -3.7846 -2.0066)
			(end -4.4704 -2.0066)
			(stroke
				(width 0.1524)
				(type default)
			)
			(layer "F.SilkS")
		)
		(fp_line
			(start 4.3434 -1.524)
			(end 3.8608 -1.524)
			(stroke
				(width 0.1524)
				(type default)
			)
			(layer "F.SilkS")
		)
		(fp_line
			(start -3.8608 0.4826)
			(end -4.318 0.4826)
			(stroke
				(width 0.1524)
				(type default)
			)
			(layer "F.SilkS")
		)
		(fp_line
			(start 4.4958 0.9652)
			(end 3.81 0.9652)
			(stroke
				(width 0.1524)
				(type default)
			)
			(layer "F.SilkS")
		)
		(fp_line
			(start -1.4986 3.8354)
			(end -1.4986 4.445)
			(stroke
				(width 0.1524)
				(type default)
			)
			(layer "F.SilkS")
		)
		(fp_line
			(start 4.0132 4.0132)
			(end 4.0132 2.7432)
			(stroke
				(width 0.1524)
				(type default)
			)
			(layer "F.SilkS")
		)
		(fp_line
			(start 2.7432 4.0132)
			(end 4.0132 4.0132)
			(stroke
				(width 0.1524)
				(type default)
			)
			(layer "F.SilkS")
		)
		(fp_line
			(start -2.7432 4.0132)
			(end -4.0132 4.0132)
			(stroke
				(width 0.1524)
				(type default)
			)
			(layer "F.SilkS")
		)
		(fp_line
			(start -4.0132 4.0132)
			(end -4.0132 2.7432)
			(stroke
				(width 0.1524)
				(type default)
			)
			(layer "F.SilkS")
		)
		(fp_line
			(start 0.9906 4.318)
			(end 0.9906 3.81)
			(stroke
				(width 0.1524)
				(type default)
			)
			(layer "F.SilkS")
		)
		(fp_poly
			(pts
				(xy 2.7432 -4.0132) (xy 4.0132 -2.7432) (xy 4.0132 -4.0132)
			)
			(stroke
				(width 0)
				(type default)
			)
			(fill yes)
			(layer "F.SilkS")
		)
		(fp_rect
			(start -4.0132 4.0132)
			(end 4.0132 -4.0132)
			(stroke
				(width 0)
				(type default)
			)
			(fill no)
			(layer "F.CrtYd")
		)
		(fp_rect
			(start -4.0132 4.0132)
			(end 4.0132 -4.0132)
			(stroke
				(width 0)
				(type default)
			)
			(fill no)
			(layer "F.Fab")
		)
		(pad "1" smd rect
			(at 1.999996 -2.9591 90)
			(size 0.3048 1.0922)
			(layers "F.Cu" "F.Mask" "F.Paste")
			(net "USB_P1_DN")
		)
		(pad "2" smd rect
			(at 1.500124 -2.8702 90)
			(size 0.3048 1.27)
			(layers "F.Cu" "F.Mask" "F.Paste")
			(net "USB_P1_DP")
		)
		(pad "3" smd rect
			(at 0.999998 -2.8702 90)
			(size 0.3048 1.27)
			(layers "F.Cu" "F.Mask" "F.Paste")
			(net "USB_P2_DN")
		)
		(pad "4" smd rect
			(at 0.500126 -2.8702 90)
			(size 0.3048 1.27)
			(layers "F.Cu" "F.Mask" "F.Paste")
			(net "USB_P2_DP")
		)
		(pad "5" smd rect
			(at 0 -2.8702 90)
			(size 0.3048 1.27)
			(layers "F.Cu" "F.Mask" "F.Paste")
			(net "P3V3_STBY")
		)
		(pad "6" smd rect
			(at -0.500126 -2.8702 90)
			(size 0.3048 1.27)
			(layers "F.Cu" "F.Mask" "F.Paste")
			(net "USB_P3_DN")
		)
		(pad "7" smd rect
			(at -0.999998 -2.8702 90)
			(size 0.3048 1.27)
			(layers "F.Cu" "F.Mask" "F.Paste")
			(net "USB_P3_DP")
		)
		(pad "8" smd rect
			(at -1.500124 -2.8702 90)
			(size 0.3048 1.27)
			(layers "F.Cu" "F.Mask" "F.Paste")
			(net "Net_109")
		)
		(pad "9" smd rect
			(at -1.999996 -2.9591 90)
			(size 0.3048 1.0922)
			(layers "F.Cu" "F.Mask" "F.Paste")
			(net "Net_110")
		)
		(pad "10" smd rect
			(at -2.9591 -1.999996 90)
			(size 1.0922 0.3048)
			(layers "F.Cu" "F.Mask" "F.Paste")
			(net "P3V3_STBY")
		)
		(pad "11" smd rect
			(at -2.8702 -1.500124 90)
			(size 1.27 0.3048)
			(layers "F.Cu" "F.Mask" "F.Paste")
			(net "GND")
		)
		(pad "12" smd rect
			(at -2.8702 -0.999998 90)
			(size 1.27 0.3048)
			(layers "F.Cu" "F.Mask" "F.Paste")
			(net "USB_EN_1")
		)
		(pad "13" smd rect
			(at -2.8702 -0.500126 90)
			(size 1.27 0.3048)
			(layers "F.Cu" "F.Mask" "F.Paste")
			(net "USB_OCS_N1")
		)
		(pad "14" smd rect
			(at -2.8702 0 90)
			(size 1.27 0.3048)
			(layers "F.Cu" "F.Mask" "F.Paste")
			(net "CRFILT")
		)
		(pad "15" smd rect
			(at -2.8702 0.500126 90)
			(size 1.27 0.3048)
			(layers "F.Cu" "F.Mask" "F.Paste")
			(net "P3V3_STBY")
		)
		(pad "16" smd rect
			(at -2.8702 0.999998 90)
			(size 1.27 0.3048)
			(layers "F.Cu" "F.Mask" "F.Paste")
			(net "USB_EN_2")
		)
		(pad "17" smd rect
			(at -2.8702 1.500124 90)
			(size 1.27 0.3048)
			(layers "F.Cu" "F.Mask" "F.Paste")
			(net "USB_OCS_N2")
		)
		(pad "18" smd rect
			(at -2.9591 1.999996 90)
			(size 1.0922 0.3048)
			(layers "F.Cu" "F.Mask" "F.Paste")
			(net "USB_EN_3")
		)
		(pad "19" smd rect
			(at -1.999996 2.9591 90)
			(size 0.3048 1.0922)
			(layers "F.Cu" "F.Mask" "F.Paste")
			(net "USB_OCS_N3")
		)
		(pad "20" smd rect
			(at -1.500124 2.8702 90)
			(size 0.3048 1.27)
			(layers "F.Cu" "F.Mask" "F.Paste")
			(net "USB_EN_4")
		)
		(pad "21" smd rect
			(at -0.999998 2.8702 90)
			(size 0.3048 1.27)
			(layers "F.Cu" "F.Mask" "F.Paste")
			(net "USB_OCS_N4")
		)
		(pad "22" smd rect
			(at -0.500126 2.8702 90)
			(size 0.3048 1.27)
			(layers "F.Cu" "F.Mask" "F.Paste")
			(net "TP_USB_SDA")
		)
		(pad "23" smd rect
			(at 0 2.8702 90)
			(size 0.3048 1.27)
			(layers "F.Cu" "F.Mask" "F.Paste")
			(net "P3V3_STBY")
		)
		(pad "24" smd rect
			(at 0.500126 2.8702 90)
			(size 0.3048 1.27)
			(layers "F.Cu" "F.Mask" "F.Paste")
			(net "CFG_SEL0")
		)
		(pad "25" smd rect
			(at 0.999998 2.8702 90)
			(size 0.3048 1.27)
			(layers "F.Cu" "F.Mask" "F.Paste")
			(net "CFG_SEL1")
		)
		(pad "26" smd rect
			(at 1.500124 2.8702 90)
			(size 0.3048 1.27)
			(layers "F.Cu" "F.Mask" "F.Paste")
			(net "USB_RESET_N")
		)
		(pad "27" smd rect
			(at 1.999996 2.9591 90)
			(size 0.3048 1.0922)
			(layers "F.Cu" "F.Mask" "F.Paste")
			(net "VBUS_DET")
		)
		(pad "28" smd rect
			(at 2.9591 1.999996 90)
			(size 1.0922 0.3048)
			(layers "F.Cu" "F.Mask" "F.Paste")
			(net "USB_SUSP_IND")
		)
		(pad "29" smd rect
			(at 2.8702 1.500124 90)
			(size 1.27 0.3048)
			(layers "F.Cu" "F.Mask" "F.Paste")
			(net "P3V3_STBY")
		)
		(pad "30" smd rect
			(at 2.8702 0.999998 90)
			(size 1.27 0.3048)
			(layers "F.Cu" "F.Mask" "F.Paste")
			(net "USB_COMP_DN")
		)
		(pad "31" smd rect
			(at 2.8702 0.500126 90)
			(size 1.27 0.3048)
			(layers "F.Cu" "F.Mask" "F.Paste")
			(net "USB_COMP_DP")
		)
		(pad "32" smd rect
			(at 2.8702 0 90)
			(size 1.27 0.3048)
			(layers "F.Cu" "F.Mask" "F.Paste")
			(net "USB_HUB_XTAL_OUT")
		)
		(pad "33" smd rect
			(at 2.8702 -0.500126 90)
			(size 1.27 0.3048)
			(layers "F.Cu" "F.Mask" "F.Paste")
			(net "USB_HUB_XTAL_IN")
		)
		(pad "34" smd rect
			(at 2.8702 -0.999998 90)
			(size 1.27 0.3048)
			(layers "F.Cu" "F.Mask" "F.Paste")
			(net "PLLFILT")
		)
		(pad "35" smd rect
			(at 2.8702 -1.500124 90)
			(size 1.27 0.3048)
			(layers "F.Cu" "F.Mask" "F.Paste")
			(net "RBIAS")
		)
		(pad "36" smd rect
			(at 2.9591 -1.999996 90)
			(size 1.0922 0.3048)
			(layers "F.Cu" "F.Mask" "F.Paste")
			(net "P3V3_STBY")
		)
		(pad "37" smd rect
			(at 0 0 90)
			(size 3.8608 3.8608)
			(layers "F.Cu" "F.Mask" "F.Paste")
			(net "GND")
		)
	)
	(footprint ""
		(layer "F.Cu")
		(at 88.362028 -69.285612)
		(property "Reference" "R15"
			(at 0 0 0)
			(layer "F.SilkS")
			(hide yes)
			(effects
				(font
					(size 1.27 1.27)
				)
			)
		)
		(property "Value" "0R2J-2-GP"
			(at 0.064008 -3.993896 0)
			(unlocked yes)
			(layer "F.Fab")
			(hide yes)
			(effects
				(font
					(size 1.016 1.016)
					(thickness 0.1524)
				)
			)
		)
		(property "Device Type" "R402H16"
			(at 0.064008 -5.517896 0)
			(unlocked yes)
			(layer "F.Fab")
			(hide yes)
			(effects
				(font
					(size 1.016 1.016)
					(thickness 0.1524)
				)
			)
		)
		(duplicate_pad_numbers_are_jumpers no)
		(fp_line
			(start -0.508 -0.9398)
			(end -0.508 0.9398)
			(stroke
				(width 0.1524)
				(type default)
			)
			(layer "F.SilkS")
		)
		(fp_line
			(start 0.508 -0.9398)
			(end -0.508 -0.9398)
			(stroke
				(width 0.1524)
				(type default)
			)
			(layer "F.SilkS")
		)
		(fp_rect
			(start -0.508 0.9398)
			(end 0.508 -0.9398)
			(stroke
				(width 0)
				(type default)
			)
			(fill no)
			(layer "F.CrtYd")
		)
		(fp_rect
			(start -0.508 0.9398)
			(end 0.508 -0.9398)
			(stroke
				(width 0)
				(type default)
			)
			(fill no)
			(layer "F.Fab")
		)
		(pad "1" smd custom
			(at 0 -0.4445)
			(size 0.1397 0.1397)
			(layers "F.Cu" "F.Mask" "F.Paste")
			(net "NCSI_RXD1")
			(options
				(clearance outline)
				(anchor circle)
			)
			(primitives
				(gr_poly
					(pts
						(arc
							(start -0.1778 -0.2794)
							(mid -0.249642 -0.249642)
							(end -0.2794 -0.1778)
						)
						(arc
							(start -0.2794 0.1778)
							(mid -0.249642 0.249642)
							(end -0.1778 0.2794)
						)
						(arc
							(start 0.1778 0.2794)
							(mid 0.249642 0.249642)
							(end 0.2794 0.1778)
						)
						(arc
							(start 0.2794 -0.1778)
							(mid 0.249642 -0.249642)
							(end 0.1778 -0.2794)
						)
					)
					(width 0)
					(fill yes)
				)
			)
		)
		(pad "2" smd custom
			(at 0 0.4445)
			(size 0.1397 0.1397)
			(layers "F.Cu" "F.Mask" "F.Paste")
			(net "NCSI_RXD1_R")
			(options
				(clearance outline)
				(anchor circle)
			)
			(primitives
				(gr_poly
					(pts
						(arc
							(start -0.1778 -0.2794)
							(mid -0.249642 -0.249642)
							(end -0.2794 -0.1778)
						)
						(arc
							(start -0.2794 0.1778)
							(mid -0.249642 0.249642)
							(end -0.1778 0.2794)
						)
						(arc
							(start 0.1778 0.2794)
							(mid 0.249642 0.249642)
							(end 0.2794 0.1778)
						)
						(arc
							(start 0.2794 -0.1778)
							(mid 0.249642 -0.249642)
							(end 0.1778 -0.2794)
						)
					)
					(width 0)
					(fill yes)
				)
			)
		)
	)
	(footprint ""
		(layer "F.Cu")
		(at 93.72092 -62.359032 90)
		(property "Reference" "R502"
			(at 0 0 90)
			(layer "F.SilkS")
			(hide yes)
			(effects
				(font
					(size 1.27 1.27)
				)
			)
		)
		(property "Value" "2K2R2J-2-GP"
			(at 0.064008 -3.993896 90)
			(unlocked yes)
			(layer "F.Fab")
			(hide yes)
			(effects
				(font
					(size 1.016 1.016)
					(thickness 0.1524)
				)
			)
		)
		(property "Device Type" "R402H16"
			(at 0.064008 -5.517896 90)
			(unlocked yes)
			(layer "F.Fab")
			(hide yes)
			(effects
				(font
					(size 1.016 1.016)
					(thickness 0.1524)
				)
			)
		)
		(duplicate_pad_numbers_are_jumpers no)
		(fp_line
			(start 0.508 -0.9398)
			(end -0.508 -0.9398)
			(stroke
				(width 0.1524)
				(type default)
			)
			(layer "F.SilkS")
		)
		(fp_line
			(start -0.508 -0.9398)
			(end -0.508 0.9398)
			(stroke
				(width 0.1524)
				(type default)
			)
			(layer "F.SilkS")
		)
		(fp_rect
			(start -0.508 0.9398)
			(end 0.508 -0.9398)
			(stroke
				(width 0)
				(type default)
			)
			(fill no)
			(layer "F.CrtYd")
		)
		(fp_rect
			(start -0.508 0.9398)
			(end 0.508 -0.9398)
			(stroke
				(width 0)
				(type default)
			)
			(fill no)
			(layer "F.Fab")
		)
		(pad "1" smd custom
			(at 0 -0.4445 90)
			(size 0.1397 0.1397)
			(layers "F.Cu" "F.Mask" "F.Paste")
			(net "P3V3_STBY")
			(options
				(clearance outline)
				(anchor circle)
			)
			(primitives
				(gr_poly
					(pts
						(arc
							(start -0.1778 -0.2794)
							(mid -0.249642 -0.249642)
							(end -0.2794 -0.1778)
						)
						(arc
							(start -0.2794 0.1778)
							(mid -0.249642 0.249642)
							(end -0.1778 0.2794)
						)
						(arc
							(start 0.1778 0.2794)
							(mid 0.249642 0.249642)
							(end 0.2794 0.1778)
						)
						(arc
							(start 0.2794 -0.1778)
							(mid 0.249642 -0.249642)
							(end 0.1778 -0.2794)
						)
					)
					(width 0)
					(fill yes)
				)
			)
		)
		(pad "2" smd custom
			(at 0 0.4445 90)
			(size 0.1397 0.1397)
			(layers "F.Cu" "F.Mask" "F.Paste")
			(net "IOM_FULL_PWR_EN")
			(options
				(clearance outline)
				(anchor circle)
			)
			(primitives
				(gr_poly
					(pts
						(arc
							(start -0.1778 -0.2794)
							(mid -0.249642 -0.249642)
							(end -0.2794 -0.1778)
						)
						(arc
							(start -0.2794 0.1778)
							(mid -0.249642 0.249642)
							(end -0.1778 0.2794)
						)
						(arc
							(start 0.1778 0.2794)
							(mid 0.249642 0.249642)
							(end 0.2794 0.1778)
						)
						(arc
							(start 0.2794 -0.1778)
							(mid 0.249642 -0.249642)
							(end 0.1778 -0.2794)
						)
					)
					(width 0)
					(fill yes)
				)
			)
		)
	)
	(footprint ""
		(layer "F.Cu")
		(at 212.085936 -94.683326)
		(property "Reference" "R840"
			(at 0 0 0)
			(layer "F.SilkS")
			(hide yes)
			(effects
				(font
					(size 1.27 1.27)
				)
			)
		)
		(property "Value" "44K2R2F-1-GP"
			(at 0.064008 -3.993896 0)
			(unlocked yes)
			(layer "F.Fab")
			(hide yes)
			(effects
				(font
					(size 1.016 1.016)
					(thickness 0.1524)
				)
			)
		)
		(property "Device Type" "R402H16"
			(at 0.064008 -5.517896 0)
			(unlocked yes)
			(layer "F.Fab")
			(hide yes)
			(effects
				(font
					(size 1.016 1.016)
					(thickness 0.1524)
				)
			)
		)
		(duplicate_pad_numbers_are_jumpers no)
		(fp_line
			(start -0.508 -0.9398)
			(end -0.508 0.9398)
			(stroke
				(width 0.1524)
				(type default)
			)
			(layer "F.SilkS")
		)
		(fp_line
			(start 0.508 -0.9398)
			(end -0.508 -0.9398)
			(stroke
				(width 0.1524)
				(type default)
			)
			(layer "F.SilkS")
		)
		(fp_rect
			(start -0.508 0.9398)
			(end 0.508 -0.9398)
			(stroke
				(width 0)
				(type default)
			)
			(fill no)
			(layer "F.CrtYd")
		)
		(fp_rect
			(start -0.508 0.9398)
			(end 0.508 -0.9398)
			(stroke
				(width 0)
				(type default)
			)
			(fill no)
			(layer "F.Fab")
		)
		(pad "1" smd custom
			(at 0 -0.4445)
			(size 0.1397 0.1397)
			(layers "F.Cu" "F.Mask" "F.Paste")
			(net "P3V3_M2_VFB")
			(options
				(clearance outline)
				(anchor circle)
			)
			(primitives
				(gr_poly
					(pts
						(arc
							(start -0.1778 -0.2794)
							(mid -0.249642 -0.249642)
							(end -0.2794 -0.1778)
						)
						(arc
							(start -0.2794 0.1778)
							(mid -0.249642 0.249642)
							(end -0.1778 0.2794)
						)
						(arc
							(start 0.1778 0.2794)
							(mid 0.249642 0.249642)
							(end 0.2794 0.1778)
						)
						(arc
							(start 0.2794 -0.1778)
							(mid 0.249642 -0.249642)
							(end 0.1778 -0.2794)
						)
					)
					(width 0)
					(fill yes)
				)
			)
		)
		(pad "2" smd custom
			(at 0 0.4445)
			(size 0.1397 0.1397)
			(layers "F.Cu" "F.Mask" "F.Paste")
			(net "P3V3_M2_VFB_R")
			(options
				(clearance outline)
				(anchor circle)
			)
			(primitives
				(gr_poly
					(pts
						(arc
							(start -0.1778 -0.2794)
							(mid -0.249642 -0.249642)
							(end -0.2794 -0.1778)
						)
						(arc
							(start -0.2794 0.1778)
							(mid -0.249642 0.249642)
							(end -0.1778 0.2794)
						)
						(arc
							(start 0.1778 0.2794)
							(mid 0.249642 0.249642)
							(end 0.2794 0.1778)
						)
						(arc
							(start 0.2794 -0.1778)
							(mid 0.249642 -0.249642)
							(end 0.1778 -0.2794)
						)
					)
					(width 0)
					(fill yes)
				)
			)
		)
	)
	(footprint ""
		(layer "F.Cu")
		(at 92.2528 -174.0408 -90)
		(property "Reference" "U107"
			(at 0 0 270)
			(layer "F.SilkS")
			(hide yes)
			(effects
				(font
					(size 1.27 1.27)
				)
			)
		)
		(property "Value" "SN74CBTLV3245APWR-GP"
			(at -0.889 -6.2738 270)
			(unlocked yes)
			(layer "F.Fab")
			(hide yes)
			(effects
				(font
					(size 1.016 1.016)
					(thickness 0.1524)
				)
			)
		)
		(property "Device Type" "TSOIC20H48"
			(at -0.9144 -7.8994 270)
			(unlocked yes)
			(layer "F.Fab")
			(hide yes)
			(effects
				(font
					(size 1.016 1.016)
					(thickness 0.1524)
				)
			)
		)
		(duplicate_pad_numbers_are_jumpers no)
		(fp_line
			(start -3.556 4.064)
			(end -3.556 1.778)
			(stroke
				(width 0.508)
				(type default)
			)
			(layer "F.SilkS")
		)
		(fp_line
			(start -3.556 1.397)
			(end -3.556 1.778)
			(stroke
				(width 0.2032)
				(type default)
			)
			(layer "F.SilkS")
		)
		(fp_line
			(start 3.175 1.397)
			(end -3.556 1.397)
			(stroke
				(width 0.2032)
				(type default)
			)
			(layer "F.SilkS")
		)
		(fp_line
			(start -2.667 0)
			(end -3.556 0.889)
			(stroke
				(width 0.2032)
				(type default)
			)
			(layer "F.SilkS")
		)
		(fp_line
			(start -2.667 0)
			(end -3.556 -0.889)
			(stroke
				(width 0.2032)
				(type default)
			)
			(layer "F.SilkS")
		)
		(fp_line
			(start -3.556 -1.397)
			(end -3.556 4.064)
			(stroke
				(width 0.2032)
				(type default)
			)
			(layer "F.SilkS")
		)
		(fp_line
			(start -3.556 -1.397)
			(end 3.175 -1.397)
			(stroke
				(width 0.2032)
				(type default)
			)
			(layer "F.SilkS")
		)
		(fp_line
			(start 3.175 -1.397)
			(end 3.175 1.397)
			(stroke
				(width 0.2032)
				(type default)
			)
			(layer "F.SilkS")
		)
		(fp_poly
			(pts
				(xy -3.25628 -1.8542) (xy 3.25628 -1.8542) (xy 3.25628 1.8542) (xy -3.25628 1.8542)
			)
			(stroke
				(width 0)
				(type default)
			)
			(fill yes)
			(layer "F.SilkS")
		)
		(fp_rect
			(start -3.556 3.81)
			(end 3.556 -3.81)
			(stroke
				(width 0)
				(type default)
			)
			(fill no)
			(layer "F.CrtYd")
		)
		(fp_poly
			(pts
				(xy -3.556 -3.81) (xy 3.556 -3.81) (xy 3.556 3.81) (xy -3.556 3.81)
			)
			(stroke
				(width 0)
				(type default)
			)
			(fill no)
			(layer "F.Fab")
		)
		(pad "1" smd rect
			(at -2.92608 2.8194 270)
			(size 0.3556 1.524)
			(layers "F.Cu" "F.Mask" "F.Paste")
			(net "Net_131")
		)
		(pad "2" smd rect
			(at -2.27584 2.8194 270)
			(size 0.3556 1.524)
			(layers "F.Cu" "F.Mask" "F.Paste")
			(net "Net_68")
		)
		(pad "3" smd rect
			(at -1.6256 2.8194 270)
			(size 0.3556 1.524)
			(layers "F.Cu" "F.Mask" "F.Paste")
			(net "Net_70")
		)
		(pad "4" smd rect
			(at -0.97536 2.8194 270)
			(size 0.3556 1.524)
			(layers "F.Cu" "F.Mask" "F.Paste")
			(net "Net_66")
		)
		(pad "5" smd rect
			(at -0.32512 2.8194 270)
			(size 0.3556 1.524)
			(layers "F.Cu" "F.Mask" "F.Paste")
			(net "I2C_DPB_MISC_SCL_OUT")
		)
		(pad "6" smd rect
			(at 0.32512 2.8194 270)
			(size 0.3556 1.524)
			(layers "F.Cu" "F.Mask" "F.Paste")
			(net "I2C_DPB_MISC_SDA_OUT")
		)
		(pad "7" smd rect
			(at 0.97536 2.8194 270)
			(size 0.3556 1.524)
			(layers "F.Cu" "F.Mask" "F.Paste")
			(net "DPB_MISC_ALERT")
		)
		(pad "8" smd rect
			(at 1.6256 2.8194 270)
			(size 0.3556 1.524)
			(layers "F.Cu" "F.Mask" "F.Paste")
			(net "Net_130")
		)
		(pad "9" smd rect
			(at 2.27584 2.8194 270)
			(size 0.3556 1.524)
			(layers "F.Cu" "F.Mask" "F.Paste")
			(net "Net_129")
		)
		(pad "10" smd rect
			(at 2.92608 2.8194 270)
			(size 0.3556 1.524)
			(layers "F.Cu" "F.Mask" "F.Paste")
			(net "GND")
		)
		(pad "11" smd rect
			(at 2.92608 -2.8194 270)
			(size 0.3556 1.524)
			(layers "F.Cu" "F.Mask" "F.Paste")
			(net "Net_128")
		)
		(pad "12" smd rect
			(at 2.27584 -2.8194 270)
			(size 0.3556 1.524)
			(layers "F.Cu" "F.Mask" "F.Paste")
			(net "Net_127")
		)
		(pad "13" smd rect
			(at 1.6256 -2.8194 270)
			(size 0.3556 1.524)
			(layers "F.Cu" "F.Mask" "F.Paste")
			(net "DPB_MISC_ALERT_OUT_R")
		)
		(pad "14" smd rect
			(at 0.97536 -2.8194 270)
			(size 0.3556 1.524)
			(layers "F.Cu" "F.Mask" "F.Paste")
			(net "I2C_DPB_MISC_SDA_R")
		)
		(pad "15" smd rect
			(at 0.32512 -2.8194 270)
			(size 0.3556 1.524)
			(layers "F.Cu" "F.Mask" "F.Paste")
			(net "I2C_DPB_MISC_SCL_R")
		)
		(pad "16" smd rect
			(at -0.32512 -2.8194 270)
			(size 0.3556 1.524)
			(layers "F.Cu" "F.Mask" "F.Paste")
			(net "Net_71")
		)
		(pad "17" smd rect
			(at -0.97536 -2.8194 270)
			(size 0.3556 1.524)
			(layers "F.Cu" "F.Mask" "F.Paste")
			(net "Net_69")
		)
		(pad "18" smd rect
			(at -1.6256 -2.8194 270)
			(size 0.3556 1.524)
			(layers "F.Cu" "F.Mask" "F.Paste")
			(net "Net_67")
		)
		(pad "19" smd rect
			(at -2.27584 -2.8194 270)
			(size 0.3556 1.524)
			(layers "F.Cu" "F.Mask" "F.Paste")
			(net "PWRGD_P3V3_STBY_N_R2")
		)
		(pad "20" smd rect
			(at -2.92608 -2.8194 270)
			(size 0.3556 1.524)
			(layers "F.Cu" "F.Mask" "F.Paste")
			(net "P3V3_STBY")
		)
	)
	(footprint ""
		(layer "F.Cu")
		(at 212.836506 -90.426032 -90)
		(property "Reference" "R820"
			(at 0 0 270)
			(layer "F.SilkS")
			(hide yes)
			(effects
				(font
					(size 1.27 1.27)
				)
			)
		)
		(property "Value" "0R2J-2-GP"
			(at 0.064008 -3.993896 270)
			(unlocked yes)
			(layer "F.Fab")
			(hide yes)
			(effects
				(font
					(size 1.016 1.016)
					(thickness 0.1524)
				)
			)
		)
		(property "Device Type" "R402H16"
			(at 0.064008 -5.517896 270)
			(unlocked yes)
			(layer "F.Fab")
			(hide yes)
			(effects
				(font
					(size 1.016 1.016)
					(thickness 0.1524)
				)
			)
		)
		(duplicate_pad_numbers_are_jumpers no)
		(fp_line
			(start -0.508 -0.9398)
			(end -0.508 0.9398)
			(stroke
				(width 0.1524)
				(type default)
			)
			(layer "F.SilkS")
		)
		(fp_line
			(start 0.508 -0.9398)
			(end -0.508 -0.9398)
			(stroke
				(width 0.1524)
				(type default)
			)
			(layer "F.SilkS")
		)
		(fp_rect
			(start -0.508 0.9398)
			(end 0.508 -0.9398)
			(stroke
				(width 0)
				(type default)
			)
			(fill no)
			(layer "F.CrtYd")
		)
		(fp_rect
			(start -0.508 0.9398)
			(end 0.508 -0.9398)
			(stroke
				(width 0)
				(type default)
			)
			(fill no)
			(layer "F.Fab")
		)
		(pad "1" smd custom
			(at 0 -0.4445 270)
			(size 0.1397 0.1397)
			(layers "F.Cu" "F.Mask" "F.Paste")
			(net "P3V3_M2_EN")
			(options
				(clearance outline)
				(anchor circle)
			)
			(primitives
				(gr_poly
					(pts
						(arc
							(start -0.1778 -0.2794)
							(mid -0.249642 -0.249642)
							(end -0.2794 -0.1778)
						)
						(arc
							(start -0.2794 0.1778)
							(mid -0.249642 0.249642)
							(end -0.1778 0.2794)
						)
						(arc
							(start 0.1778 0.2794)
							(mid 0.249642 0.249642)
							(end 0.2794 0.1778)
						)
						(arc
							(start 0.2794 -0.1778)
							(mid 0.249642 -0.249642)
							(end 0.1778 -0.2794)
						)
					)
					(width 0)
					(fill yes)
				)
			)
		)
		(pad "2" smd custom
			(at 0 0.4445 270)
			(size 0.1397 0.1397)
			(layers "F.Cu" "F.Mask" "F.Paste")
			(net "P3V3_PG")
			(options
				(clearance outline)
				(anchor circle)
			)
			(primitives
				(gr_poly
					(pts
						(arc
							(start -0.1778 -0.2794)
							(mid -0.249642 -0.249642)
							(end -0.2794 -0.1778)
						)
						(arc
							(start -0.2794 0.1778)
							(mid -0.249642 0.249642)
							(end -0.1778 0.2794)
						)
						(arc
							(start 0.1778 0.2794)
							(mid 0.249642 0.249642)
							(end 0.2794 0.1778)
						)
						(arc
							(start 0.2794 -0.1778)
							(mid 0.249642 -0.249642)
							(end 0.1778 -0.2794)
						)
					)
					(width 0)
					(fill yes)
				)
			)
		)
	)
	(footprint ""
		(layer "F.Cu")
		(at 86.368636 -29.238448)
		(property "Reference" "C22"
			(at 0 0 0)
			(layer "F.SilkS")
			(hide yes)
			(effects
				(font
					(size 1.27 1.27)
				)
			)
		)
		(property "Value" "SC1U16V3KX-5GP"
			(at 0 -2.8194 0)
			(unlocked yes)
			(layer "F.Fab")
			(hide yes)
			(effects
				(font
					(size 1.016 1.016)
					(thickness 0.1524)
				)
			)
		)
		(property "Device Type" "C603H36"
			(at 0 -4.3434 0)
			(unlocked yes)
			(layer "F.Fab")
			(hide yes)
			(effects
				(font
					(size 1.016 1.016)
					(thickness 0.1524)
				)
			)
		)
		(duplicate_pad_numbers_are_jumpers no)
		(fp_line
			(start 0.508 0)
			(end -0.508 0)
			(stroke
				(width 0.2032)
				(type default)
			)
			(layer "F.SilkS")
		)
		(fp_rect
			(start -0.5842 1.3335)
			(end 0.5842 -1.3335)
			(stroke
				(width 0)
				(type default)
			)
			(fill no)
			(layer "F.CrtYd")
		)
		(fp_rect
			(start -0.5842 1.3335)
			(end 0.5842 -1.3335)
			(stroke
				(width 0)
				(type default)
			)
			(fill no)
			(layer "F.Fab")
		)
		(pad "1" smd custom
			(at 0 -0.762)
			(size 0.2159 0.2159)
			(layers "F.Cu" "F.Mask" "F.Paste")
			(net "P5V_USB")
			(options
				(clearance outline)
				(anchor circle)
			)
			(primitives
				(gr_poly
					(pts
						(arc
							(start -0.3302 -0.4318)
							(mid -0.402042 -0.402042)
							(end -0.4318 -0.3302)
						)
						(arc
							(start -0.4318 0.3302)
							(mid -0.402042 0.402042)
							(end -0.3302 0.4318)
						)
						(arc
							(start 0.3302 0.4318)
							(mid 0.402042 0.402042)
							(end 0.4318 0.3302)
						)
						(arc
							(start 0.4318 -0.3302)
							(mid 0.402042 -0.402042)
							(end 0.3302 -0.4318)
						)
					)
					(width 0)
					(fill yes)
				)
			)
		)
		(pad "2" smd custom
			(at 0 0.762)
			(size 0.2159 0.2159)
			(layers "F.Cu" "F.Mask" "F.Paste")
			(net "GND")
			(options
				(clearance outline)
				(anchor circle)
			)
			(primitives
				(gr_poly
					(pts
						(arc
							(start -0.3302 -0.4318)
							(mid -0.402042 -0.402042)
							(end -0.4318 -0.3302)
						)
						(arc
							(start -0.4318 0.3302)
							(mid -0.402042 0.402042)
							(end -0.3302 0.4318)
						)
						(arc
							(start 0.3302 0.4318)
							(mid 0.402042 0.402042)
							(end 0.4318 0.3302)
						)
						(arc
							(start 0.4318 -0.3302)
							(mid 0.402042 -0.402042)
							(end 0.3302 -0.4318)
						)
					)
					(width 0)
					(fill yes)
				)
			)
		)
	)
	(footprint ""
		(layer "F.Cu")
		(at 80.552544 -168.199816 180)
		(property "Reference" "C243"
			(at 0 0 180)
			(layer "F.SilkS")
			(hide yes)
			(effects
				(font
					(size 1.27 1.27)
				)
			)
		)
		(property "Value" "SC10U6D3V5KX-4GP"
			(at -0.0762 -6.1214 180)
			(unlocked yes)
			(layer "F.Fab")
			(hide yes)
			(effects
				(font
					(size 1.016 1.016)
					(thickness 0.1524)
				)
			)
		)
		(property "Device Type" "C805H58"
			(at -0.0762 -8.1534 180)
			(unlocked yes)
			(layer "F.Fab")
			(hide yes)
			(effects
				(font
					(size 1.016 1.016)
					(thickness 0.1524)
				)
			)
		)
		(duplicate_pad_numbers_are_jumpers no)
		(fp_line
			(start 0.635 0)
			(end -0.635 0)
			(stroke
				(width 0.508)
				(type default)
			)
			(layer "F.SilkS")
		)
		(fp_rect
			(start -0.9652 1.778)
			(end 0.9652 -1.778)
			(stroke
				(width 0)
				(type default)
			)
			(fill no)
			(layer "F.CrtYd")
		)
		(fp_poly
			(pts
				(xy -0.9652 -1.778) (xy 0.9652 -1.778) (xy 0.9652 1.778) (xy -0.9652 1.778)
			)
			(stroke
				(width 0)
				(type default)
			)
			(fill no)
			(layer "F.Fab")
		)
		(pad "1" smd rect
			(at 0 -0.9652 180)
			(size 1.397 1.143)
			(layers "F.Cu" "F.Mask" "F.Paste")
			(net "P1V8_STBY")
		)
		(pad "2" smd rect
			(at 0 0.9652 180)
			(size 1.397 1.143)
			(layers "F.Cu" "F.Mask" "F.Paste")
			(net "GND")
		)
	)
	(footprint ""
		(layer "F.Cu")
		(at 56.3626 -158.8516)
		(property "Reference" "R395"
			(at 0 0 0)
			(layer "F.SilkS")
			(hide yes)
			(effects
				(font
					(size 1.27 1.27)
				)
			)
		)
		(property "Value" "4K7R2F-GP"
			(at 0.064008 -3.993896 0)
			(unlocked yes)
			(layer "F.Fab")
			(hide yes)
			(effects
				(font
					(size 1.016 1.016)
					(thickness 0.1524)
				)
			)
		)
		(property "Device Type" "R402H16"
			(at 0.064008 -5.517896 0)
			(unlocked yes)
			(layer "F.Fab")
			(hide yes)
			(effects
				(font
					(size 1.016 1.016)
					(thickness 0.1524)
				)
			)
		)
		(duplicate_pad_numbers_are_jumpers no)
		(fp_line
			(start -0.508 -0.9398)
			(end -0.508 0.9398)
			(stroke
				(width 0.1524)
				(type default)
			)
			(layer "F.SilkS")
		)
		(fp_line
			(start 0.508 -0.9398)
			(end -0.508 -0.9398)
			(stroke
				(width 0.1524)
				(type default)
			)
			(layer "F.SilkS")
		)
		(fp_rect
			(start -0.508 0.9398)
			(end 0.508 -0.9398)
			(stroke
				(width 0)
				(type default)
			)
			(fill no)
			(layer "F.CrtYd")
		)
		(fp_rect
			(start -0.508 0.9398)
			(end 0.508 -0.9398)
			(stroke
				(width 0)
				(type default)
			)
			(fill no)
			(layer "F.Fab")
		)
		(pad "1" smd custom
			(at 0 -0.4445)
			(size 0.1397 0.1397)
			(layers "F.Cu" "F.Mask" "F.Paste")
			(net "GND")
			(options
				(clearance outline)
				(anchor circle)
			)
			(primitives
				(gr_poly
					(pts
						(arc
							(start -0.1778 -0.2794)
							(mid -0.249642 -0.249642)
							(end -0.2794 -0.1778)
						)
						(arc
							(start -0.2794 0.1778)
							(mid -0.249642 0.249642)
							(end -0.1778 0.2794)
						)
						(arc
							(start 0.1778 0.2794)
							(mid 0.249642 0.249642)
							(end 0.2794 0.1778)
						)
						(arc
							(start 0.2794 -0.1778)
							(mid 0.249642 -0.249642)
							(end 0.1778 -0.2794)
						)
					)
					(width 0)
					(fill yes)
				)
			)
		)
		(pad "2" smd custom
			(at 0 0.4445)
			(size 0.1397 0.1397)
			(layers "F.Cu" "F.Mask" "F.Paste")
			(net "MAC2_TXCTL")
			(options
				(clearance outline)
				(anchor circle)
			)
			(primitives
				(gr_poly
					(pts
						(arc
							(start -0.1778 -0.2794)
							(mid -0.249642 -0.249642)
							(end -0.2794 -0.1778)
						)
						(arc
							(start -0.2794 0.1778)
							(mid -0.249642 0.249642)
							(end -0.1778 0.2794)
						)
						(arc
							(start 0.1778 0.2794)
							(mid 0.249642 0.249642)
							(end 0.2794 0.1778)
						)
						(arc
							(start 0.2794 -0.1778)
							(mid 0.249642 -0.249642)
							(end 0.1778 -0.2794)
						)
					)
					(width 0)
					(fill yes)
				)
			)
		)
	)
	(footprint ""
		(layer "F.Cu")
		(at 82.423 -136.017 180)
		(property "Reference" "R95"
			(at 0 0 180)
			(layer "F.SilkS")
			(hide yes)
			(effects
				(font
					(size 1.27 1.27)
				)
			)
		)
		(property "Value" "0R2J-2-GP"
			(at 0.064008 -3.993896 180)
			(unlocked yes)
			(layer "F.Fab")
			(hide yes)
			(effects
				(font
					(size 1.016 1.016)
					(thickness 0.1524)
				)
			)
		)
		(property "Device Type" "R402H16"
			(at 0.064008 -5.517896 180)
			(unlocked yes)
			(layer "F.Fab")
			(hide yes)
			(effects
				(font
					(size 1.016 1.016)
					(thickness 0.1524)
				)
			)
		)
		(duplicate_pad_numbers_are_jumpers no)
		(fp_line
			(start 0.508 -0.9398)
			(end -0.508 -0.9398)
			(stroke
				(width 0.1524)
				(type default)
			)
			(layer "F.SilkS")
		)
		(fp_line
			(start -0.508 -0.9398)
			(end -0.508 0.9398)
			(stroke
				(width 0.1524)
				(type default)
			)
			(layer "F.SilkS")
		)
		(fp_rect
			(start -0.508 0.9398)
			(end 0.508 -0.9398)
			(stroke
				(width 0)
				(type default)
			)
			(fill no)
			(layer "F.CrtYd")
		)
		(fp_rect
			(start -0.508 0.9398)
			(end 0.508 -0.9398)
			(stroke
				(width 0)
				(type default)
			)
			(fill no)
			(layer "F.Fab")
		)
		(pad "1" smd custom
			(at 0 -0.4445 180)
			(size 0.1397 0.1397)
			(layers "F.Cu" "F.Mask" "F.Paste")
			(net "UART_SEL_MUX")
			(options
				(clearance outline)
				(anchor circle)
			)
			(primitives
				(gr_poly
					(pts
						(arc
							(start -0.1778 -0.2794)
							(mid -0.249642 -0.249642)
							(end -0.2794 -0.1778)
						)
						(arc
							(start -0.2794 0.1778)
							(mid -0.249642 0.249642)
							(end -0.1778 0.2794)
						)
						(arc
							(start 0.1778 0.2794)
							(mid 0.249642 0.249642)
							(end 0.2794 0.1778)
						)
						(arc
							(start 0.2794 -0.1778)
							(mid 0.249642 -0.249642)
							(end 0.1778 -0.2794)
						)
					)
					(width 0)
					(fill yes)
				)
			)
		)
		(pad "2" smd custom
			(at 0 0.4445 180)
			(size 0.1397 0.1397)
			(layers "F.Cu" "F.Mask" "F.Paste")
			(net "D_FLIP_Q#")
			(options
				(clearance outline)
				(anchor circle)
			)
			(primitives
				(gr_poly
					(pts
						(arc
							(start -0.1778 -0.2794)
							(mid -0.249642 -0.249642)
							(end -0.2794 -0.1778)
						)
						(arc
							(start -0.2794 0.1778)
							(mid -0.249642 0.249642)
							(end -0.1778 0.2794)
						)
						(arc
							(start 0.1778 0.2794)
							(mid 0.249642 0.249642)
							(end 0.2794 0.1778)
						)
						(arc
							(start 0.2794 -0.1778)
							(mid 0.249642 -0.249642)
							(end 0.1778 -0.2794)
						)
					)
					(width 0)
					(fill yes)
				)
			)
		)
	)
	(footprint ""
		(layer "F.Cu")
		(at 85.046058 -131.788662)
		(property "Reference" "R349"
			(at 0 0 0)
			(layer "F.SilkS")
			(hide yes)
			(effects
				(font
					(size 1.27 1.27)
				)
			)
		)
		(property "Value" "100KR2F-L1-GP"
			(at 0.064008 -3.993896 0)
			(unlocked yes)
			(layer "F.Fab")
			(hide yes)
			(effects
				(font
					(size 1.016 1.016)
					(thickness 0.1524)
				)
			)
		)
		(property "Device Type" "R402H16"
			(at 0.064008 -5.517896 0)
			(unlocked yes)
			(layer "F.Fab")
			(hide yes)
			(effects
				(font
					(size 1.016 1.016)
					(thickness 0.1524)
				)
			)
		)
		(duplicate_pad_numbers_are_jumpers no)
		(fp_line
			(start -0.508 -0.9398)
			(end -0.508 0.9398)
			(stroke
				(width 0.1524)
				(type default)
			)
			(layer "F.SilkS")
		)
		(fp_line
			(start 0.508 -0.9398)
			(end -0.508 -0.9398)
			(stroke
				(width 0.1524)
				(type default)
			)
			(layer "F.SilkS")
		)
		(fp_rect
			(start -0.508 0.9398)
			(end 0.508 -0.9398)
			(stroke
				(width 0)
				(type default)
			)
			(fill no)
			(layer "F.CrtYd")
		)
		(fp_rect
			(start -0.508 0.9398)
			(end 0.508 -0.9398)
			(stroke
				(width 0)
				(type default)
			)
			(fill no)
			(layer "F.Fab")
		)
		(pad "1" smd custom
			(at 0 -0.4445)
			(size 0.1397 0.1397)
			(layers "F.Cu" "F.Mask" "F.Paste")
			(net "P3V3_STBY")
			(options
				(clearance outline)
				(anchor circle)
			)
			(primitives
				(gr_poly
					(pts
						(arc
							(start -0.1778 -0.2794)
							(mid -0.249642 -0.249642)
							(end -0.2794 -0.1778)
						)
						(arc
							(start -0.2794 0.1778)
							(mid -0.249642 0.249642)
							(end -0.1778 0.2794)
						)
						(arc
							(start 0.1778 0.2794)
							(mid 0.249642 0.249642)
							(end 0.2794 0.1778)
						)
						(arc
							(start 0.2794 -0.1778)
							(mid 0.249642 -0.249642)
							(end 0.1778 -0.2794)
						)
					)
					(width 0)
					(fill yes)
				)
			)
		)
		(pad "2" smd custom
			(at 0 0.4445)
			(size 0.1397 0.1397)
			(layers "F.Cu" "F.Mask" "F.Paste")
			(net "DEBUG_UART_IOM_RX")
			(options
				(clearance outline)
				(anchor circle)
			)
			(primitives
				(gr_poly
					(pts
						(arc
							(start -0.1778 -0.2794)
							(mid -0.249642 -0.249642)
							(end -0.2794 -0.1778)
						)
						(arc
							(start -0.2794 0.1778)
							(mid -0.249642 0.249642)
							(end -0.1778 0.2794)
						)
						(arc
							(start 0.1778 0.2794)
							(mid 0.249642 0.249642)
							(end 0.2794 0.1778)
						)
						(arc
							(start 0.2794 -0.1778)
							(mid 0.249642 -0.249642)
							(end 0.1778 -0.2794)
						)
					)
					(width 0)
					(fill yes)
				)
			)
		)
	)
	(footprint ""
		(layer "F.Cu")
		(at 128.944116 -10.691622 -90)
		(property "Reference" "R710"
			(at 0 0 270)
			(layer "F.SilkS")
			(hide yes)
			(effects
				(font
					(size 1.27 1.27)
				)
			)
		)
		(property "Value" "0R5J-5-GP"
			(at 0 -8.9535 270)
			(unlocked yes)
			(layer "F.Fab")
			(hide yes)
			(effects
				(font
					(size 1.27 1.016)
					(thickness 0.1524)
				)
			)
		)
		(property "Device Type" "R805H24"
			(at 0 -10.6299 270)
			(unlocked yes)
			(layer "F.Fab")
			(hide yes)
			(effects
				(font
					(size 1.27 1.016)
					(thickness 0.1524)
				)
			)
		)
		(duplicate_pad_numbers_are_jumpers no)
		(fp_line
			(start -0.889 1.7018)
			(end 0.889 1.7018)
			(stroke
				(width 0.1524)
				(type default)
			)
			(layer "F.SilkS")
		)
		(fp_line
			(start 0.889 1.7018)
			(end 0.889 -0.508)
			(stroke
				(width 0.1524)
				(type default)
			)
			(layer "F.SilkS")
		)
		(fp_line
			(start -0.889 0.0762)
			(end -0.889 1.7018)
			(stroke
				(width 0.1524)
				(type default)
			)
			(layer "F.SilkS")
		)
		(fp_line
			(start -0.889 -1.7018)
			(end -0.889 0.2794)
			(stroke
				(width 0.1524)
				(type default)
			)
			(layer "F.SilkS")
		)
		(fp_line
			(start 0.889 -1.7018)
			(end 0.889 -0.381)
			(stroke
				(width 0.1524)
				(type default)
			)
			(layer "F.SilkS")
		)
		(fp_line
			(start 0.889 -1.7018)
			(end -0.889 -1.7018)
			(stroke
				(width 0.1524)
				(type default)
			)
			(layer "F.SilkS")
		)
		(fp_poly
			(pts
				(xy 0.9652 -1.778) (xy 0.9652 1.778) (xy -0.9652 1.778) (xy -0.9652 -1.778)
			)
			(stroke
				(width 0)
				(type default)
			)
			(fill no)
			(layer "F.CrtYd")
		)
		(fp_rect
			(start -0.9652 1.778)
			(end 0.9652 -1.778)
			(stroke
				(width 0)
				(type default)
			)
			(fill no)
			(layer "F.Fab")
		)
		(pad "1" smd rect
			(at 0 -0.9652 270)
			(size 1.397 1.143)
			(layers "F.Cu" "F.Mask" "F.Paste")
			(net "MB0_CM_GATE_R")
		)
		(pad "2" smd rect
			(at 0 0.9652 270)
			(size 1.397 1.143)
			(layers "F.Cu" "F.Mask" "F.Paste")
			(net "MB0_CM_GATE")
		)
	)
	(footprint ""
		(layer "F.Cu")
		(at 77.81798 -186.683396 180)
		(property "Reference" "C200"
			(at 0 0 180)
			(layer "F.SilkS")
			(hide yes)
			(effects
				(font
					(size 1.27 1.27)
				)
			)
		)
		(property "Value" "SC10U6D3V5KX-4GP"
			(at -0.0762 -6.1214 180)
			(unlocked yes)
			(layer "F.Fab")
			(hide yes)
			(effects
				(font
					(size 1.016 1.016)
					(thickness 0.1524)
				)
			)
		)
		(property "Device Type" "C805H58"
			(at -0.0762 -8.1534 180)
			(unlocked yes)
			(layer "F.Fab")
			(hide yes)
			(effects
				(font
					(size 1.016 1.016)
					(thickness 0.1524)
				)
			)
		)
		(duplicate_pad_numbers_are_jumpers no)
		(fp_line
			(start 0.635 0)
			(end -0.635 0)
			(stroke
				(width 0.508)
				(type default)
			)
			(layer "F.SilkS")
		)
		(fp_rect
			(start -0.9652 1.778)
			(end 0.9652 -1.778)
			(stroke
				(width 0)
				(type default)
			)
			(fill no)
			(layer "F.CrtYd")
		)
		(fp_poly
			(pts
				(xy -0.9652 -1.778) (xy 0.9652 -1.778) (xy 0.9652 1.778) (xy -0.9652 1.778)
			)
			(stroke
				(width 0)
				(type default)
			)
			(fill no)
			(layer "F.Fab")
		)
		(pad "1" smd rect
			(at 0 -0.9652 180)
			(size 1.397 1.143)
			(layers "F.Cu" "F.Mask" "F.Paste")
			(net "P3V3_STBY")
		)
		(pad "2" smd rect
			(at 0 0.9652 180)
			(size 1.397 1.143)
			(layers "F.Cu" "F.Mask" "F.Paste")
			(net "GND")
		)
	)
	(footprint ""
		(layer "F.Cu")
		(at 81.732882 -171.299378 -90)
		(property "Reference" "R651"
			(at 0 0 270)
			(layer "F.SilkS")
			(hide yes)
			(effects
				(font
					(size 1.27 1.27)
				)
			)
		)
		(property "Value" "0R2J-2-GP"
			(at 0.064008 -3.993896 270)
			(unlocked yes)
			(layer "F.Fab")
			(hide yes)
			(effects
				(font
					(size 1.016 1.016)
					(thickness 0.1524)
				)
			)
		)
		(property "Device Type" "R402H16"
			(at 0.064008 -5.517896 270)
			(unlocked yes)
			(layer "F.Fab")
			(hide yes)
			(effects
				(font
					(size 1.016 1.016)
					(thickness 0.1524)
				)
			)
		)
		(duplicate_pad_numbers_are_jumpers no)
		(fp_line
			(start -0.508 -0.9398)
			(end -0.508 0.9398)
			(stroke
				(width 0.1524)
				(type default)
			)
			(layer "F.SilkS")
		)
		(fp_line
			(start 0.508 -0.9398)
			(end -0.508 -0.9398)
			(stroke
				(width 0.1524)
				(type default)
			)
			(layer "F.SilkS")
		)
		(fp_rect
			(start -0.508 0.9398)
			(end 0.508 -0.9398)
			(stroke
				(width 0)
				(type default)
			)
			(fill no)
			(layer "F.CrtYd")
		)
		(fp_rect
			(start -0.508 0.9398)
			(end 0.508 -0.9398)
			(stroke
				(width 0)
				(type default)
			)
			(fill no)
			(layer "F.Fab")
		)
		(pad "1" smd custom
			(at 0 -0.4445 270)
			(size 0.1397 0.1397)
			(layers "F.Cu" "F.Mask" "F.Paste")
			(net "EXP_UART_EN_R")
			(options
				(clearance outline)
				(anchor circle)
			)
			(primitives
				(gr_poly
					(pts
						(arc
							(start -0.1778 -0.2794)
							(mid -0.249642 -0.249642)
							(end -0.2794 -0.1778)
						)
						(arc
							(start -0.2794 0.1778)
							(mid -0.249642 0.249642)
							(end -0.1778 0.2794)
						)
						(arc
							(start 0.1778 0.2794)
							(mid 0.249642 0.249642)
							(end 0.2794 0.1778)
						)
						(arc
							(start 0.2794 -0.1778)
							(mid 0.249642 -0.249642)
							(end 0.1778 -0.2794)
						)
					)
					(width 0)
					(fill yes)
				)
			)
		)
		(pad "2" smd custom
			(at 0 0.4445 270)
			(size 0.1397 0.1397)
			(layers "F.Cu" "F.Mask" "F.Paste")
			(net "EXP_UART_EN")
			(options
				(clearance outline)
				(anchor circle)
			)
			(primitives
				(gr_poly
					(pts
						(arc
							(start -0.1778 -0.2794)
							(mid -0.249642 -0.249642)
							(end -0.2794 -0.1778)
						)
						(arc
							(start -0.2794 0.1778)
							(mid -0.249642 0.249642)
							(end -0.1778 0.2794)
						)
						(arc
							(start 0.1778 0.2794)
							(mid 0.249642 0.249642)
							(end 0.2794 0.1778)
						)
						(arc
							(start 0.2794 -0.1778)
							(mid 0.249642 -0.249642)
							(end 0.1778 -0.2794)
						)
					)
					(width 0)
					(fill yes)
				)
			)
		)
	)
	(footprint ""
		(layer "F.Cu")
		(at 11.999976 -6.249924)
		(property "Reference" "RST1"
			(at 0 0 0)
			(layer "F.SilkS")
			(hide yes)
			(effects
				(font
					(size 1.27 1.27)
				)
			)
		)
		(property "Value" "SW-TACT-4P-210-GP"
			(at -5.9436 2.1209 0)
			(unlocked yes)
			(layer "F.Fab")
			(hide yes)
			(effects
				(font
					(size 1.016 1.016)
					(thickness 0.1524)
				)
			)
		)
		(property "Device Type" "DIPTRONICS"
			(at -5.9436 0.5969 0)
			(unlocked yes)
			(layer "F.Fab")
			(hide yes)
			(effects
				(font
					(size 1.016 1.016)
					(thickness 0.1524)
				)
			)
		)
		(duplicate_pad_numbers_are_jumpers no)
		(fp_line
			(start -4.4704 -4.2418)
			(end 4.4704 -4.2418)
			(stroke
				(width 0.1524)
				(type default)
			)
			(layer "F.SilkS")
		)
		(fp_line
			(start -4.4704 -1.5494)
			(end -4.4704 -4.2418)
			(stroke
				(width 0.1524)
				(type default)
			)
			(layer "F.SilkS")
		)
		(fp_line
			(start -3.9497 -1.5494)
			(end -4.4704 -1.5494)
			(stroke
				(width 0.1524)
				(type default)
			)
			(layer "F.SilkS")
		)
		(fp_line
			(start -3.9497 3.2258)
			(end -3.9497 -1.5494)
			(stroke
				(width 0.1524)
				(type default)
			)
			(layer "F.SilkS")
		)
		(fp_line
			(start -2.0066 3.2258)
			(end -3.9497 3.2258)
			(stroke
				(width 0.1524)
				(type default)
			)
			(layer "F.SilkS")
		)
		(fp_line
			(start -2.0066 6.1214)
			(end -2.0066 3.2258)
			(stroke
				(width 0.1524)
				(type default)
			)
			(layer "F.SilkS")
		)
		(fp_line
			(start 2.0066 3.2258)
			(end 2.0066 6.1214)
			(stroke
				(width 0.1524)
				(type default)
			)
			(layer "F.SilkS")
		)
		(fp_line
			(start 2.0066 6.1214)
			(end -2.0066 6.1214)
			(stroke
				(width 0.1524)
				(type default)
			)
			(layer "F.SilkS")
		)
		(fp_line
			(start 3.9497 -1.5494)
			(end 3.9497 3.2258)
			(stroke
				(width 0.1524)
				(type default)
			)
			(layer "F.SilkS")
		)
		(fp_line
			(start 3.9497 3.2258)
			(end 2.0066 3.2258)
			(stroke
				(width 0.1524)
				(type default)
			)
			(layer "F.SilkS")
		)
		(fp_line
			(start 4.4704 -4.2418)
			(end 4.4704 -1.5494)
			(stroke
				(width 0.1524)
				(type default)
			)
			(layer "F.SilkS")
		)
		(fp_line
			(start 4.4704 -1.5494)
			(end 3.9497 -1.5494)
			(stroke
				(width 0.1524)
				(type default)
			)
			(layer "F.SilkS")
		)
		(fp_circle
			(center -3.50012 -2.500122)
			(end -2.43332 -2.500122)
			(stroke
				(width 0.3048)
				(type default)
			)
			(fill no)
			(layer "F.SilkS")
		)
		(fp_circle
			(center -2.249932 0)
			(end -1.183132 0)
			(stroke
				(width 0.3048)
				(type default)
			)
			(fill no)
			(layer "F.SilkS")
		)
		(fp_circle
			(center 2.249932 0)
			(end 3.316732 0)
			(stroke
				(width 0.3048)
				(type default)
			)
			(fill no)
			(layer "F.SilkS")
		)
		(fp_circle
			(center 3.50012 -2.500122)
			(end 4.56692 -2.500122)
			(stroke
				(width 0.3048)
				(type default)
			)
			(fill no)
			(layer "F.SilkS")
		)
		(fp_poly
			(pts
				(xy -1.7526 5.8674) (xy -1.7526 2.9718) (xy -3.6957 2.9718) (xy -3.6957 -3.9878) (xy 3.6957 -3.9878)
				(xy 3.6957 2.9718) (xy 1.7526 2.9718) (xy 1.7526 5.8674)
			)
			(stroke
				(width 0)
				(type default)
			)
			(fill no)
			(layer "F.CrtYd")
		)
		(fp_poly
			(pts
				(xy -2.2606 6.3754) (xy -2.2606 3.4798) (xy -4.2037 3.4798) (xy -4.2037 -1.2954) (xy -4.7244 -1.2954)
				(xy -4.7244 -4.4958) (xy 4.7244 -4.4958) (xy 4.7244 -1.2954) (xy 4.2037 -1.2954) (xy 4.2037 -0.00635)
				(xy 3.6957 -0.00635) (xy 3.6957 -3.9878) (xy -3.6957 -3.9878) (xy -3.6957 2.9718) (xy -1.7526 2.9718)
				(xy -1.7526 5.8674) (xy 1.7526 5.8674) (xy 1.7526 2.9718) (xy 3.6957 2.9718) (xy 3.6957 0.00635)
				(xy 4.2037 0.00635) (xy 4.2037 3.4798) (xy 2.2606 3.4798) (xy 2.2606 6.3754)
			)
			(stroke
				(width 0)
				(type default)
			)
			(fill no)
			(layer "F.CrtYd")
		)
		(fp_poly
			(pts
				(xy -2.2606 6.3754) (xy -2.2606 3.4798) (xy -4.2037 3.4798) (xy -4.2037 -1.2954) (xy -4.7244 -1.2954)
				(xy -4.7244 -4.4958) (xy 4.7244 -4.4958) (xy 4.7244 -1.2954) (xy 4.2037 -1.2954) (xy 4.2037 3.4798)
				(xy 2.2606 3.4798) (xy 2.2606 6.3754)
			)
			(stroke
				(width 0)
				(type default)
			)
			(fill no)
			(layer "F.Fab")
		)
		(pad "1" thru_hole circle
			(at -2.249932 0)
			(size 1.4224 1.4224)
			(drill 1.016)
			(layers "*.Cu" "*.Mask")
			(remove_unused_layers no)
			(net "SYS_RST_BTN_IN_N")
			(clearance 0.1524)
			(thermal_gap 0.1524)
		)
		(pad "2" thru_hole circle
			(at 2.249932 0)
			(size 1.4224 1.4224)
			(drill 1.016)
			(layers "*.Cu" "*.Mask")
			(remove_unused_layers no)
			(net "GND")
			(clearance 0.1524)
			(thermal_gap 0.1524)
		)
		(pad "3" thru_hole circle
			(at -3.50012 -2.500122)
			(size 1.4224 1.4224)
			(drill 1.016)
			(layers "*.Cu" "*.Mask")
			(remove_unused_layers no)
			(net "RST_BTN_GND")
			(clearance 0.1524)
			(thermal_gap 0.1524)
		)
		(pad "4" thru_hole circle
			(at 3.50012 -2.500122)
			(size 1.4224 1.4224)
			(drill 1.016)
			(layers "*.Cu" "*.Mask")
			(remove_unused_layers no)
			(net "RST_BTN_GND")
			(clearance 0.1524)
			(thermal_gap 0.1524)
		)
		(zone
			(layer "F.Cu")
			(hatch none 0.5)
			(connect_pads
				(clearance 0)
			)
			(min_thickness 0.25)
			(keepout
				(tracks not_allowed)
				(vias allowed)
				(pads allowed)
				(copperpour not_allowed)
				(footprints allowed)
			)
			(placement
				(enabled no)
				(sheetname "")
			)
			(fill
				(thermal_gap 0.5)
				(thermal_bridge_width 0.5)
				(island_removal_mode 0)
			)
			(polygon
				(pts
					(xy 8.177276 -9.461246) (xy 8.837676 -9.461246) (xy 8.837676 -10.364724) (xy 8.177276 -10.364724)
				)
			)
		)
		(zone
			(layer "F.Cu")
			(hatch none 0.5)
			(connect_pads
				(clearance 0)
			)
			(min_thickness 0.25)
			(keepout
				(tracks allowed)
				(vias not_allowed)
				(pads allowed)
				(copperpour not_allowed)
				(footprints allowed)
			)
			(placement
				(enabled no)
				(sheetname "")
			)
			(fill
				(thermal_gap 0.5)
				(thermal_bridge_width 0.5)
				(island_removal_mode 0)
			)
			(polygon
				(pts
					(xy 8.177276 -9.461246) (xy 8.837676 -9.461246) (xy 8.837676 -10.364724) (xy 8.177276 -10.364724)
				)
			)
		)
		(zone
			(layer "F.Cu")
			(hatch none 0.5)
			(connect_pads
				(clearance 0)
			)
			(min_thickness 0.25)
			(keepout
				(tracks allowed)
				(vias not_allowed)
				(pads allowed)
				(copperpour not_allowed)
				(footprints allowed)
			)
			(placement
				(enabled no)
				(sheetname "")
			)
			(fill
				(thermal_gap 0.5)
				(thermal_bridge_width 0.5)
				(island_removal_mode 0)
			)
			(polygon
				(pts
					(xy 8.177276 -3.532124) (xy 8.837676 -3.532124) (xy 8.837676 -8.038846) (xy 8.177276 -8.038846)
				)
			)
		)
		(zone
			(layer "F.Cu")
			(hatch none 0.5)
			(connect_pads
				(clearance 0)
			)
			(min_thickness 0.25)
			(keepout
				(tracks not_allowed)
				(vias allowed)
				(pads allowed)
				(copperpour not_allowed)
				(footprints allowed)
			)
			(placement
				(enabled no)
				(sheetname "")
			)
			(fill
				(thermal_gap 0.5)
				(thermal_bridge_width 0.5)
				(island_removal_mode 0)
			)
			(polygon
				(pts
					(xy 8.177276 -3.532124) (xy 8.837676 -3.532124) (xy 8.837676 -8.038846) (xy 8.177276 -8.038846)
				)
			)
		)
		(zone
			(layer "F.Cu")
			(hatch none 0.5)
			(connect_pads
				(clearance 0)
			)
			(min_thickness 0.25)
			(keepout
				(tracks not_allowed)
				(vias allowed)
				(pads allowed)
				(copperpour not_allowed)
				(footprints allowed)
			)
			(placement
				(enabled no)
				(sheetname "")
			)
			(fill
				(thermal_gap 0.5)
				(thermal_bridge_width 0.5)
				(island_removal_mode 0)
			)
			(polygon
				(pts
					(xy 11.072876 -3.532124) (xy 12.927076 -3.532124) (xy 12.927076 -4.294124) (xy 11.072876 -4.294124)
				)
			)
		)
		(zone
			(layer "F.Cu")
			(hatch none 0.5)
			(connect_pads
				(clearance 0)
			)
			(min_thickness 0.25)
			(keepout
				(tracks allowed)
				(vias not_allowed)
				(pads allowed)
				(copperpour not_allowed)
				(footprints allowed)
			)
			(placement
				(enabled no)
				(sheetname "")
			)
			(fill
				(thermal_gap 0.5)
				(thermal_bridge_width 0.5)
				(island_removal_mode 0)
			)
			(polygon
				(pts
					(xy 11.072876 -3.532124) (xy 12.927076 -3.532124) (xy 12.927076 -4.294124) (xy 11.072876 -4.294124)
				)
			)
		)
		(zone
			(layer "F.Cu")
			(hatch none 0.5)
			(connect_pads
				(clearance 0)
			)
			(min_thickness 0.25)
			(keepout
				(tracks not_allowed)
				(vias allowed)
				(pads allowed)
				(copperpour not_allowed)
				(footprints allowed)
			)
			(placement
				(enabled no)
				(sheetname "")
			)
			(fill
				(thermal_gap 0.5)
				(thermal_bridge_width 0.5)
				(island_removal_mode 0)
			)
			(polygon
				(pts
					(xy 15.162276 -9.461246) (xy 15.822676 -9.461246) (xy 15.822676 -10.364724) (xy 15.162276 -10.364724)
				)
			)
		)
		(zone
			(layer "F.Cu")
			(hatch none 0.5)
			(connect_pads
				(clearance 0)
			)
			(min_thickness 0.25)
			(keepout
				(tracks allowed)
				(vias not_allowed)
				(pads allowed)
				(copperpour not_allowed)
				(footprints allowed)
			)
			(placement
				(enabled no)
				(sheetname "")
			)
			(fill
				(thermal_gap 0.5)
				(thermal_bridge_width 0.5)
				(island_removal_mode 0)
			)
			(polygon
				(pts
					(xy 15.162276 -9.461246) (xy 15.822676 -9.461246) (xy 15.822676 -10.364724) (xy 15.162276 -10.364724)
				)
			)
		)
		(zone
			(layer "F.Cu")
			(hatch none 0.5)
			(connect_pads
				(clearance 0)
			)
			(min_thickness 0.25)
			(keepout
				(tracks not_allowed)
				(vias allowed)
				(pads allowed)
				(copperpour not_allowed)
				(footprints allowed)
			)
			(placement
				(enabled no)
				(sheetname "")
			)
			(fill
				(thermal_gap 0.5)
				(thermal_bridge_width 0.5)
				(island_removal_mode 0)
			)
			(polygon
				(pts
					(xy 15.162276 -3.532124) (xy 15.822676 -3.532124) (xy 15.822676 -8.038846) (xy 15.162276 -8.038846)
				)
			)
		)
		(zone
			(layer "F.Cu")
			(hatch none 0.5)
			(connect_pads
				(clearance 0)
			)
			(min_thickness 0.25)
			(keepout
				(tracks allowed)
				(vias not_allowed)
				(pads allowed)
				(copperpour not_allowed)
				(footprints allowed)
			)
			(placement
				(enabled no)
				(sheetname "")
			)
			(fill
				(thermal_gap 0.5)
				(thermal_bridge_width 0.5)
				(island_removal_mode 0)
			)
			(polygon
				(pts
					(xy 15.162276 -3.532124) (xy 15.822676 -3.532124) (xy 15.822676 -8.038846) (xy 15.162276 -8.038846)
				)
			)
		)
	)
	(footprint ""
		(layer "F.Cu")
		(at 112.87379 -7.736078 -90)
		(property "Reference" "R459"
			(at 0 0 270)
			(layer "F.SilkS")
			(hide yes)
			(effects
				(font
					(size 1.27 1.27)
				)
			)
		)
		(property "Value" "0R2J-2-GP"
			(at 0.064008 -3.993896 270)
			(unlocked yes)
			(layer "F.Fab")
			(hide yes)
			(effects
				(font
					(size 1.016 1.016)
					(thickness 0.1524)
				)
			)
		)
		(property "Device Type" "R402H16"
			(at 0.064008 -5.517896 270)
			(unlocked yes)
			(layer "F.Fab")
			(hide yes)
			(effects
				(font
					(size 1.016 1.016)
					(thickness 0.1524)
				)
			)
		)
		(duplicate_pad_numbers_are_jumpers no)
		(fp_line
			(start -0.508 -0.9398)
			(end -0.508 0.9398)
			(stroke
				(width 0.1524)
				(type default)
			)
			(layer "F.SilkS")
		)
		(fp_line
			(start 0.508 -0.9398)
			(end -0.508 -0.9398)
			(stroke
				(width 0.1524)
				(type default)
			)
			(layer "F.SilkS")
		)
		(fp_rect
			(start -0.508 0.9398)
			(end 0.508 -0.9398)
			(stroke
				(width 0)
				(type default)
			)
			(fill no)
			(layer "F.CrtYd")
		)
		(fp_rect
			(start -0.508 0.9398)
			(end 0.508 -0.9398)
			(stroke
				(width 0)
				(type default)
			)
			(fill no)
			(layer "F.Fab")
		)
		(pad "1" smd custom
			(at 0 -0.4445 270)
			(size 0.1397 0.1397)
			(layers "F.Cu" "F.Mask" "F.Paste")
			(net "MB0_CM_ADR1_R")
			(options
				(clearance outline)
				(anchor circle)
			)
			(primitives
				(gr_poly
					(pts
						(arc
							(start -0.1778 -0.2794)
							(mid -0.249642 -0.249642)
							(end -0.2794 -0.1778)
						)
						(arc
							(start -0.2794 0.1778)
							(mid -0.249642 0.249642)
							(end -0.1778 0.2794)
						)
						(arc
							(start 0.1778 0.2794)
							(mid 0.249642 0.249642)
							(end 0.2794 0.1778)
						)
						(arc
							(start 0.2794 -0.1778)
							(mid 0.249642 -0.249642)
							(end 0.1778 -0.2794)
						)
					)
					(width 0)
					(fill yes)
				)
			)
		)
		(pad "2" smd custom
			(at 0 0.4445 270)
			(size 0.1397 0.1397)
			(layers "F.Cu" "F.Mask" "F.Paste")
			(net "AGND_CURRENT_MON")
			(options
				(clearance outline)
				(anchor circle)
			)
			(primitives
				(gr_poly
					(pts
						(arc
							(start -0.1778 -0.2794)
							(mid -0.249642 -0.249642)
							(end -0.2794 -0.1778)
						)
						(arc
							(start -0.2794 0.1778)
							(mid -0.249642 0.249642)
							(end -0.1778 0.2794)
						)
						(arc
							(start 0.1778 0.2794)
							(mid 0.249642 0.249642)
							(end 0.2794 0.1778)
						)
						(arc
							(start 0.2794 -0.1778)
							(mid 0.249642 -0.249642)
							(end 0.1778 -0.2794)
						)
					)
					(width 0)
					(fill yes)
				)
			)
		)
	)
	(footprint ""
		(layer "F.Cu")
		(at 29.456634 -151.499316 -90)
		(property "Reference" "R768"
			(at 0 0 270)
			(layer "F.SilkS")
			(hide yes)
			(effects
				(font
					(size 1.27 1.27)
				)
			)
		)
		(property "Value" "0R2J-2-GP"
			(at 0.064008 -3.993896 270)
			(unlocked yes)
			(layer "F.Fab")
			(hide yes)
			(effects
				(font
					(size 1.016 1.016)
					(thickness 0.1524)
				)
			)
		)
		(property "Device Type" "R402H16"
			(at 0.064008 -5.517896 270)
			(unlocked yes)
			(layer "F.Fab")
			(hide yes)
			(effects
				(font
					(size 1.016 1.016)
					(thickness 0.1524)
				)
			)
		)
		(duplicate_pad_numbers_are_jumpers no)
		(fp_line
			(start -0.508 -0.9398)
			(end -0.508 0.9398)
			(stroke
				(width 0.1524)
				(type default)
			)
			(layer "F.SilkS")
		)
		(fp_line
			(start 0.508 -0.9398)
			(end -0.508 -0.9398)
			(stroke
				(width 0.1524)
				(type default)
			)
			(layer "F.SilkS")
		)
		(fp_rect
			(start -0.508 0.9398)
			(end 0.508 -0.9398)
			(stroke
				(width 0)
				(type default)
			)
			(fill no)
			(layer "F.CrtYd")
		)
		(fp_rect
			(start -0.508 0.9398)
			(end 0.508 -0.9398)
			(stroke
				(width 0)
				(type default)
			)
			(fill no)
			(layer "F.Fab")
		)
		(pad "1" smd custom
			(at 0 -0.4445 270)
			(size 0.1397 0.1397)
			(layers "F.Cu" "F.Mask" "F.Paste")
			(net "DEBUG_GPIO_BMC_R_1")
			(options
				(clearance outline)
				(anchor circle)
			)
			(primitives
				(gr_poly
					(pts
						(arc
							(start -0.1778 -0.2794)
							(mid -0.249642 -0.249642)
							(end -0.2794 -0.1778)
						)
						(arc
							(start -0.2794 0.1778)
							(mid -0.249642 0.249642)
							(end -0.1778 0.2794)
						)
						(arc
							(start 0.1778 0.2794)
							(mid 0.249642 0.249642)
							(end 0.2794 0.1778)
						)
						(arc
							(start 0.2794 -0.1778)
							(mid 0.249642 -0.249642)
							(end 0.1778 -0.2794)
						)
					)
					(width 0)
					(fill yes)
				)
			)
		)
		(pad "2" smd custom
			(at 0 0.4445 270)
			(size 0.1397 0.1397)
			(layers "F.Cu" "F.Mask" "F.Paste")
			(net "DEBUG_GPIO_BMC_1")
			(options
				(clearance outline)
				(anchor circle)
			)
			(primitives
				(gr_poly
					(pts
						(arc
							(start -0.1778 -0.2794)
							(mid -0.249642 -0.249642)
							(end -0.2794 -0.1778)
						)
						(arc
							(start -0.2794 0.1778)
							(mid -0.249642 0.249642)
							(end -0.1778 0.2794)
						)
						(arc
							(start 0.1778 0.2794)
							(mid 0.249642 0.249642)
							(end 0.2794 0.1778)
						)
						(arc
							(start 0.2794 -0.1778)
							(mid 0.249642 -0.249642)
							(end 0.1778 -0.2794)
						)
					)
					(width 0)
					(fill yes)
				)
			)
		)
	)
	(footprint ""
		(layer "F.Cu")
		(at 30.3276 -162.7378 180)
		(property "Reference" "C105"
			(at 0 0 180)
			(layer "F.SilkS")
			(hide yes)
			(effects
				(font
					(size 1.27 1.27)
				)
			)
		)
		(property "Value" "SC100P50V2JN-3GP"
			(at 1.1811 -2.7051 180)
			(unlocked yes)
			(layer "F.Fab")
			(hide yes)
			(effects
				(font
					(size 1.016 1.016)
					(thickness 0.1524)
				)
			)
		)
		(property "Device Type" "C402H22"
			(at 1.1811 -4.2291 180)
			(unlocked yes)
			(layer "F.Fab")
			(hide yes)
			(effects
				(font
					(size 1.016 1.016)
					(thickness 0.1524)
				)
			)
		)
		(duplicate_pad_numbers_are_jumpers no)
		(fp_rect
			(start -0.4318 0.9525)
			(end 0.4318 -0.9525)
			(stroke
				(width 0)
				(type default)
			)
			(fill no)
			(layer "F.CrtYd")
		)
		(fp_rect
			(start -0.4318 0.9525)
			(end 0.4318 -0.9525)
			(stroke
				(width 0)
				(type default)
			)
			(fill no)
			(layer "F.Fab")
		)
		(pad "1" smd custom
			(at 0 -0.4445 180)
			(size 0.1524 0.1524)
			(layers "F.Cu" "F.Mask" "F.Paste")
			(net "V1PLLAV11")
			(options
				(clearance outline)
				(anchor circle)
			)
			(primitives
				(gr_poly
					(pts
						(arc
							(start 0.3048 -0.2032)
							(mid 0.275042 -0.275042)
							(end 0.2032 -0.3048)
						)
						(arc
							(start -0.2032 -0.3048)
							(mid -0.275042 -0.275042)
							(end -0.3048 -0.2032)
						)
						(arc
							(start -0.3048 0.2032)
							(mid -0.275042 0.275042)
							(end -0.2032 0.3048)
						)
						(arc
							(start 0.2032 0.3048)
							(mid 0.275042 0.275042)
							(end 0.3048 0.2032)
						)
					)
					(width 0)
					(fill yes)
				)
			)
		)
		(pad "2" smd custom
			(at 0 0.4445 180)
			(size 0.1524 0.1524)
			(layers "F.Cu" "F.Mask" "F.Paste")
			(net "GND")
			(options
				(clearance outline)
				(anchor circle)
			)
			(primitives
				(gr_poly
					(pts
						(arc
							(start 0.3048 -0.2032)
							(mid 0.275042 -0.275042)
							(end 0.2032 -0.3048)
						)
						(arc
							(start -0.2032 -0.3048)
							(mid -0.275042 -0.275042)
							(end -0.3048 -0.2032)
						)
						(arc
							(start -0.3048 0.2032)
							(mid -0.275042 0.275042)
							(end -0.2032 0.3048)
						)
						(arc
							(start 0.2032 0.3048)
							(mid 0.275042 0.275042)
							(end 0.3048 0.2032)
						)
					)
					(width 0)
					(fill yes)
				)
			)
		)
	)
	(footprint ""
		(layer "F.Cu")
		(at 207.8736 -109.22 -90)
		(property "Reference" "R554"
			(at 0 0 270)
			(layer "F.SilkS")
			(hide yes)
			(effects
				(font
					(size 1.27 1.27)
				)
			)
		)
		(property "Value" "4K7R2F-GP"
			(at 0.064008 -3.993896 270)
			(unlocked yes)
			(layer "F.Fab")
			(hide yes)
			(effects
				(font
					(size 1.016 1.016)
					(thickness 0.1524)
				)
			)
		)
		(property "Device Type" "R402H16"
			(at 0.064008 -5.517896 270)
			(unlocked yes)
			(layer "F.Fab")
			(hide yes)
			(effects
				(font
					(size 1.016 1.016)
					(thickness 0.1524)
				)
			)
		)
		(duplicate_pad_numbers_are_jumpers no)
		(fp_line
			(start -0.508 -0.9398)
			(end -0.508 0.9398)
			(stroke
				(width 0.1524)
				(type default)
			)
			(layer "F.SilkS")
		)
		(fp_line
			(start 0.508 -0.9398)
			(end -0.508 -0.9398)
			(stroke
				(width 0.1524)
				(type default)
			)
			(layer "F.SilkS")
		)
		(fp_rect
			(start -0.508 0.9398)
			(end 0.508 -0.9398)
			(stroke
				(width 0)
				(type default)
			)
			(fill no)
			(layer "F.CrtYd")
		)
		(fp_rect
			(start -0.508 0.9398)
			(end 0.508 -0.9398)
			(stroke
				(width 0)
				(type default)
			)
			(fill no)
			(layer "F.Fab")
		)
		(pad "1" smd custom
			(at 0 -0.4445 270)
			(size 0.1397 0.1397)
			(layers "F.Cu" "F.Mask" "F.Paste")
			(net "P3V3_STBY")
			(options
				(clearance outline)
				(anchor circle)
			)
			(primitives
				(gr_poly
					(pts
						(arc
							(start -0.1778 -0.2794)
							(mid -0.249642 -0.249642)
							(end -0.2794 -0.1778)
						)
						(arc
							(start -0.2794 0.1778)
							(mid -0.249642 0.249642)
							(end -0.1778 0.2794)
						)
						(arc
							(start 0.1778 0.2794)
							(mid 0.249642 0.249642)
							(end 0.2794 0.1778)
						)
						(arc
							(start 0.2794 -0.1778)
							(mid 0.249642 -0.249642)
							(end 0.1778 -0.2794)
						)
					)
					(width 0)
					(fill yes)
				)
			)
		)
		(pad "2" smd custom
			(at 0 0.4445 270)
			(size 0.1397 0.1397)
			(layers "F.Cu" "F.Mask" "F.Paste")
			(net "TEMP_2_A2")
			(options
				(clearance outline)
				(anchor circle)
			)
			(primitives
				(gr_poly
					(pts
						(arc
							(start -0.1778 -0.2794)
							(mid -0.249642 -0.249642)
							(end -0.2794 -0.1778)
						)
						(arc
							(start -0.2794 0.1778)
							(mid -0.249642 0.249642)
							(end -0.1778 0.2794)
						)
						(arc
							(start 0.1778 0.2794)
							(mid 0.249642 0.249642)
							(end 0.2794 0.1778)
						)
						(arc
							(start 0.2794 -0.1778)
							(mid 0.249642 -0.249642)
							(end 0.1778 -0.2794)
						)
					)
					(width 0)
					(fill yes)
				)
			)
		)
	)
	(footprint ""
		(layer "F.Cu")
		(at 62.865 -178.816)
		(property "Reference" "R356"
			(at 0 0 0)
			(layer "F.SilkS")
			(hide yes)
			(effects
				(font
					(size 1.27 1.27)
				)
			)
		)
		(property "Value" "0R2J-2-GP"
			(at 0.064008 -3.993896 0)
			(unlocked yes)
			(layer "F.Fab")
			(hide yes)
			(effects
				(font
					(size 1.016 1.016)
					(thickness 0.1524)
				)
			)
		)
		(property "Device Type" "R402H16"
			(at 0.064008 -5.517896 0)
			(unlocked yes)
			(layer "F.Fab")
			(hide yes)
			(effects
				(font
					(size 1.016 1.016)
					(thickness 0.1524)
				)
			)
		)
		(duplicate_pad_numbers_are_jumpers no)
		(fp_line
			(start -0.508 -0.9398)
			(end -0.508 0.9398)
			(stroke
				(width 0.1524)
				(type default)
			)
			(layer "F.SilkS")
		)
		(fp_line
			(start 0.508 -0.9398)
			(end -0.508 -0.9398)
			(stroke
				(width 0.1524)
				(type default)
			)
			(layer "F.SilkS")
		)
		(fp_rect
			(start -0.508 0.9398)
			(end 0.508 -0.9398)
			(stroke
				(width 0)
				(type default)
			)
			(fill no)
			(layer "F.CrtYd")
		)
		(fp_rect
			(start -0.508 0.9398)
			(end 0.508 -0.9398)
			(stroke
				(width 0)
				(type default)
			)
			(fill no)
			(layer "F.Fab")
		)
		(pad "1" smd custom
			(at 0 -0.4445)
			(size 0.1397 0.1397)
			(layers "F.Cu" "F.Mask" "F.Paste")
			(net "IOM_STBY_PGOOD")
			(options
				(clearance outline)
				(anchor circle)
			)
			(primitives
				(gr_poly
					(pts
						(arc
							(start -0.1778 -0.2794)
							(mid -0.249642 -0.249642)
							(end -0.2794 -0.1778)
						)
						(arc
							(start -0.2794 0.1778)
							(mid -0.249642 0.249642)
							(end -0.1778 0.2794)
						)
						(arc
							(start 0.1778 0.2794)
							(mid 0.249642 0.249642)
							(end 0.2794 0.1778)
						)
						(arc
							(start 0.2794 -0.1778)
							(mid 0.249642 -0.249642)
							(end 0.1778 -0.2794)
						)
					)
					(width 0)
					(fill yes)
				)
			)
		)
		(pad "2" smd custom
			(at 0 0.4445)
			(size 0.1397 0.1397)
			(layers "F.Cu" "F.Mask" "F.Paste")
			(net "FM_BMC_RESET_N")
			(options
				(clearance outline)
				(anchor circle)
			)
			(primitives
				(gr_poly
					(pts
						(arc
							(start -0.1778 -0.2794)
							(mid -0.249642 -0.249642)
							(end -0.2794 -0.1778)
						)
						(arc
							(start -0.2794 0.1778)
							(mid -0.249642 0.249642)
							(end -0.1778 0.2794)
						)
						(arc
							(start 0.1778 0.2794)
							(mid 0.249642 0.249642)
							(end 0.2794 0.1778)
						)
						(arc
							(start 0.2794 -0.1778)
							(mid 0.249642 -0.249642)
							(end 0.1778 -0.2794)
						)
					)
					(width 0)
					(fill yes)
				)
			)
		)
	)
	(footprint ""
		(layer "F.Cu")
		(at 75.091036 -180.35778 -90)
		(property "Reference" "PU9"
			(at 0 0 270)
			(layer "F.SilkS")
			(hide yes)
			(effects
				(font
					(size 1.27 1.27)
				)
			)
		)
		(property "Value" "TPS74801RGW-GP"
			(at -4.7244 -6.223 270)
			(unlocked yes)
			(layer "F.Fab")
			(hide yes)
			(effects
				(font
					(size 1.016 1.016)
					(thickness 0.1524)
				)
			)
		)
		(property "Device Type" "QFN20-1G3D15H40"
			(at -4.7244 -7.747 270)
			(unlocked yes)
			(layer "F.Fab")
			(hide yes)
			(effects
				(font
					(size 1.016 1.016)
					(thickness 0.1524)
				)
			)
		)
		(duplicate_pad_numbers_are_jumpers no)
		(fp_line
			(start -3.5179 3.5179)
			(end -2.2479 3.5179)
			(stroke
				(width 0.1524)
				(type default)
			)
			(layer "F.SilkS")
		)
		(fp_line
			(start 2.2479 3.5179)
			(end 3.5179 3.5179)
			(stroke
				(width 0.1524)
				(type default)
			)
			(layer "F.SilkS")
		)
		(fp_line
			(start 3.5179 3.5179)
			(end 3.5179 2.2479)
			(stroke
				(width 0.1524)
				(type default)
			)
			(layer "F.SilkS")
		)
		(fp_line
			(start 1.299972 3.160522)
			(end 1.299972 3.668522)
			(stroke
				(width 0.1524)
				(type default)
			)
			(layer "F.SilkS")
		)
		(fp_line
			(start -3.5179 2.2479)
			(end -3.5179 3.5179)
			(stroke
				(width 0.1524)
				(type default)
			)
			(layer "F.SilkS")
		)
		(fp_line
			(start -3.160522 1.299972)
			(end -3.922522 1.299972)
			(stroke
				(width 0.1524)
				(type default)
			)
			(layer "F.SilkS")
		)
		(fp_line
			(start 3.160522 -1.299972)
			(end 3.922522 -1.299972)
			(stroke
				(width 0.1524)
				(type default)
			)
			(layer "F.SilkS")
		)
		(fp_line
			(start -1.299972 -3.160522)
			(end -1.299972 -3.668522)
			(stroke
				(width 0.1524)
				(type default)
			)
			(layer "F.SilkS")
		)
		(fp_line
			(start -3.5179 -3.5179)
			(end -3.5179 -2.2479)
			(stroke
				(width 0.1524)
				(type default)
			)
			(layer "F.SilkS")
		)
		(fp_line
			(start -2.2479 -3.5179)
			(end -3.5179 -3.5179)
			(stroke
				(width 0.1524)
				(type default)
			)
			(layer "F.SilkS")
		)
		(fp_poly
			(pts
				(xy 3.5179 -3.5179) (xy 2.2479 -3.5179) (xy 3.5179 -2.2479)
			)
			(stroke
				(width 0)
				(type default)
			)
			(fill yes)
			(layer "F.SilkS")
		)
		(fp_rect
			(start -2.5019 2.5019)
			(end 2.5019 -2.5019)
			(stroke
				(width 0)
				(type default)
			)
			(fill no)
			(layer "F.CrtYd")
		)
		(fp_poly
			(pts
				(xy -3.5179 3.5179) (xy -3.5179 -3.5179) (xy 3.5179 -3.5179) (xy 3.5179 -2.5019) (xy -2.5019 -2.5019)
				(xy -2.5019 2.5019) (xy 2.5019 2.5019) (xy 2.5019 -2.49682) (xy 3.5179 -2.49682) (xy 3.5179 3.5179)
			)
			(stroke
				(width 0)
				(type default)
			)
			(fill no)
			(layer "F.CrtYd")
		)
		(fp_rect
			(start -3.5179 3.5179)
			(end 3.5179 -3.5179)
			(stroke
				(width 0)
				(type default)
			)
			(fill no)
			(layer "F.Fab")
		)
		(pad "1" smd rect
			(at 1.299972 -2.474722 270)
			(size 0.3556 1.0668)
			(layers "F.Cu" "F.Mask" "F.Paste")
			(net "TPS74801_P2V5_STBY_OUT")
		)
		(pad "2" smd rect
			(at 0.649986 -2.474722 270)
			(size 0.3556 1.0668)
			(layers "F.Cu" "F.Mask" "F.Paste")
			(net "GND")
		)
		(pad "3" smd rect
			(at 0 -2.474722 270)
			(size 0.3556 1.0668)
			(layers "F.Cu" "F.Mask" "F.Paste")
			(net "GND")
		)
		(pad "4" smd rect
			(at -0.649986 -2.474722 270)
			(size 0.3556 1.0668)
			(layers "F.Cu" "F.Mask" "F.Paste")
			(net "GND")
		)
		(pad "5" smd rect
			(at -1.299972 -2.474722 270)
			(size 0.3556 1.0668)
			(layers "F.Cu" "F.Mask" "F.Paste")
			(net "P3V3_STBY")
		)
		(pad "6" smd rect
			(at -2.474722 -1.299972 270)
			(size 1.0668 0.3556)
			(layers "F.Cu" "F.Mask" "F.Paste")
			(net "P3V3_STBY")
		)
		(pad "7" smd rect
			(at -2.474722 -0.649986 270)
			(size 1.0668 0.3556)
			(layers "F.Cu" "F.Mask" "F.Paste")
			(net "P3V3_STBY")
		)
		(pad "8" smd rect
			(at -2.474722 0 270)
			(size 1.0668 0.3556)
			(layers "F.Cu" "F.Mask" "F.Paste")
			(net "P3V3_STBY")
		)
		(pad "9" smd rect
			(at -2.474722 0.649986 270)
			(size 1.0668 0.3556)
			(layers "F.Cu" "F.Mask" "F.Paste")
			(net "PWRGD_P2V5_STBY")
		)
		(pad "10" smd rect
			(at -2.474722 1.299972 270)
			(size 1.0668 0.3556)
			(layers "F.Cu" "F.Mask" "F.Paste")
			(net "TPS74801_P2V5_STBY_BIAS")
		)
		(pad "11" smd rect
			(at -1.299972 2.474722 270)
			(size 0.3556 1.0668)
			(layers "F.Cu" "F.Mask" "F.Paste")
			(net "TPS74801_P2V5_STBY_EN")
		)
		(pad "12" smd rect
			(at -0.649986 2.474722 270)
			(size 0.3556 1.0668)
			(layers "F.Cu" "F.Mask" "F.Paste")
			(net "GND")
		)
		(pad "13" smd rect
			(at 0 2.474722 270)
			(size 0.3556 1.0668)
			(layers "F.Cu" "F.Mask" "F.Paste")
			(net "GND")
		)
		(pad "14" smd rect
			(at 0.649986 2.474722 270)
			(size 0.3556 1.0668)
			(layers "F.Cu" "F.Mask" "F.Paste")
			(net "GND")
		)
		(pad "15" smd rect
			(at 1.299972 2.474722 270)
			(size 0.3556 1.0668)
			(layers "F.Cu" "F.Mask" "F.Paste")
			(net "TPS74801_P2V5_STBY_SS")
		)
		(pad "16" smd rect
			(at 2.474722 1.299972 270)
			(size 1.0668 0.3556)
			(layers "F.Cu" "F.Mask" "F.Paste")
			(net "TPS74801_P2V5_STBY_FB")
		)
		(pad "17" smd rect
			(at 2.474722 0.649986 270)
			(size 1.0668 0.3556)
			(layers "F.Cu" "F.Mask" "F.Paste")
			(net "GND")
		)
		(pad "18" smd rect
			(at 2.474722 0 270)
			(size 1.0668 0.3556)
			(layers "F.Cu" "F.Mask" "F.Paste")
			(net "TPS74801_P2V5_STBY_OUT")
		)
		(pad "19" smd rect
			(at 2.474722 -0.649986 270)
			(size 1.0668 0.3556)
			(layers "F.Cu" "F.Mask" "F.Paste")
			(net "TPS74801_P2V5_STBY_OUT")
		)
		(pad "20" smd rect
			(at 2.474722 -1.299972 270)
			(size 1.0668 0.3556)
			(layers "F.Cu" "F.Mask" "F.Paste")
			(net "TPS74801_P2V5_STBY_OUT")
		)
		(pad "21" smd rect
			(at 0 0 270)
			(size 3.2512 3.2512)
			(layers "F.Cu" "F.Mask" "F.Paste")
			(net "GND")
		)
	)
	(footprint ""
		(layer "F.Cu")
		(at 139.954 -15.5448 90)
		(property "Reference" "C138"
			(at 0 0 90)
			(layer "F.SilkS")
			(hide yes)
			(effects
				(font
					(size 1.27 1.27)
				)
			)
		)
		(property "Value" "SCD1U25V2KX-2-GP"
			(at 1.1811 -2.7051 90)
			(unlocked yes)
			(layer "F.Fab")
			(hide yes)
			(effects
				(font
					(size 1.016 1.016)
					(thickness 0.1524)
				)
			)
		)
		(property "Device Type" "C402H22"
			(at 1.1811 -4.2291 90)
			(unlocked yes)
			(layer "F.Fab")
			(hide yes)
			(effects
				(font
					(size 1.016 1.016)
					(thickness 0.1524)
				)
			)
		)
		(duplicate_pad_numbers_are_jumpers no)
		(fp_rect
			(start -0.4318 0.9525)
			(end 0.4318 -0.9525)
			(stroke
				(width 0)
				(type default)
			)
			(fill no)
			(layer "F.CrtYd")
		)
		(fp_rect
			(start -0.4318 0.9525)
			(end 0.4318 -0.9525)
			(stroke
				(width 0)
				(type default)
			)
			(fill no)
			(layer "F.Fab")
		)
		(pad "1" smd custom
			(at 0 -0.4445 90)
			(size 0.1524 0.1524)
			(layers "F.Cu" "F.Mask" "F.Paste")
			(net "P12V_IOM")
			(options
				(clearance outline)
				(anchor circle)
			)
			(primitives
				(gr_poly
					(pts
						(arc
							(start 0.3048 -0.2032)
							(mid 0.275042 -0.275042)
							(end 0.2032 -0.3048)
						)
						(arc
							(start -0.2032 -0.3048)
							(mid -0.275042 -0.275042)
							(end -0.3048 -0.2032)
						)
						(arc
							(start -0.3048 0.2032)
							(mid -0.275042 0.275042)
							(end -0.2032 0.3048)
						)
						(arc
							(start 0.2032 0.3048)
							(mid 0.275042 0.275042)
							(end 0.3048 0.2032)
						)
					)
					(width 0)
					(fill yes)
				)
			)
		)
		(pad "2" smd custom
			(at 0 0.4445 90)
			(size 0.1524 0.1524)
			(layers "F.Cu" "F.Mask" "F.Paste")
			(net "GND")
			(options
				(clearance outline)
				(anchor circle)
			)
			(primitives
				(gr_poly
					(pts
						(arc
							(start 0.3048 -0.2032)
							(mid 0.275042 -0.275042)
							(end 0.2032 -0.3048)
						)
						(arc
							(start -0.2032 -0.3048)
							(mid -0.275042 -0.275042)
							(end -0.3048 -0.2032)
						)
						(arc
							(start -0.3048 0.2032)
							(mid -0.275042 0.275042)
							(end -0.2032 0.3048)
						)
						(arc
							(start 0.2032 0.3048)
							(mid 0.275042 0.275042)
							(end 0.3048 0.2032)
						)
					)
					(width 0)
					(fill yes)
				)
			)
		)
	)
	(footprint ""
		(layer "F.Cu")
		(at 157.555184 -14.005052 -90)
		(property "Reference" "R517"
			(at 0 0 270)
			(layer "F.SilkS")
			(hide yes)
			(effects
				(font
					(size 1.27 1.27)
				)
			)
		)
		(property "Value" "0R2J-2-GP"
			(at 0.064008 -3.993896 270)
			(unlocked yes)
			(layer "F.Fab")
			(hide yes)
			(effects
				(font
					(size 1.016 1.016)
					(thickness 0.1524)
				)
			)
		)
		(property "Device Type" "R402H16"
			(at 0.064008 -5.517896 270)
			(unlocked yes)
			(layer "F.Fab")
			(hide yes)
			(effects
				(font
					(size 1.016 1.016)
					(thickness 0.1524)
				)
			)
		)
		(duplicate_pad_numbers_are_jumpers no)
		(fp_line
			(start -0.508 -0.9398)
			(end -0.508 0.9398)
			(stroke
				(width 0.1524)
				(type default)
			)
			(layer "F.SilkS")
		)
		(fp_line
			(start 0.508 -0.9398)
			(end -0.508 -0.9398)
			(stroke
				(width 0.1524)
				(type default)
			)
			(layer "F.SilkS")
		)
		(fp_rect
			(start -0.508 0.9398)
			(end 0.508 -0.9398)
			(stroke
				(width 0)
				(type default)
			)
			(fill no)
			(layer "F.CrtYd")
		)
		(fp_rect
			(start -0.508 0.9398)
			(end 0.508 -0.9398)
			(stroke
				(width 0)
				(type default)
			)
			(fill no)
			(layer "F.Fab")
		)
		(pad "1" smd custom
			(at 0 -0.4445 270)
			(size 0.1397 0.1397)
			(layers "F.Cu" "F.Mask" "F.Paste")
			(net "P1V8_STBY_VBST_RR")
			(options
				(clearance outline)
				(anchor circle)
			)
			(primitives
				(gr_poly
					(pts
						(arc
							(start -0.1778 -0.2794)
							(mid -0.249642 -0.249642)
							(end -0.2794 -0.1778)
						)
						(arc
							(start -0.2794 0.1778)
							(mid -0.249642 0.249642)
							(end -0.1778 0.2794)
						)
						(arc
							(start 0.1778 0.2794)
							(mid 0.249642 0.249642)
							(end 0.2794 0.1778)
						)
						(arc
							(start 0.2794 -0.1778)
							(mid 0.249642 -0.249642)
							(end 0.1778 -0.2794)
						)
					)
					(width 0)
					(fill yes)
				)
			)
		)
		(pad "2" smd custom
			(at 0 0.4445 270)
			(size 0.1397 0.1397)
			(layers "F.Cu" "F.Mask" "F.Paste")
			(net "P1V8_STBY_VBST")
			(options
				(clearance outline)
				(anchor circle)
			)
			(primitives
				(gr_poly
					(pts
						(arc
							(start -0.1778 -0.2794)
							(mid -0.249642 -0.249642)
							(end -0.2794 -0.1778)
						)
						(arc
							(start -0.2794 0.1778)
							(mid -0.249642 0.249642)
							(end -0.1778 0.2794)
						)
						(arc
							(start 0.1778 0.2794)
							(mid 0.249642 0.249642)
							(end 0.2794 0.1778)
						)
						(arc
							(start 0.2794 -0.1778)
							(mid 0.249642 -0.249642)
							(end 0.1778 -0.2794)
						)
					)
					(width 0)
					(fill yes)
				)
			)
		)
	)
	(footprint ""
		(layer "F.Cu")
		(at 57.9628 -162.7886 180)
		(property "Reference" "C120"
			(at 0 0 180)
			(layer "F.SilkS")
			(hide yes)
			(effects
				(font
					(size 1.27 1.27)
				)
			)
		)
		(property "Value" "SCD1U25V2KX-2-GP"
			(at 1.1811 -2.7051 180)
			(unlocked yes)
			(layer "F.Fab")
			(hide yes)
			(effects
				(font
					(size 1.016 1.016)
					(thickness 0.1524)
				)
			)
		)
		(property "Device Type" "C402H22"
			(at 1.1811 -4.2291 180)
			(unlocked yes)
			(layer "F.Fab")
			(hide yes)
			(effects
				(font
					(size 1.016 1.016)
					(thickness 0.1524)
				)
			)
		)
		(duplicate_pad_numbers_are_jumpers no)
		(fp_rect
			(start -0.4318 0.9525)
			(end 0.4318 -0.9525)
			(stroke
				(width 0)
				(type default)
			)
			(fill no)
			(layer "F.CrtYd")
		)
		(fp_rect
			(start -0.4318 0.9525)
			(end 0.4318 -0.9525)
			(stroke
				(width 0)
				(type default)
			)
			(fill no)
			(layer "F.Fab")
		)
		(pad "1" smd custom
			(at 0 -0.4445 180)
			(size 0.1524 0.1524)
			(layers "F.Cu" "F.Mask" "F.Paste")
			(net "ADC_P3V3_STBY")
			(options
				(clearance outline)
				(anchor circle)
			)
			(primitives
				(gr_poly
					(pts
						(arc
							(start 0.3048 -0.2032)
							(mid 0.275042 -0.275042)
							(end 0.2032 -0.3048)
						)
						(arc
							(start -0.2032 -0.3048)
							(mid -0.275042 -0.275042)
							(end -0.3048 -0.2032)
						)
						(arc
							(start -0.3048 0.2032)
							(mid -0.275042 0.275042)
							(end -0.2032 0.3048)
						)
						(arc
							(start 0.2032 0.3048)
							(mid 0.275042 0.275042)
							(end 0.3048 0.2032)
						)
					)
					(width 0)
					(fill yes)
				)
			)
		)
		(pad "2" smd custom
			(at 0 0.4445 180)
			(size 0.1524 0.1524)
			(layers "F.Cu" "F.Mask" "F.Paste")
			(net "GND")
			(options
				(clearance outline)
				(anchor circle)
			)
			(primitives
				(gr_poly
					(pts
						(arc
							(start 0.3048 -0.2032)
							(mid 0.275042 -0.275042)
							(end 0.2032 -0.3048)
						)
						(arc
							(start -0.2032 -0.3048)
							(mid -0.275042 -0.275042)
							(end -0.3048 -0.2032)
						)
						(arc
							(start -0.3048 0.2032)
							(mid -0.275042 0.275042)
							(end -0.2032 0.3048)
						)
						(arc
							(start 0.2032 0.3048)
							(mid 0.275042 0.275042)
							(end 0.3048 0.2032)
						)
					)
					(width 0)
					(fill yes)
				)
			)
		)
	)
	(footprint ""
		(layer "F.Cu")
		(at 79.72298 -178.555396 180)
		(property "Reference" "C193"
			(at 0 0 180)
			(layer "F.SilkS")
			(hide yes)
			(effects
				(font
					(size 1.27 1.27)
				)
			)
		)
		(property "Value" "SC10U6D3V5KX-4GP"
			(at -0.0762 -6.1214 180)
			(unlocked yes)
			(layer "F.Fab")
			(hide yes)
			(effects
				(font
					(size 1.016 1.016)
					(thickness 0.1524)
				)
			)
		)
		(property "Device Type" "C805H58"
			(at -0.0762 -8.1534 180)
			(unlocked yes)
			(layer "F.Fab")
			(hide yes)
			(effects
				(font
					(size 1.016 1.016)
					(thickness 0.1524)
				)
			)
		)
		(duplicate_pad_numbers_are_jumpers no)
		(fp_line
			(start 0.635 0)
			(end -0.635 0)
			(stroke
				(width 0.508)
				(type default)
			)
			(layer "F.SilkS")
		)
		(fp_rect
			(start -0.9652 1.778)
			(end 0.9652 -1.778)
			(stroke
				(width 0)
				(type default)
			)
			(fill no)
			(layer "F.CrtYd")
		)
		(fp_poly
			(pts
				(xy -0.9652 -1.778) (xy 0.9652 -1.778) (xy 0.9652 1.778) (xy -0.9652 1.778)
			)
			(stroke
				(width 0)
				(type default)
			)
			(fill no)
			(layer "F.Fab")
		)
		(pad "1" smd rect
			(at 0 -0.9652 180)
			(size 1.397 1.143)
			(layers "F.Cu" "F.Mask" "F.Paste")
			(net "TPS74801_P2V5_STBY_OUT")
		)
		(pad "2" smd rect
			(at 0 0.9652 180)
			(size 1.397 1.143)
			(layers "F.Cu" "F.Mask" "F.Paste")
			(net "GND")
		)
	)
	(footprint ""
		(layer "F.Cu")
		(at 82.441796 -173.80458 90)
		(property "Reference" "C194"
			(at 0 0 90)
			(layer "F.SilkS")
			(hide yes)
			(effects
				(font
					(size 1.27 1.27)
				)
			)
		)
		(property "Value" "SC10U6D3V5KX-4GP"
			(at -0.0762 -6.1214 90)
			(unlocked yes)
			(layer "F.Fab")
			(hide yes)
			(effects
				(font
					(size 1.016 1.016)
					(thickness 0.1524)
				)
			)
		)
		(property "Device Type" "C805H58"
			(at -0.0762 -8.1534 90)
			(unlocked yes)
			(layer "F.Fab")
			(hide yes)
			(effects
				(font
					(size 1.016 1.016)
					(thickness 0.1524)
				)
			)
		)
		(duplicate_pad_numbers_are_jumpers no)
		(fp_line
			(start 0.635 0)
			(end -0.635 0)
			(stroke
				(width 0.508)
				(type default)
			)
			(layer "F.SilkS")
		)
		(fp_rect
			(start -0.9652 1.778)
			(end 0.9652 -1.778)
			(stroke
				(width 0)
				(type default)
			)
			(fill no)
			(layer "F.CrtYd")
		)
		(fp_poly
			(pts
				(xy -0.9652 -1.778) (xy 0.9652 -1.778) (xy 0.9652 1.778) (xy -0.9652 1.778)
			)
			(stroke
				(width 0)
				(type default)
			)
			(fill no)
			(layer "F.Fab")
		)
		(pad "1" smd rect
			(at 0 -0.9652 90)
			(size 1.397 1.143)
			(layers "F.Cu" "F.Mask" "F.Paste")
			(net "TPS74801_P2V5_STBY_OUT")
		)
		(pad "2" smd rect
			(at 0 0.9652 90)
			(size 1.397 1.143)
			(layers "F.Cu" "F.Mask" "F.Paste")
			(net "GND")
		)
	)
	(footprint ""
		(layer "F.Cu")
		(at 33.5026 -159.2834)
		(property "Reference" "C90"
			(at 0 0 0)
			(layer "F.SilkS")
			(hide yes)
			(effects
				(font
					(size 1.27 1.27)
				)
			)
		)
		(property "Value" "SC1U16V3KX-5GP"
			(at 0 -2.8194 0)
			(unlocked yes)
			(layer "F.Fab")
			(hide yes)
			(effects
				(font
					(size 1.016 1.016)
					(thickness 0.1524)
				)
			)
		)
		(property "Device Type" "C603H36"
			(at 0 -4.3434 0)
			(unlocked yes)
			(layer "F.Fab")
			(hide yes)
			(effects
				(font
					(size 1.016 1.016)
					(thickness 0.1524)
				)
			)
		)
		(duplicate_pad_numbers_are_jumpers no)
		(fp_line
			(start 0.508 0)
			(end -0.508 0)
			(stroke
				(width 0.2032)
				(type default)
			)
			(layer "F.SilkS")
		)
		(fp_rect
			(start -0.5842 1.3335)
			(end 0.5842 -1.3335)
			(stroke
				(width 0)
				(type default)
			)
			(fill no)
			(layer "F.CrtYd")
		)
		(fp_rect
			(start -0.5842 1.3335)
			(end 0.5842 -1.3335)
			(stroke
				(width 0)
				(type default)
			)
			(fill no)
			(layer "F.Fab")
		)
		(pad "1" smd custom
			(at 0 -0.762)
			(size 0.2159 0.2159)
			(layers "F.Cu" "F.Mask" "F.Paste")
			(net "DACAV33")
			(options
				(clearance outline)
				(anchor circle)
			)
			(primitives
				(gr_poly
					(pts
						(arc
							(start -0.3302 -0.4318)
							(mid -0.402042 -0.402042)
							(end -0.4318 -0.3302)
						)
						(arc
							(start -0.4318 0.3302)
							(mid -0.402042 0.402042)
							(end -0.3302 0.4318)
						)
						(arc
							(start 0.3302 0.4318)
							(mid 0.402042 0.402042)
							(end 0.4318 0.3302)
						)
						(arc
							(start 0.4318 -0.3302)
							(mid 0.402042 -0.402042)
							(end 0.3302 -0.4318)
						)
					)
					(width 0)
					(fill yes)
				)
			)
		)
		(pad "2" smd custom
			(at 0 0.762)
			(size 0.2159 0.2159)
			(layers "F.Cu" "F.Mask" "F.Paste")
			(net "GND")
			(options
				(clearance outline)
				(anchor circle)
			)
			(primitives
				(gr_poly
					(pts
						(arc
							(start -0.3302 -0.4318)
							(mid -0.402042 -0.402042)
							(end -0.4318 -0.3302)
						)
						(arc
							(start -0.4318 0.3302)
							(mid -0.402042 0.402042)
							(end -0.3302 0.4318)
						)
						(arc
							(start 0.3302 0.4318)
							(mid 0.402042 0.402042)
							(end 0.4318 0.3302)
						)
						(arc
							(start 0.4318 -0.3302)
							(mid 0.402042 -0.402042)
							(end 0.3302 -0.4318)
						)
					)
					(width 0)
					(fill yes)
				)
			)
		)
	)
	(footprint ""
		(layer "F.Cu")
		(at 43.27652 -131.7498 180)
		(property "Reference" "R262"
			(at 0 0 180)
			(layer "F.SilkS")
			(hide yes)
			(effects
				(font
					(size 1.27 1.27)
				)
			)
		)
		(property "Value" "4K7R2F-GP"
			(at 0.064008 -3.993896 180)
			(unlocked yes)
			(layer "F.Fab")
			(hide yes)
			(effects
				(font
					(size 1.016 1.016)
					(thickness 0.1524)
				)
			)
		)
		(property "Device Type" "R402H16"
			(at 0.064008 -5.517896 180)
			(unlocked yes)
			(layer "F.Fab")
			(hide yes)
			(effects
				(font
					(size 1.016 1.016)
					(thickness 0.1524)
				)
			)
		)
		(duplicate_pad_numbers_are_jumpers no)
		(fp_line
			(start 0.508 -0.9398)
			(end -0.508 -0.9398)
			(stroke
				(width 0.1524)
				(type default)
			)
			(layer "F.SilkS")
		)
		(fp_line
			(start -0.508 -0.9398)
			(end -0.508 0.9398)
			(stroke
				(width 0.1524)
				(type default)
			)
			(layer "F.SilkS")
		)
		(fp_rect
			(start -0.508 0.9398)
			(end 0.508 -0.9398)
			(stroke
				(width 0)
				(type default)
			)
			(fill no)
			(layer "F.CrtYd")
		)
		(fp_rect
			(start -0.508 0.9398)
			(end 0.508 -0.9398)
			(stroke
				(width 0)
				(type default)
			)
			(fill no)
			(layer "F.Fab")
		)
		(pad "1" smd custom
			(at 0 -0.4445 180)
			(size 0.1397 0.1397)
			(layers "F.Cu" "F.Mask" "F.Paste")
			(net "P3V3_STBY")
			(options
				(clearance outline)
				(anchor circle)
			)
			(primitives
				(gr_poly
					(pts
						(arc
							(start -0.1778 -0.2794)
							(mid -0.249642 -0.249642)
							(end -0.2794 -0.1778)
						)
						(arc
							(start -0.2794 0.1778)
							(mid -0.249642 0.249642)
							(end -0.1778 0.2794)
						)
						(arc
							(start 0.1778 0.2794)
							(mid 0.249642 0.249642)
							(end 0.2794 0.1778)
						)
						(arc
							(start 0.2794 -0.1778)
							(mid 0.249642 -0.249642)
							(end 0.1778 -0.2794)
						)
					)
					(width 0)
					(fill yes)
				)
			)
		)
		(pad "2" smd custom
			(at 0 0.4445 180)
			(size 0.1397 0.1397)
			(layers "F.Cu" "F.Mask" "F.Paste")
			(net "BMC_GPIOY0")
			(options
				(clearance outline)
				(anchor circle)
			)
			(primitives
				(gr_poly
					(pts
						(arc
							(start -0.1778 -0.2794)
							(mid -0.249642 -0.249642)
							(end -0.2794 -0.1778)
						)
						(arc
							(start -0.2794 0.1778)
							(mid -0.249642 0.249642)
							(end -0.1778 0.2794)
						)
						(arc
							(start 0.1778 0.2794)
							(mid 0.249642 0.249642)
							(end 0.2794 0.1778)
						)
						(arc
							(start 0.2794 -0.1778)
							(mid 0.249642 -0.249642)
							(end 0.1778 -0.2794)
						)
					)
					(width 0)
					(fill yes)
				)
			)
		)
	)
	(footprint ""
		(layer "F.Cu")
		(at 198.12 -140.97 -135)
		(property "Reference" "VIA55"
			(at 0 0 225)
			(layer "F.SilkS")
			(hide yes)
			(effects
				(font
					(size 1.27 1.27)
				)
			)
		)
		(property "Value" "85OHM-8L-1D6MM-L16L18-GP"
			(at 4.064105 0.609655 225)
			(unlocked yes)
			(layer "F.Fab")
			(hide yes)
			(effects
				(font
					(size 1.016 1.016)
					(thickness 0.1524)
				)
			)
		)
		(property "Device Type" "VIA-PCIE-4P-368076"
			(at 4.064105 -0.914474 225)
			(unlocked yes)
			(layer "F.Fab")
			(hide yes)
			(effects
				(font
					(size 1.016 1.016)
					(thickness 0.1524)
				)
			)
		)
		(duplicate_pad_numbers_are_jumpers no)
		(fp_poly
			(pts
				(xy -1.841491 -0.381057) (xy 1.841509 -0.381058) (xy 1.841508 0.380942) (xy -1.841491 0.380942)
			)
			(stroke
				(width 0)
				(type default)
			)
			(fill no)
			(layer "F.CrtYd")
		)
		(fp_poly
			(pts
				(xy -1.841491 -0.381057) (xy 1.841509 -0.381058) (xy 1.841508 0.380942) (xy -1.841491 0.380942)
			)
			(stroke
				(width 0)
				(type default)
			)
			(fill no)
			(layer "F.Fab")
		)
		(pad "1" thru_hole circle
			(at -1.460499 0 225)
			(size 0.508 0.508)
			(drill 0.254)
			(layers "*.Cu" "*.Mask")
			(remove_unused_layers no)
			(net "GND")
			(clearance 0.127)
			(thermal_gap 0.127)
		)
		(pad "2" thru_hole circle
			(at -0.4445 0 225)
			(size 0.508 0.508)
			(drill 0.254)
			(layers "*.Cu" "*.Mask")
			(remove_unused_layers no)
			(net "PCIE_IOM_TO_COMP_10_DP")
			(clearance 0.127)
			(thermal_gap 0.127)
		)
		(pad "3" thru_hole circle
			(at 0.4445 0 225)
			(size 0.508 0.508)
			(drill 0.254)
			(layers "*.Cu" "*.Mask")
			(remove_unused_layers no)
			(net "PCIE_IOM_TO_COMP_10_DN")
			(clearance 0.127)
			(thermal_gap 0.127)
		)
		(pad "4" thru_hole circle
			(at 1.460499 0 225)
			(size 0.508 0.508)
			(drill 0.254)
			(layers "*.Cu" "*.Mask")
			(remove_unused_layers no)
			(net "GND")
			(clearance 0.127)
			(thermal_gap 0.127)
		)
	)
	(footprint ""
		(layer "F.Cu")
		(at 9.779 -13.081)
		(property "Reference" "R65"
			(at 0 0 0)
			(layer "F.SilkS")
			(hide yes)
			(effects
				(font
					(size 1.27 1.27)
				)
			)
		)
		(property "Value" "8K2R2J-3-GP"
			(at 0.064008 -3.993896 0)
			(unlocked yes)
			(layer "F.Fab")
			(hide yes)
			(effects
				(font
					(size 1.016 1.016)
					(thickness 0.1524)
				)
			)
		)
		(property "Device Type" "R402H16"
			(at 0.064008 -5.517896 0)
			(unlocked yes)
			(layer "F.Fab")
			(hide yes)
			(effects
				(font
					(size 1.016 1.016)
					(thickness 0.1524)
				)
			)
		)
		(duplicate_pad_numbers_are_jumpers no)
		(fp_line
			(start -0.508 -0.9398)
			(end -0.508 0.9398)
			(stroke
				(width 0.1524)
				(type default)
			)
			(layer "F.SilkS")
		)
		(fp_line
			(start 0.508 -0.9398)
			(end -0.508 -0.9398)
			(stroke
				(width 0.1524)
				(type default)
			)
			(layer "F.SilkS")
		)
		(fp_rect
			(start -0.508 0.9398)
			(end 0.508 -0.9398)
			(stroke
				(width 0)
				(type default)
			)
			(fill no)
			(layer "F.CrtYd")
		)
		(fp_rect
			(start -0.508 0.9398)
			(end 0.508 -0.9398)
			(stroke
				(width 0)
				(type default)
			)
			(fill no)
			(layer "F.Fab")
		)
		(pad "1" smd custom
			(at 0 -0.4445)
			(size 0.1397 0.1397)
			(layers "F.Cu" "F.Mask" "F.Paste")
			(net "P3V3_STBY")
			(options
				(clearance outline)
				(anchor circle)
			)
			(primitives
				(gr_poly
					(pts
						(arc
							(start -0.1778 -0.2794)
							(mid -0.249642 -0.249642)
							(end -0.2794 -0.1778)
						)
						(arc
							(start -0.2794 0.1778)
							(mid -0.249642 0.249642)
							(end -0.1778 0.2794)
						)
						(arc
							(start 0.1778 0.2794)
							(mid 0.249642 0.249642)
							(end 0.2794 0.1778)
						)
						(arc
							(start 0.2794 -0.1778)
							(mid 0.249642 -0.249642)
							(end 0.1778 -0.2794)
						)
					)
					(width 0)
					(fill yes)
				)
			)
		)
		(pad "2" smd custom
			(at 0 0.4445)
			(size 0.1397 0.1397)
			(layers "F.Cu" "F.Mask" "F.Paste")
			(net "SYS_RST_BTN_IN_N")
			(options
				(clearance outline)
				(anchor circle)
			)
			(primitives
				(gr_poly
					(pts
						(arc
							(start -0.1778 -0.2794)
							(mid -0.249642 -0.249642)
							(end -0.2794 -0.1778)
						)
						(arc
							(start -0.2794 0.1778)
							(mid -0.249642 0.249642)
							(end -0.1778 0.2794)
						)
						(arc
							(start 0.1778 0.2794)
							(mid 0.249642 0.249642)
							(end 0.2794 0.1778)
						)
						(arc
							(start 0.2794 -0.1778)
							(mid 0.249642 -0.249642)
							(end 0.1778 -0.2794)
						)
					)
					(width 0)
					(fill yes)
				)
			)
		)
	)
	(footprint ""
		(layer "F.Cu")
		(at 40.6654 -158.0642)
		(property "Reference" "TP189"
			(at 0 0 0)
			(layer "F.SilkS")
			(hide yes)
			(effects
				(font
					(size 1.27 1.27)
				)
			)
		)
		(property "Value" "TPAD28-2-GP"
			(at -0.0127 -1.6637 0)
			(unlocked yes)
			(layer "F.Fab")
			(hide yes)
			(effects
				(font
					(size 1.016 1.016)
					(thickness 0.1524)
				)
			)
		)
		(property "Device Type" "TPAD28"
			(at -0.0127 -3.1877 0)
			(unlocked yes)
			(layer "F.Fab")
			(hide yes)
			(effects
				(font
					(size 1.016 1.016)
					(thickness 0.1524)
				)
			)
		)
		(duplicate_pad_numbers_are_jumpers no)
		(fp_poly
			(pts
				(arc
					(start 0.3556 0)
					(mid -0.3556 0)
					(end 0.3556 0)
				)
			)
			(stroke
				(width 0)
				(type default)
			)
			(fill no)
			(layer "F.CrtYd")
		)
		(fp_poly
			(pts
				(arc
					(start 0.6096 0)
					(mid -0.6096 0)
					(end 0.6096 0)
				)
			)
			(stroke
				(width 0)
				(type default)
			)
			(fill no)
			(layer "F.Fab")
		)
		(pad "1" smd circle
			(at 0 0)
			(size 0.7112 0.7112)
			(layers "F.Cu" "F.Mask" "F.Paste")
			(net "TP_BMC_GPIOL3")
		)
	)
	(footprint ""
		(layer "F.Cu")
		(at 88.773 -130.0226 -90)
		(property "Reference" "R421"
			(at 0 0 270)
			(layer "F.SilkS")
			(hide yes)
			(effects
				(font
					(size 1.27 1.27)
				)
			)
		)
		(property "Value" "10KR2F-2-GP"
			(at 0.064008 -3.993896 270)
			(unlocked yes)
			(layer "F.Fab")
			(hide yes)
			(effects
				(font
					(size 1.016 1.016)
					(thickness 0.1524)
				)
			)
		)
		(property "Device Type" "R402H16"
			(at 0.064008 -5.517896 270)
			(unlocked yes)
			(layer "F.Fab")
			(hide yes)
			(effects
				(font
					(size 1.016 1.016)
					(thickness 0.1524)
				)
			)
		)
		(duplicate_pad_numbers_are_jumpers no)
		(fp_line
			(start -0.508 -0.9398)
			(end -0.508 0.9398)
			(stroke
				(width 0.1524)
				(type default)
			)
			(layer "F.SilkS")
		)
		(fp_line
			(start 0.508 -0.9398)
			(end -0.508 -0.9398)
			(stroke
				(width 0.1524)
				(type default)
			)
			(layer "F.SilkS")
		)
		(fp_rect
			(start -0.508 0.9398)
			(end 0.508 -0.9398)
			(stroke
				(width 0)
				(type default)
			)
			(fill no)
			(layer "F.CrtYd")
		)
		(fp_rect
			(start -0.508 0.9398)
			(end 0.508 -0.9398)
			(stroke
				(width 0)
				(type default)
			)
			(fill no)
			(layer "F.Fab")
		)
		(pad "1" smd custom
			(at 0 -0.4445 270)
			(size 0.1397 0.1397)
			(layers "F.Cu" "F.Mask" "F.Paste")
			(net "UART_SEL_MUX")
			(options
				(clearance outline)
				(anchor circle)
			)
			(primitives
				(gr_poly
					(pts
						(arc
							(start -0.1778 -0.2794)
							(mid -0.249642 -0.249642)
							(end -0.2794 -0.1778)
						)
						(arc
							(start -0.2794 0.1778)
							(mid -0.249642 0.249642)
							(end -0.1778 0.2794)
						)
						(arc
							(start 0.1778 0.2794)
							(mid 0.249642 0.249642)
							(end 0.2794 0.1778)
						)
						(arc
							(start 0.2794 -0.1778)
							(mid 0.249642 -0.249642)
							(end 0.1778 -0.2794)
						)
					)
					(width 0)
					(fill yes)
				)
			)
		)
		(pad "2" smd custom
			(at 0 0.4445 270)
			(size 0.1397 0.1397)
			(layers "F.Cu" "F.Mask" "F.Paste")
			(net "GND")
			(options
				(clearance outline)
				(anchor circle)
			)
			(primitives
				(gr_poly
					(pts
						(arc
							(start -0.1778 -0.2794)
							(mid -0.249642 -0.249642)
							(end -0.2794 -0.1778)
						)
						(arc
							(start -0.2794 0.1778)
							(mid -0.249642 0.249642)
							(end -0.1778 0.2794)
						)
						(arc
							(start 0.1778 0.2794)
							(mid 0.249642 0.249642)
							(end 0.2794 0.1778)
						)
						(arc
							(start 0.2794 -0.1778)
							(mid 0.249642 -0.249642)
							(end 0.1778 -0.2794)
						)
					)
					(width 0)
					(fill yes)
				)
			)
		)
	)
	(footprint ""
		(layer "F.Cu")
		(at 216.069672 -51.781456 -90)
		(property "Reference" "R477"
			(at 0 0 270)
			(layer "F.SilkS")
			(hide yes)
			(effects
				(font
					(size 1.27 1.27)
				)
			)
		)
		(property "Value" "619KR2F-GP"
			(at 0.064008 -3.993896 270)
			(unlocked yes)
			(layer "F.Fab")
			(hide yes)
			(effects
				(font
					(size 1.016 1.016)
					(thickness 0.1524)
				)
			)
		)
		(property "Device Type" "R402H16"
			(at 0.064008 -5.517896 270)
			(unlocked yes)
			(layer "F.Fab")
			(hide yes)
			(effects
				(font
					(size 1.016 1.016)
					(thickness 0.1524)
				)
			)
		)
		(duplicate_pad_numbers_are_jumpers no)
		(fp_line
			(start -0.508 -0.9398)
			(end -0.508 0.9398)
			(stroke
				(width 0.1524)
				(type default)
			)
			(layer "F.SilkS")
		)
		(fp_line
			(start 0.508 -0.9398)
			(end -0.508 -0.9398)
			(stroke
				(width 0.1524)
				(type default)
			)
			(layer "F.SilkS")
		)
		(fp_rect
			(start -0.508 0.9398)
			(end 0.508 -0.9398)
			(stroke
				(width 0)
				(type default)
			)
			(fill no)
			(layer "F.CrtYd")
		)
		(fp_rect
			(start -0.508 0.9398)
			(end 0.508 -0.9398)
			(stroke
				(width 0)
				(type default)
			)
			(fill no)
			(layer "F.Fab")
		)
		(pad "1" smd custom
			(at 0 -0.4445 270)
			(size 0.1397 0.1397)
			(layers "F.Cu" "F.Mask" "F.Paste")
			(net "P5V_RF")
			(options
				(clearance outline)
				(anchor circle)
			)
			(primitives
				(gr_poly
					(pts
						(arc
							(start -0.1778 -0.2794)
							(mid -0.249642 -0.249642)
							(end -0.2794 -0.1778)
						)
						(arc
							(start -0.2794 0.1778)
							(mid -0.249642 0.249642)
							(end -0.1778 0.2794)
						)
						(arc
							(start 0.1778 0.2794)
							(mid 0.249642 0.249642)
							(end 0.2794 0.1778)
						)
						(arc
							(start 0.2794 -0.1778)
							(mid 0.249642 -0.249642)
							(end 0.1778 -0.2794)
						)
					)
					(width 0)
					(fill yes)
				)
			)
		)
		(pad "2" smd custom
			(at 0 0.4445 270)
			(size 0.1397 0.1397)
			(layers "F.Cu" "F.Mask" "F.Paste")
			(net "AGND_P5V")
			(options
				(clearance outline)
				(anchor circle)
			)
			(primitives
				(gr_poly
					(pts
						(arc
							(start -0.1778 -0.2794)
							(mid -0.249642 -0.249642)
							(end -0.2794 -0.1778)
						)
						(arc
							(start -0.2794 0.1778)
							(mid -0.249642 0.249642)
							(end -0.1778 0.2794)
						)
						(arc
							(start 0.1778 0.2794)
							(mid 0.249642 0.249642)
							(end 0.2794 0.1778)
						)
						(arc
							(start 0.2794 -0.1778)
							(mid 0.249642 -0.249642)
							(end 0.1778 -0.2794)
						)
					)
					(width 0)
					(fill yes)
				)
			)
		)
	)
	(footprint ""
		(layer "F.Cu")
		(at 28.790646 -176.618138 180)
		(property "Reference" "R493"
			(at 0 0 180)
			(layer "F.SilkS")
			(hide yes)
			(effects
				(font
					(size 1.27 1.27)
				)
			)
		)
		(property "Value" "100KR2F-L1-GP"
			(at 0.064008 -3.993896 180)
			(unlocked yes)
			(layer "F.Fab")
			(hide yes)
			(effects
				(font
					(size 1.016 1.016)
					(thickness 0.1524)
				)
			)
		)
		(property "Device Type" "R402H16"
			(at 0.064008 -5.517896 180)
			(unlocked yes)
			(layer "F.Fab")
			(hide yes)
			(effects
				(font
					(size 1.016 1.016)
					(thickness 0.1524)
				)
			)
		)
		(duplicate_pad_numbers_are_jumpers no)
		(fp_line
			(start 0.508 -0.9398)
			(end -0.508 -0.9398)
			(stroke
				(width 0.1524)
				(type default)
			)
			(layer "F.SilkS")
		)
		(fp_line
			(start -0.508 -0.9398)
			(end -0.508 0.9398)
			(stroke
				(width 0.1524)
				(type default)
			)
			(layer "F.SilkS")
		)
		(fp_rect
			(start -0.508 0.9398)
			(end 0.508 -0.9398)
			(stroke
				(width 0)
				(type default)
			)
			(fill no)
			(layer "F.CrtYd")
		)
		(fp_rect
			(start -0.508 0.9398)
			(end 0.508 -0.9398)
			(stroke
				(width 0)
				(type default)
			)
			(fill no)
			(layer "F.Fab")
		)
		(pad "1" smd custom
			(at 0 -0.4445 180)
			(size 0.1397 0.1397)
			(layers "F.Cu" "F.Mask" "F.Paste")
			(net "AGND_P3V3_STBY")
			(options
				(clearance outline)
				(anchor circle)
			)
			(primitives
				(gr_poly
					(pts
						(arc
							(start -0.1778 -0.2794)
							(mid -0.249642 -0.249642)
							(end -0.2794 -0.1778)
						)
						(arc
							(start -0.2794 0.1778)
							(mid -0.249642 0.249642)
							(end -0.1778 0.2794)
						)
						(arc
							(start 0.1778 0.2794)
							(mid 0.249642 0.249642)
							(end 0.2794 0.1778)
						)
						(arc
							(start 0.2794 -0.1778)
							(mid 0.249642 -0.249642)
							(end 0.1778 -0.2794)
						)
					)
					(width 0)
					(fill yes)
				)
			)
		)
		(pad "2" smd custom
			(at 0 0.4445 180)
			(size 0.1397 0.1397)
			(layers "F.Cu" "F.Mask" "F.Paste")
			(net "P3V3_STBY_MODE")
			(options
				(clearance outline)
				(anchor circle)
			)
			(primitives
				(gr_poly
					(pts
						(arc
							(start -0.1778 -0.2794)
							(mid -0.249642 -0.249642)
							(end -0.2794 -0.1778)
						)
						(arc
							(start -0.2794 0.1778)
							(mid -0.249642 0.249642)
							(end -0.1778 0.2794)
						)
						(arc
							(start 0.1778 0.2794)
							(mid 0.249642 0.249642)
							(end 0.2794 0.1778)
						)
						(arc
							(start 0.2794 -0.1778)
							(mid 0.249642 -0.249642)
							(end 0.1778 -0.2794)
						)
					)
					(width 0)
					(fill yes)
				)
			)
		)
	)
	(footprint ""
		(layer "F.Cu")
		(at 220.883988 -48.58131 180)
		(property "Reference" "PU1"
			(at 0 0 180)
			(layer "F.SilkS")
			(hide yes)
			(effects
				(font
					(size 1.27 1.27)
				)
			)
		)
		(property "Value" "TPS53318DQPR-GP"
			(at -5.022088 -6.851904 180)
			(unlocked yes)
			(layer "F.Fab")
			(hide yes)
			(effects
				(font
					(size 1.016 1.016)
					(thickness 0.1524)
				)
			)
		)
		(property "Device Type" "DFN22G6050-G6133H60"
			(at -5.022088 -8.375904 180)
			(unlocked yes)
			(layer "F.Fab")
			(hide yes)
			(effects
				(font
					(size 1.016 1.016)
					(thickness 0.1524)
				)
			)
		)
		(duplicate_pad_numbers_are_jumpers no)
		(fp_line
			(start 3.5052 3.5179)
			(end 3.5052 2.2479)
			(stroke
				(width 0.1524)
				(type default)
			)
			(layer "F.SilkS")
		)
		(fp_line
			(start 2.2352 3.5179)
			(end 3.5052 3.5179)
			(stroke
				(width 0.1524)
				(type default)
			)
			(layer "F.SilkS")
		)
		(fp_line
			(start 1.500124 3.262122)
			(end 1.500124 4.024122)
			(stroke
				(width 0.1524)
				(type default)
			)
			(layer "F.SilkS")
		)
		(fp_line
			(start 0.500126 -3.262122)
			(end 0.500126 -3.770122)
			(stroke
				(width 0.1524)
				(type default)
			)
			(layer "F.SilkS")
		)
		(fp_line
			(start -0.999998 3.262122)
			(end -0.999998 3.770122)
			(stroke
				(width 0.1524)
				(type default)
			)
			(layer "F.SilkS")
		)
		(fp_line
			(start -1.999996 -3.262122)
			(end -1.999996 -4.024122)
			(stroke
				(width 0.1524)
				(type default)
			)
			(layer "F.SilkS")
		)
		(fp_line
			(start -2.2352 -3.5179)
			(end -3.5052 -3.5179)
			(stroke
				(width 0.1524)
				(type default)
			)
			(layer "F.SilkS")
		)
		(fp_line
			(start -3.5052 3.5179)
			(end -2.2352 3.5179)
			(stroke
				(width 0.1524)
				(type default)
			)
			(layer "F.SilkS")
		)
		(fp_line
			(start -3.5052 2.2479)
			(end -3.5052 3.5179)
			(stroke
				(width 0.1524)
				(type default)
			)
			(layer "F.SilkS")
		)
		(fp_line
			(start -3.5052 -3.5179)
			(end -3.5052 -2.2479)
			(stroke
				(width 0.1524)
				(type default)
			)
			(layer "F.SilkS")
		)
		(fp_poly
			(pts
				(xy 3.5052 -3.5179) (xy 2.4765 -3.5179) (xy 3.5052 -2.4892)
			)
			(stroke
				(width 0)
				(type default)
			)
			(fill yes)
			(layer "F.SilkS")
		)
		(fp_rect
			(start -2.9972 2.5019)
			(end 2.9972 -2.5019)
			(stroke
				(width 0)
				(type default)
			)
			(fill no)
			(layer "F.CrtYd")
		)
		(fp_poly
			(pts
				(xy 3.556 -2.5019) (xy -2.9972 -2.5019) (xy -2.9972 2.5019) (xy 2.9972 2.5019) (xy 2.9972 -2.4892)
				(xy 3.556 -2.4892) (xy 3.556 3.5179) (xy -3.556 3.5179) (xy -3.556 -3.5179) (xy 3.556 -3.5179)
			)
			(stroke
				(width 0)
				(type default)
			)
			(fill no)
			(layer "F.CrtYd")
		)
		(fp_rect
			(start -3.556 3.5179)
			(end 3.556 -3.5179)
			(stroke
				(width 0)
				(type default)
			)
			(fill no)
			(layer "F.Fab")
		)
		(pad "1" smd rect
			(at 2.500122 -2.449322 180)
			(size 0.3048 1.1176)
			(layers "F.Cu" "F.Mask" "F.Paste")
			(net "P5V_VFB")
		)
		(pad "2" smd rect
			(at 1.999996 -2.449322 180)
			(size 0.3048 1.1176)
			(layers "F.Cu" "F.Mask" "F.Paste")
			(net "P5V_EN_R")
		)
		(pad "3" smd rect
			(at 1.500124 -2.449322 180)
			(size 0.3048 1.1176)
			(layers "F.Cu" "F.Mask" "F.Paste")
			(net "PWRGD_P5V_STBY")
		)
		(pad "4" smd rect
			(at 0.999998 -2.449322 180)
			(size 0.3048 1.1176)
			(layers "F.Cu" "F.Mask" "F.Paste")
			(net "P5V_VBST")
		)
		(pad "5" smd rect
			(at 0.500126 -2.449322 180)
			(size 0.3048 1.1176)
			(layers "F.Cu" "F.Mask" "F.Paste")
			(net "AGND_P5V")
		)
		(pad "6" smd rect
			(at 0 -2.449322 180)
			(size 0.3048 1.1176)
			(layers "F.Cu" "F.Mask" "F.Paste")
			(net "P5V_LL")
		)
		(pad "7" smd rect
			(at -0.500126 -2.449322 180)
			(size 0.3048 1.1176)
			(layers "F.Cu" "F.Mask" "F.Paste")
			(net "P5V_LL")
		)
		(pad "8" smd rect
			(at -0.999998 -2.449322 180)
			(size 0.3048 1.1176)
			(layers "F.Cu" "F.Mask" "F.Paste")
			(net "P5V_LL")
		)
		(pad "9" smd rect
			(at -1.500124 -2.449322 180)
			(size 0.3048 1.1176)
			(layers "F.Cu" "F.Mask" "F.Paste")
			(net "P5V_LL")
		)
		(pad "10" smd rect
			(at -1.999996 -2.449322 180)
			(size 0.3048 1.1176)
			(layers "F.Cu" "F.Mask" "F.Paste")
			(net "P5V_LL")
		)
		(pad "11" smd rect
			(at -2.500122 -2.449322 180)
			(size 0.3048 1.1176)
			(layers "F.Cu" "F.Mask" "F.Paste")
			(net "P5V_LL")
		)
		(pad "12" smd rect
			(at -2.500122 2.449322 180)
			(size 0.3048 1.1176)
			(layers "F.Cu" "F.Mask" "F.Paste")
			(net "P12V_STBY_VIN_PU1")
		)
		(pad "13" smd rect
			(at -1.999996 2.449322 180)
			(size 0.3048 1.1176)
			(layers "F.Cu" "F.Mask" "F.Paste")
			(net "P12V_STBY_VIN_PU1")
		)
		(pad "14" smd rect
			(at -1.500124 2.449322 180)
			(size 0.3048 1.1176)
			(layers "F.Cu" "F.Mask" "F.Paste")
			(net "P12V_STBY_VIN_PU1")
		)
		(pad "15" smd rect
			(at -0.999998 2.449322 180)
			(size 0.3048 1.1176)
			(layers "F.Cu" "F.Mask" "F.Paste")
			(net "P12V_STBY_VIN_PU1")
		)
		(pad "16" smd rect
			(at -0.500126 2.449322 180)
			(size 0.3048 1.1176)
			(layers "F.Cu" "F.Mask" "F.Paste")
			(net "P12V_STBY_VIN_PU1")
		)
		(pad "17" smd rect
			(at 0 2.449322 180)
			(size 0.3048 1.1176)
			(layers "F.Cu" "F.Mask" "F.Paste")
			(net "P12V_STBY_VIN_PU1")
		)
		(pad "18" smd rect
			(at 0.500126 2.449322 180)
			(size 0.3048 1.1176)
			(layers "F.Cu" "F.Mask" "F.Paste")
			(net "P5V_STBY_VREG")
		)
		(pad "19" smd rect
			(at 0.999998 2.449322 180)
			(size 0.3048 1.1176)
			(layers "F.Cu" "F.Mask" "F.Paste")
			(net "P5V_VDD")
		)
		(pad "20" smd rect
			(at 1.500124 2.449322 180)
			(size 0.3048 1.1176)
			(layers "F.Cu" "F.Mask" "F.Paste")
			(net "P5V_MODE")
		)
		(pad "21" smd rect
			(at 1.999996 2.449322 180)
			(size 0.3048 1.1176)
			(layers "F.Cu" "F.Mask" "F.Paste")
			(net "P5V_TRIP")
		)
		(pad "22" smd rect
			(at 2.500122 2.449322 180)
			(size 0.3048 1.1176)
			(layers "F.Cu" "F.Mask" "F.Paste")
			(net "P5V_RF")
		)
		(pad "23" smd custom
			(at 0 0 180)
			(size 0.83185 0.83185)
			(layers "F.Cu" "F.Mask" "F.Paste")
			(net "GND")
			(options
				(clearance outline)
				(anchor circle)
			)
			(primitives
				(gr_poly
					(pts
						(xy -2.7813 1.6637) (xy -2.7813 1.2954) (xy -3.048 1.2954) (xy -3.048 0.9525) (xy -2.7813 0.9525)
						(xy -2.7813 -0.9525) (xy -3.048 -0.9525) (xy -3.048 -1.2954) (xy -2.7813 -1.2954) (xy -2.7813 -1.6637)
						(xy 2.7813 -1.6637) (xy 2.7813 -1.2954) (xy 3.048 -1.2954) (xy 3.048 -0.9525) (xy 2.7813 -0.9525)
						(xy 2.7813 0.9525) (xy 3.048 0.9525) (xy 3.048 1.2954) (xy 2.7813 1.2954) (xy 2.7813 1.6637)
					)
					(width 0)
					(fill yes)
				)
			)
		)
	)
	(footprint ""
		(layer "F.Cu")
		(at 72.82053 -146.421602 -90)
		(property "Reference" "C513"
			(at 0 0 270)
			(layer "F.SilkS")
			(hide yes)
			(effects
				(font
					(size 1.27 1.27)
				)
			)
		)
		(property "Value" "SCD1U16V2KX-3GP"
			(at 1.1811 -2.7051 270)
			(unlocked yes)
			(layer "F.Fab")
			(hide yes)
			(effects
				(font
					(size 1.016 1.016)
					(thickness 0.1524)
				)
			)
		)
		(property "Device Type" "C402H22"
			(at 1.1811 -4.2291 270)
			(unlocked yes)
			(layer "F.Fab")
			(hide yes)
			(effects
				(font
					(size 1.016 1.016)
					(thickness 0.1524)
				)
			)
		)
		(duplicate_pad_numbers_are_jumpers no)
		(fp_rect
			(start -0.4318 0.9525)
			(end 0.4318 -0.9525)
			(stroke
				(width 0)
				(type default)
			)
			(fill no)
			(layer "F.CrtYd")
		)
		(fp_rect
			(start -0.4318 0.9525)
			(end 0.4318 -0.9525)
			(stroke
				(width 0)
				(type default)
			)
			(fill no)
			(layer "F.Fab")
		)
		(pad "1" smd custom
			(at 0 -0.4445 270)
			(size 0.1524 0.1524)
			(layers "F.Cu" "F.Mask" "F.Paste")
			(net "P3V3_STBY")
			(options
				(clearance outline)
				(anchor circle)
			)
			(primitives
				(gr_poly
					(pts
						(arc
							(start 0.3048 -0.2032)
							(mid 0.275042 -0.275042)
							(end 0.2032 -0.3048)
						)
						(arc
							(start -0.2032 -0.3048)
							(mid -0.275042 -0.275042)
							(end -0.3048 -0.2032)
						)
						(arc
							(start -0.3048 0.2032)
							(mid -0.275042 0.275042)
							(end -0.2032 0.3048)
						)
						(arc
							(start 0.2032 0.3048)
							(mid 0.275042 0.275042)
							(end 0.3048 0.2032)
						)
					)
					(width 0)
					(fill yes)
				)
			)
		)
		(pad "2" smd custom
			(at 0 0.4445 270)
			(size 0.1524 0.1524)
			(layers "F.Cu" "F.Mask" "F.Paste")
			(net "GND")
			(options
				(clearance outline)
				(anchor circle)
			)
			(primitives
				(gr_poly
					(pts
						(arc
							(start 0.3048 -0.2032)
							(mid 0.275042 -0.275042)
							(end 0.2032 -0.3048)
						)
						(arc
							(start -0.2032 -0.3048)
							(mid -0.275042 -0.275042)
							(end -0.3048 -0.2032)
						)
						(arc
							(start -0.3048 0.2032)
							(mid -0.275042 0.275042)
							(end -0.2032 0.3048)
						)
						(arc
							(start 0.2032 0.3048)
							(mid 0.275042 0.275042)
							(end 0.3048 0.2032)
						)
					)
					(width 0)
					(fill yes)
				)
			)
		)
	)
	(footprint ""
		(layer "F.Cu")
		(at 181.064154 -121.051828)
		(property "Reference" "R805"
			(at 0 0 0)
			(layer "F.SilkS")
			(hide yes)
			(effects
				(font
					(size 1.27 1.27)
				)
			)
		)
		(property "Value" "4K7R2F-GP"
			(at 0.064008 -3.993896 0)
			(unlocked yes)
			(layer "F.Fab")
			(hide yes)
			(effects
				(font
					(size 1.016 1.016)
					(thickness 0.1524)
				)
			)
		)
		(property "Device Type" "R402H16"
			(at 0.064008 -5.517896 0)
			(unlocked yes)
			(layer "F.Fab")
			(hide yes)
			(effects
				(font
					(size 1.016 1.016)
					(thickness 0.1524)
				)
			)
		)
		(duplicate_pad_numbers_are_jumpers no)
		(fp_line
			(start -0.508 -0.9398)
			(end -0.508 0.9398)
			(stroke
				(width 0.1524)
				(type default)
			)
			(layer "F.SilkS")
		)
		(fp_line
			(start 0.508 -0.9398)
			(end -0.508 -0.9398)
			(stroke
				(width 0.1524)
				(type default)
			)
			(layer "F.SilkS")
		)
		(fp_rect
			(start -0.508 0.9398)
			(end 0.508 -0.9398)
			(stroke
				(width 0)
				(type default)
			)
			(fill no)
			(layer "F.CrtYd")
		)
		(fp_rect
			(start -0.508 0.9398)
			(end 0.508 -0.9398)
			(stroke
				(width 0)
				(type default)
			)
			(fill no)
			(layer "F.Fab")
		)
		(pad "1" smd custom
			(at 0 -0.4445)
			(size 0.1397 0.1397)
			(layers "F.Cu" "F.Mask" "F.Paste")
			(net "M2_2_ALERT#")
			(options
				(clearance outline)
				(anchor circle)
			)
			(primitives
				(gr_poly
					(pts
						(arc
							(start -0.1778 -0.2794)
							(mid -0.249642 -0.249642)
							(end -0.2794 -0.1778)
						)
						(arc
							(start -0.2794 0.1778)
							(mid -0.249642 0.249642)
							(end -0.1778 0.2794)
						)
						(arc
							(start 0.1778 0.2794)
							(mid 0.249642 0.249642)
							(end 0.2794 0.1778)
						)
						(arc
							(start 0.2794 -0.1778)
							(mid 0.249642 -0.249642)
							(end 0.1778 -0.2794)
						)
					)
					(width 0)
					(fill yes)
				)
			)
		)
		(pad "2" smd custom
			(at 0 0.4445)
			(size 0.1397 0.1397)
			(layers "F.Cu" "F.Mask" "F.Paste")
			(net "P1V8_STBY")
			(options
				(clearance outline)
				(anchor circle)
			)
			(primitives
				(gr_poly
					(pts
						(arc
							(start -0.1778 -0.2794)
							(mid -0.249642 -0.249642)
							(end -0.2794 -0.1778)
						)
						(arc
							(start -0.2794 0.1778)
							(mid -0.249642 0.249642)
							(end -0.1778 0.2794)
						)
						(arc
							(start 0.1778 0.2794)
							(mid 0.249642 0.249642)
							(end 0.2794 0.1778)
						)
						(arc
							(start 0.2794 -0.1778)
							(mid 0.249642 -0.249642)
							(end 0.1778 -0.2794)
						)
					)
					(width 0)
					(fill yes)
				)
			)
		)
	)
	(footprint ""
		(layer "F.Cu")
		(at 214.152988 -40.719756 -90)
		(property "Reference" "C156"
			(at 0 0 270)
			(layer "F.SilkS")
			(hide yes)
			(effects
				(font
					(size 1.27 1.27)
				)
			)
		)
		(property "Value" "SC1U16V3KX-5GP"
			(at 0 -2.8194 270)
			(unlocked yes)
			(layer "F.Fab")
			(hide yes)
			(effects
				(font
					(size 1.016 1.016)
					(thickness 0.1524)
				)
			)
		)
		(property "Device Type" "C603H36"
			(at 0 -4.3434 270)
			(unlocked yes)
			(layer "F.Fab")
			(hide yes)
			(effects
				(font
					(size 1.016 1.016)
					(thickness 0.1524)
				)
			)
		)
		(duplicate_pad_numbers_are_jumpers no)
		(fp_line
			(start 0.508 0)
			(end -0.508 0)
			(stroke
				(width 0.2032)
				(type default)
			)
			(layer "F.SilkS")
		)
		(fp_rect
			(start -0.5842 1.3335)
			(end 0.5842 -1.3335)
			(stroke
				(width 0)
				(type default)
			)
			(fill no)
			(layer "F.CrtYd")
		)
		(fp_rect
			(start -0.5842 1.3335)
			(end 0.5842 -1.3335)
			(stroke
				(width 0)
				(type default)
			)
			(fill no)
			(layer "F.Fab")
		)
		(pad "1" smd custom
			(at 0 -0.762 270)
			(size 0.2159 0.2159)
			(layers "F.Cu" "F.Mask" "F.Paste")
			(net "P5V_EN_R")
			(options
				(clearance outline)
				(anchor circle)
			)
			(primitives
				(gr_poly
					(pts
						(arc
							(start -0.3302 -0.4318)
							(mid -0.402042 -0.402042)
							(end -0.4318 -0.3302)
						)
						(arc
							(start -0.4318 0.3302)
							(mid -0.402042 0.402042)
							(end -0.3302 0.4318)
						)
						(arc
							(start 0.3302 0.4318)
							(mid 0.402042 0.402042)
							(end 0.4318 0.3302)
						)
						(arc
							(start 0.4318 -0.3302)
							(mid 0.402042 -0.402042)
							(end 0.3302 -0.4318)
						)
					)
					(width 0)
					(fill yes)
				)
			)
		)
		(pad "2" smd custom
			(at 0 0.762 270)
			(size 0.2159 0.2159)
			(layers "F.Cu" "F.Mask" "F.Paste")
			(net "GND")
			(options
				(clearance outline)
				(anchor circle)
			)
			(primitives
				(gr_poly
					(pts
						(arc
							(start -0.3302 -0.4318)
							(mid -0.402042 -0.402042)
							(end -0.4318 -0.3302)
						)
						(arc
							(start -0.4318 0.3302)
							(mid -0.402042 0.402042)
							(end -0.3302 0.4318)
						)
						(arc
							(start 0.3302 0.4318)
							(mid 0.402042 0.402042)
							(end 0.4318 0.3302)
						)
						(arc
							(start 0.4318 -0.3302)
							(mid 0.402042 -0.402042)
							(end 0.3302 -0.4318)
						)
					)
					(width 0)
					(fill yes)
				)
			)
		)
	)
	(footprint ""
		(layer "F.Cu")
		(at 112.84839 -5.577078 -90)
		(property "Reference" "R456"
			(at 0 0 270)
			(layer "F.SilkS")
			(hide yes)
			(effects
				(font
					(size 1.27 1.27)
				)
			)
		)
		(property "Value" "0R2J-2-GP"
			(at 0.064008 -3.993896 270)
			(unlocked yes)
			(layer "F.Fab")
			(hide yes)
			(effects
				(font
					(size 1.016 1.016)
					(thickness 0.1524)
				)
			)
		)
		(property "Device Type" "R402H16"
			(at 0.064008 -5.517896 270)
			(unlocked yes)
			(layer "F.Fab")
			(hide yes)
			(effects
				(font
					(size 1.016 1.016)
					(thickness 0.1524)
				)
			)
		)
		(duplicate_pad_numbers_are_jumpers no)
		(fp_line
			(start -0.508 -0.9398)
			(end -0.508 0.9398)
			(stroke
				(width 0.1524)
				(type default)
			)
			(layer "F.SilkS")
		)
		(fp_line
			(start 0.508 -0.9398)
			(end -0.508 -0.9398)
			(stroke
				(width 0.1524)
				(type default)
			)
			(layer "F.SilkS")
		)
		(fp_rect
			(start -0.508 0.9398)
			(end 0.508 -0.9398)
			(stroke
				(width 0)
				(type default)
			)
			(fill no)
			(layer "F.CrtYd")
		)
		(fp_rect
			(start -0.508 0.9398)
			(end 0.508 -0.9398)
			(stroke
				(width 0)
				(type default)
			)
			(fill no)
			(layer "F.Fab")
		)
		(pad "1" smd custom
			(at 0 -0.4445 270)
			(size 0.1397 0.1397)
			(layers "F.Cu" "F.Mask" "F.Paste")
			(net "MB0_SPISS_PD")
			(options
				(clearance outline)
				(anchor circle)
			)
			(primitives
				(gr_poly
					(pts
						(arc
							(start -0.1778 -0.2794)
							(mid -0.249642 -0.249642)
							(end -0.2794 -0.1778)
						)
						(arc
							(start -0.2794 0.1778)
							(mid -0.249642 0.249642)
							(end -0.1778 0.2794)
						)
						(arc
							(start 0.1778 0.2794)
							(mid 0.249642 0.249642)
							(end 0.2794 0.1778)
						)
						(arc
							(start 0.2794 -0.1778)
							(mid 0.249642 -0.249642)
							(end 0.1778 -0.2794)
						)
					)
					(width 0)
					(fill yes)
				)
			)
		)
		(pad "2" smd custom
			(at 0 0.4445 270)
			(size 0.1397 0.1397)
			(layers "F.Cu" "F.Mask" "F.Paste")
			(net "AGND_CURRENT_MON")
			(options
				(clearance outline)
				(anchor circle)
			)
			(primitives
				(gr_poly
					(pts
						(arc
							(start -0.1778 -0.2794)
							(mid -0.249642 -0.249642)
							(end -0.2794 -0.1778)
						)
						(arc
							(start -0.2794 0.1778)
							(mid -0.249642 0.249642)
							(end -0.1778 0.2794)
						)
						(arc
							(start 0.1778 0.2794)
							(mid 0.249642 0.249642)
							(end 0.2794 0.1778)
						)
						(arc
							(start 0.2794 -0.1778)
							(mid 0.249642 -0.249642)
							(end 0.1778 -0.2794)
						)
					)
					(width 0)
					(fill yes)
				)
			)
		)
	)
	(footprint ""
		(layer "F.Cu")
		(at 216.069672 -54.854856 -90)
		(property "Reference" "R470"
			(at 0 0 270)
			(layer "F.SilkS")
			(hide yes)
			(effects
				(font
					(size 1.27 1.27)
				)
			)
		)
		(property "Value" "200KR2F-L-GP"
			(at 0.064008 -3.993896 270)
			(unlocked yes)
			(layer "F.Fab")
			(hide yes)
			(effects
				(font
					(size 1.016 1.016)
					(thickness 0.1524)
				)
			)
		)
		(property "Device Type" "R402H16"
			(at 0.064008 -5.517896 270)
			(unlocked yes)
			(layer "F.Fab")
			(hide yes)
			(effects
				(font
					(size 1.016 1.016)
					(thickness 0.1524)
				)
			)
		)
		(duplicate_pad_numbers_are_jumpers no)
		(fp_line
			(start -0.508 -0.9398)
			(end -0.508 0.9398)
			(stroke
				(width 0.1524)
				(type default)
			)
			(layer "F.SilkS")
		)
		(fp_line
			(start 0.508 -0.9398)
			(end -0.508 -0.9398)
			(stroke
				(width 0.1524)
				(type default)
			)
			(layer "F.SilkS")
		)
		(fp_rect
			(start -0.508 0.9398)
			(end 0.508 -0.9398)
			(stroke
				(width 0)
				(type default)
			)
			(fill no)
			(layer "F.CrtYd")
		)
		(fp_rect
			(start -0.508 0.9398)
			(end 0.508 -0.9398)
			(stroke
				(width 0)
				(type default)
			)
			(fill no)
			(layer "F.Fab")
		)
		(pad "1" smd custom
			(at 0 -0.4445 270)
			(size 0.1397 0.1397)
			(layers "F.Cu" "F.Mask" "F.Paste")
			(net "P5V_MODE")
			(options
				(clearance outline)
				(anchor circle)
			)
			(primitives
				(gr_poly
					(pts
						(arc
							(start -0.1778 -0.2794)
							(mid -0.249642 -0.249642)
							(end -0.2794 -0.1778)
						)
						(arc
							(start -0.2794 0.1778)
							(mid -0.249642 0.249642)
							(end -0.1778 0.2794)
						)
						(arc
							(start 0.1778 0.2794)
							(mid 0.249642 0.249642)
							(end 0.2794 0.1778)
						)
						(arc
							(start 0.2794 -0.1778)
							(mid 0.249642 -0.249642)
							(end 0.1778 -0.2794)
						)
					)
					(width 0)
					(fill yes)
				)
			)
		)
		(pad "2" smd custom
			(at 0 0.4445 270)
			(size 0.1397 0.1397)
			(layers "F.Cu" "F.Mask" "F.Paste")
			(net "PWRGD_P5V_STBY")
			(options
				(clearance outline)
				(anchor circle)
			)
			(primitives
				(gr_poly
					(pts
						(arc
							(start -0.1778 -0.2794)
							(mid -0.249642 -0.249642)
							(end -0.2794 -0.1778)
						)
						(arc
							(start -0.2794 0.1778)
							(mid -0.249642 0.249642)
							(end -0.1778 0.2794)
						)
						(arc
							(start 0.1778 0.2794)
							(mid 0.249642 0.249642)
							(end 0.2794 0.1778)
						)
						(arc
							(start 0.2794 -0.1778)
							(mid 0.249642 -0.249642)
							(end 0.1778 -0.2794)
						)
					)
					(width 0)
					(fill yes)
				)
			)
		)
	)
	(footprint ""
		(layer "F.Cu")
		(at 46.450504 -161.231072 180)
		(property "Reference" "R179"
			(at 0 0 180)
			(layer "F.SilkS")
			(hide yes)
			(effects
				(font
					(size 1.27 1.27)
				)
			)
		)
		(property "Value" "2K2R2F-GP"
			(at 0.064008 -3.993896 180)
			(unlocked yes)
			(layer "F.Fab")
			(hide yes)
			(effects
				(font
					(size 1.016 1.016)
					(thickness 0.1524)
				)
			)
		)
		(property "Device Type" "R402H16"
			(at 0.064008 -5.517896 180)
			(unlocked yes)
			(layer "F.Fab")
			(hide yes)
			(effects
				(font
					(size 1.016 1.016)
					(thickness 0.1524)
				)
			)
		)
		(duplicate_pad_numbers_are_jumpers no)
		(fp_line
			(start 0.508 -0.9398)
			(end -0.508 -0.9398)
			(stroke
				(width 0.1524)
				(type default)
			)
			(layer "F.SilkS")
		)
		(fp_line
			(start -0.508 -0.9398)
			(end -0.508 0.9398)
			(stroke
				(width 0.1524)
				(type default)
			)
			(layer "F.SilkS")
		)
		(fp_rect
			(start -0.508 0.9398)
			(end 0.508 -0.9398)
			(stroke
				(width 0)
				(type default)
			)
			(fill no)
			(layer "F.CrtYd")
		)
		(fp_rect
			(start -0.508 0.9398)
			(end 0.508 -0.9398)
			(stroke
				(width 0)
				(type default)
			)
			(fill no)
			(layer "F.Fab")
		)
		(pad "1" smd custom
			(at 0 -0.4445 180)
			(size 0.1397 0.1397)
			(layers "F.Cu" "F.Mask" "F.Paste")
			(net "I2C_DPB_SCL_OUT")
			(options
				(clearance outline)
				(anchor circle)
			)
			(primitives
				(gr_poly
					(pts
						(arc
							(start -0.1778 -0.2794)
							(mid -0.249642 -0.249642)
							(end -0.2794 -0.1778)
						)
						(arc
							(start -0.2794 0.1778)
							(mid -0.249642 0.249642)
							(end -0.1778 0.2794)
						)
						(arc
							(start 0.1778 0.2794)
							(mid 0.249642 0.249642)
							(end 0.2794 0.1778)
						)
						(arc
							(start 0.2794 -0.1778)
							(mid 0.249642 -0.249642)
							(end 0.1778 -0.2794)
						)
					)
					(width 0)
					(fill yes)
				)
			)
		)
		(pad "2" smd custom
			(at 0 0.4445 180)
			(size 0.1397 0.1397)
			(layers "F.Cu" "F.Mask" "F.Paste")
			(net "P3V3_STBY")
			(options
				(clearance outline)
				(anchor circle)
			)
			(primitives
				(gr_poly
					(pts
						(arc
							(start -0.1778 -0.2794)
							(mid -0.249642 -0.249642)
							(end -0.2794 -0.1778)
						)
						(arc
							(start -0.2794 0.1778)
							(mid -0.249642 0.249642)
							(end -0.1778 0.2794)
						)
						(arc
							(start 0.1778 0.2794)
							(mid 0.249642 0.249642)
							(end 0.2794 0.1778)
						)
						(arc
							(start 0.2794 -0.1778)
							(mid 0.249642 -0.249642)
							(end 0.1778 -0.2794)
						)
					)
					(width 0)
					(fill yes)
				)
			)
		)
	)
	(footprint ""
		(layer "F.Cu")
		(at 10.791698 -141.008862 90)
		(property "Reference" "R228"
			(at 0 0 90)
			(layer "F.SilkS")
			(hide yes)
			(effects
				(font
					(size 1.27 1.27)
				)
			)
		)
		(property "Value" "120R2F-GP"
			(at 0.064008 -3.993896 90)
			(unlocked yes)
			(layer "F.Fab")
			(hide yes)
			(effects
				(font
					(size 1.016 1.016)
					(thickness 0.1524)
				)
			)
		)
		(property "Device Type" "R402H16"
			(at 0.064008 -5.517896 90)
			(unlocked yes)
			(layer "F.Fab")
			(hide yes)
			(effects
				(font
					(size 1.016 1.016)
					(thickness 0.1524)
				)
			)
		)
		(duplicate_pad_numbers_are_jumpers no)
		(fp_line
			(start 0.508 -0.9398)
			(end -0.508 -0.9398)
			(stroke
				(width 0.1524)
				(type default)
			)
			(layer "F.SilkS")
		)
		(fp_line
			(start -0.508 -0.9398)
			(end -0.508 0.9398)
			(stroke
				(width 0.1524)
				(type default)
			)
			(layer "F.SilkS")
		)
		(fp_rect
			(start -0.508 0.9398)
			(end 0.508 -0.9398)
			(stroke
				(width 0)
				(type default)
			)
			(fill no)
			(layer "F.CrtYd")
		)
		(fp_rect
			(start -0.508 0.9398)
			(end 0.508 -0.9398)
			(stroke
				(width 0)
				(type default)
			)
			(fill no)
			(layer "F.Fab")
		)
		(pad "1" smd custom
			(at 0 -0.4445 90)
			(size 0.1397 0.1397)
			(layers "F.Cu" "F.Mask" "F.Paste")
			(net "MEMWEN")
			(options
				(clearance outline)
				(anchor circle)
			)
			(primitives
				(gr_poly
					(pts
						(arc
							(start -0.1778 -0.2794)
							(mid -0.249642 -0.249642)
							(end -0.2794 -0.1778)
						)
						(arc
							(start -0.2794 0.1778)
							(mid -0.249642 0.249642)
							(end -0.1778 0.2794)
						)
						(arc
							(start 0.1778 0.2794)
							(mid 0.249642 0.249642)
							(end 0.2794 0.1778)
						)
						(arc
							(start 0.2794 -0.1778)
							(mid 0.249642 -0.249642)
							(end 0.1778 -0.2794)
						)
					)
					(width 0)
					(fill yes)
				)
			)
		)
		(pad "2" smd custom
			(at 0 0.4445 90)
			(size 0.1397 0.1397)
			(layers "F.Cu" "F.Mask" "F.Paste")
			(net "P1V2_STBY")
			(options
				(clearance outline)
				(anchor circle)
			)
			(primitives
				(gr_poly
					(pts
						(arc
							(start -0.1778 -0.2794)
							(mid -0.249642 -0.249642)
							(end -0.2794 -0.1778)
						)
						(arc
							(start -0.2794 0.1778)
							(mid -0.249642 0.249642)
							(end -0.1778 0.2794)
						)
						(arc
							(start 0.1778 0.2794)
							(mid 0.249642 0.249642)
							(end 0.2794 0.1778)
						)
						(arc
							(start 0.2794 -0.1778)
							(mid 0.249642 -0.249642)
							(end 0.1778 -0.2794)
						)
					)
					(width 0)
					(fill yes)
				)
			)
		)
	)
	(footprint ""
		(layer "F.Cu")
		(at 125.203712 -15.532354 -90)
		(property "Reference" "PQ1"
			(at 0 0 270)
			(layer "F.SilkS")
			(hide yes)
			(effects
				(font
					(size 1.27 1.27)
				)
			)
		)
		(property "Value" "MMBT3904-3-GP"
			(at 0.10287 -10.29843 270)
			(unlocked yes)
			(layer "F.Fab")
			(hide yes)
			(effects
				(font
					(size 1.016 1.016)
					(thickness 0.1524)
				)
			)
		)
		(property "Device Type" "SOT23CBE2D4H44"
			(at 0.10287 -12.20343 270)
			(unlocked yes)
			(layer "F.Fab")
			(hide yes)
			(effects
				(font
					(size 1.016 1.016)
					(thickness 0.1524)
				)
			)
		)
		(duplicate_pad_numbers_are_jumpers no)
		(fp_line
			(start -1.651 1.778)
			(end 1.651 1.778)
			(stroke
				(width 0.1524)
				(type default)
			)
			(layer "F.SilkS")
		)
		(fp_line
			(start 1.651 1.778)
			(end 1.651 -1.778)
			(stroke
				(width 0.1524)
				(type default)
			)
			(layer "F.SilkS")
		)
		(fp_line
			(start -1.651 -1.778)
			(end -1.651 1.778)
			(stroke
				(width 0.1524)
				(type default)
			)
			(layer "F.SilkS")
		)
		(fp_line
			(start 1.651 -1.778)
			(end -1.651 -1.778)
			(stroke
				(width 0.1524)
				(type default)
			)
			(layer "F.SilkS")
		)
		(fp_poly
			(pts
				(xy -1.778 1.8796) (xy -1.778 -1.8796) (xy 1.778 -1.8796) (xy 1.778 1.8796)
			)
			(stroke
				(width 0)
				(type default)
			)
			(fill no)
			(layer "F.CrtYd")
		)
		(fp_poly
			(pts
				(xy -1.778 1.8796) (xy -1.778 -1.8796) (xy 1.778 -1.8796) (xy 1.778 1.8796)
			)
			(stroke
				(width 0)
				(type default)
			)
			(fill no)
			(layer "F.Fab")
		)
		(pad "B" smd custom
			(at -0.98425 0.9525 270)
			(size 0.1905 0.1905)
			(layers "F.Cu" "F.Mask" "F.Paste")
			(net "MB0_TEMP_C")
			(options
				(clearance outline)
				(anchor circle)
			)
			(primitives
				(gr_poly
					(pts
						(arc
							(start -0.1778 0.5715)
							(mid -0.321484 0.511984)
							(end -0.381 0.3683)
						)
						(arc
							(start -0.381 -0.3683)
							(mid -0.321484 -0.511984)
							(end -0.1778 -0.5715)
						)
						(arc
							(start 0.1778 -0.5715)
							(mid 0.321484 -0.511984)
							(end 0.381 -0.3683)
						)
						(arc
							(start 0.381 0.3683)
							(mid 0.321484 0.511984)
							(end 0.1778 0.5715)
						)
					)
					(width 0)
					(fill yes)
				)
			)
		)
		(pad "C" smd custom
			(at 0 -0.9525 270)
			(size 0.1905 0.1905)
			(layers "F.Cu" "F.Mask" "F.Paste")
			(net "MB0_TEMP_C")
			(options
				(clearance outline)
				(anchor circle)
			)
			(primitives
				(gr_poly
					(pts
						(arc
							(start -0.1778 0.5715)
							(mid -0.321484 0.511984)
							(end -0.381 0.3683)
						)
						(arc
							(start -0.381 -0.3683)
							(mid -0.321484 -0.511984)
							(end -0.1778 -0.5715)
						)
						(arc
							(start 0.1778 -0.5715)
							(mid 0.321484 -0.511984)
							(end 0.381 -0.3683)
						)
						(arc
							(start 0.381 0.3683)
							(mid 0.321484 0.511984)
							(end 0.1778 0.5715)
						)
					)
					(width 0)
					(fill yes)
				)
			)
		)
		(pad "E" smd custom
			(at 0.98425 0.9525 270)
			(size 0.1905 0.1905)
			(layers "F.Cu" "F.Mask" "F.Paste")
			(net "MB0_TEMP_E")
			(options
				(clearance outline)
				(anchor circle)
			)
			(primitives
				(gr_poly
					(pts
						(arc
							(start -0.1778 0.5715)
							(mid -0.321484 0.511984)
							(end -0.381 0.3683)
						)
						(arc
							(start -0.381 -0.3683)
							(mid -0.321484 -0.511984)
							(end -0.1778 -0.5715)
						)
						(arc
							(start 0.1778 -0.5715)
							(mid 0.321484 -0.511984)
							(end 0.381 -0.3683)
						)
						(arc
							(start 0.381 0.3683)
							(mid 0.321484 0.511984)
							(end 0.1778 0.5715)
						)
					)
					(width 0)
					(fill yes)
				)
			)
		)
	)
	(footprint ""
		(layer "F.Cu")
		(at 214.999824 -90.362278)
		(property "Reference" "R826"
			(at 0 0 0)
			(layer "F.SilkS")
			(hide yes)
			(effects
				(font
					(size 1.27 1.27)
				)
			)
		)
		(property "Value" "10KR2F-2-GP"
			(at 0.064008 -3.993896 0)
			(unlocked yes)
			(layer "F.Fab")
			(hide yes)
			(effects
				(font
					(size 1.016 1.016)
					(thickness 0.1524)
				)
			)
		)
		(property "Device Type" "R402H16"
			(at 0.064008 -5.517896 0)
			(unlocked yes)
			(layer "F.Fab")
			(hide yes)
			(effects
				(font
					(size 1.016 1.016)
					(thickness 0.1524)
				)
			)
		)
		(duplicate_pad_numbers_are_jumpers no)
		(fp_line
			(start -0.508 -0.9398)
			(end -0.508 0.9398)
			(stroke
				(width 0.1524)
				(type default)
			)
			(layer "F.SilkS")
		)
		(fp_line
			(start 0.508 -0.9398)
			(end -0.508 -0.9398)
			(stroke
				(width 0.1524)
				(type default)
			)
			(layer "F.SilkS")
		)
		(fp_rect
			(start -0.508 0.9398)
			(end 0.508 -0.9398)
			(stroke
				(width 0)
				(type default)
			)
			(fill no)
			(layer "F.CrtYd")
		)
		(fp_rect
			(start -0.508 0.9398)
			(end 0.508 -0.9398)
			(stroke
				(width 0)
				(type default)
			)
			(fill no)
			(layer "F.Fab")
		)
		(pad "1" smd custom
			(at 0 -0.4445)
			(size 0.1397 0.1397)
			(layers "F.Cu" "F.Mask" "F.Paste")
			(net "IOM_FULL_PGOOD")
			(options
				(clearance outline)
				(anchor circle)
			)
			(primitives
				(gr_poly
					(pts
						(arc
							(start -0.1778 -0.2794)
							(mid -0.249642 -0.249642)
							(end -0.2794 -0.1778)
						)
						(arc
							(start -0.2794 0.1778)
							(mid -0.249642 0.249642)
							(end -0.1778 0.2794)
						)
						(arc
							(start 0.1778 0.2794)
							(mid 0.249642 0.249642)
							(end 0.2794 0.1778)
						)
						(arc
							(start 0.2794 -0.1778)
							(mid 0.249642 -0.249642)
							(end 0.1778 -0.2794)
						)
					)
					(width 0)
					(fill yes)
				)
			)
		)
		(pad "2" smd custom
			(at 0 0.4445)
			(size 0.1397 0.1397)
			(layers "F.Cu" "F.Mask" "F.Paste")
			(net "P3V3_M2_VREG")
			(options
				(clearance outline)
				(anchor circle)
			)
			(primitives
				(gr_poly
					(pts
						(arc
							(start -0.1778 -0.2794)
							(mid -0.249642 -0.249642)
							(end -0.2794 -0.1778)
						)
						(arc
							(start -0.2794 0.1778)
							(mid -0.249642 0.249642)
							(end -0.1778 0.2794)
						)
						(arc
							(start 0.1778 0.2794)
							(mid 0.249642 0.249642)
							(end 0.2794 0.1778)
						)
						(arc
							(start 0.2794 -0.1778)
							(mid 0.249642 -0.249642)
							(end 0.1778 -0.2794)
						)
					)
					(width 0)
					(fill yes)
				)
			)
		)
	)
	(footprint ""
		(layer "F.Cu")
		(at 53.34 -159.2326 90)
		(property "Reference" "C85"
			(at 0 0 90)
			(layer "F.SilkS")
			(hide yes)
			(effects
				(font
					(size 1.27 1.27)
				)
			)
		)
		(property "Value" "SCD1U16V2KX-3GP"
			(at 1.1811 -2.7051 90)
			(unlocked yes)
			(layer "F.Fab")
			(hide yes)
			(effects
				(font
					(size 1.016 1.016)
					(thickness 0.1524)
				)
			)
		)
		(property "Device Type" "C402H22"
			(at 1.1811 -4.2291 90)
			(unlocked yes)
			(layer "F.Fab")
			(hide yes)
			(effects
				(font
					(size 1.016 1.016)
					(thickness 0.1524)
				)
			)
		)
		(duplicate_pad_numbers_are_jumpers no)
		(fp_rect
			(start -0.4318 0.9525)
			(end 0.4318 -0.9525)
			(stroke
				(width 0)
				(type default)
			)
			(fill no)
			(layer "F.CrtYd")
		)
		(fp_rect
			(start -0.4318 0.9525)
			(end 0.4318 -0.9525)
			(stroke
				(width 0)
				(type default)
			)
			(fill no)
			(layer "F.Fab")
		)
		(pad "1" smd custom
			(at 0 -0.4445 90)
			(size 0.1524 0.1524)
			(layers "F.Cu" "F.Mask" "F.Paste")
			(net "GND")
			(options
				(clearance outline)
				(anchor circle)
			)
			(primitives
				(gr_poly
					(pts
						(arc
							(start 0.3048 -0.2032)
							(mid 0.275042 -0.275042)
							(end 0.2032 -0.3048)
						)
						(arc
							(start -0.2032 -0.3048)
							(mid -0.275042 -0.275042)
							(end -0.3048 -0.2032)
						)
						(arc
							(start -0.3048 0.2032)
							(mid -0.275042 0.275042)
							(end -0.2032 0.3048)
						)
						(arc
							(start 0.2032 0.3048)
							(mid 0.275042 0.275042)
							(end 0.3048 0.2032)
						)
					)
					(width 0)
					(fill yes)
				)
			)
		)
		(pad "2" smd custom
			(at 0 0.4445 90)
			(size 0.1524 0.1524)
			(layers "F.Cu" "F.Mask" "F.Paste")
			(net "ADCVREFFN")
			(options
				(clearance outline)
				(anchor circle)
			)
			(primitives
				(gr_poly
					(pts
						(arc
							(start 0.3048 -0.2032)
							(mid 0.275042 -0.275042)
							(end 0.2032 -0.3048)
						)
						(arc
							(start -0.2032 -0.3048)
							(mid -0.275042 -0.275042)
							(end -0.3048 -0.2032)
						)
						(arc
							(start -0.3048 0.2032)
							(mid -0.275042 0.275042)
							(end -0.2032 0.3048)
						)
						(arc
							(start 0.2032 0.3048)
							(mid 0.275042 0.275042)
							(end 0.3048 0.2032)
						)
					)
					(width 0)
					(fill yes)
				)
			)
		)
	)
	(footprint ""
		(layer "F.Cu")
		(at 134.4422 -13.880592 -90)
		(property "Reference" "R442"
			(at 0 0 270)
			(layer "F.SilkS")
			(hide yes)
			(effects
				(font
					(size 1.27 1.27)
				)
			)
		)
		(property "Value" "10R2F-L-GP"
			(at 0.064008 -3.993896 270)
			(unlocked yes)
			(layer "F.Fab")
			(hide yes)
			(effects
				(font
					(size 1.016 1.016)
					(thickness 0.1524)
				)
			)
		)
		(property "Device Type" "R402H14"
			(at 0.064008 -5.517896 270)
			(unlocked yes)
			(layer "F.Fab")
			(hide yes)
			(effects
				(font
					(size 1.016 1.016)
					(thickness 0.1524)
				)
			)
		)
		(duplicate_pad_numbers_are_jumpers no)
		(fp_line
			(start -0.508 -0.9398)
			(end -0.508 0.9398)
			(stroke
				(width 0.1524)
				(type default)
			)
			(layer "F.SilkS")
		)
		(fp_line
			(start 0.508 -0.9398)
			(end -0.508 -0.9398)
			(stroke
				(width 0.1524)
				(type default)
			)
			(layer "F.SilkS")
		)
		(fp_rect
			(start -0.508 0.9398)
			(end 0.508 -0.9398)
			(stroke
				(width 0)
				(type default)
			)
			(fill no)
			(layer "F.CrtYd")
		)
		(fp_rect
			(start -0.508 0.9398)
			(end 0.508 -0.9398)
			(stroke
				(width 0)
				(type default)
			)
			(fill no)
			(layer "F.Fab")
		)
		(pad "1" smd custom
			(at 0 -0.4445 270)
			(size 0.1397 0.1397)
			(layers "F.Cu" "F.Mask" "F.Paste")
			(net "MB0_CM_SENSE_R1_P")
			(options
				(clearance outline)
				(anchor circle)
			)
			(primitives
				(gr_poly
					(pts
						(arc
							(start -0.1778 -0.2794)
							(mid -0.249642 -0.249642)
							(end -0.2794 -0.1778)
						)
						(arc
							(start -0.2794 0.1778)
							(mid -0.249642 0.249642)
							(end -0.1778 0.2794)
						)
						(arc
							(start 0.1778 0.2794)
							(mid 0.249642 0.249642)
							(end 0.2794 0.1778)
						)
						(arc
							(start 0.2794 -0.1778)
							(mid 0.249642 -0.249642)
							(end 0.1778 -0.2794)
						)
					)
					(width 0)
					(fill yes)
				)
			)
		)
		(pad "2" smd custom
			(at 0 0.4445 270)
			(size 0.1397 0.1397)
			(layers "F.Cu" "F.Mask" "F.Paste")
			(net "ADM1278_HS_P")
			(options
				(clearance outline)
				(anchor circle)
			)
			(primitives
				(gr_poly
					(pts
						(arc
							(start -0.1778 -0.2794)
							(mid -0.249642 -0.249642)
							(end -0.2794 -0.1778)
						)
						(arc
							(start -0.2794 0.1778)
							(mid -0.249642 0.249642)
							(end -0.1778 0.2794)
						)
						(arc
							(start 0.1778 0.2794)
							(mid 0.249642 0.249642)
							(end 0.2794 0.1778)
						)
						(arc
							(start 0.2794 -0.1778)
							(mid 0.249642 -0.249642)
							(end 0.1778 -0.2794)
						)
					)
					(width 0)
					(fill yes)
				)
			)
		)
	)
	(footprint ""
		(layer "F.Cu")
		(at 74.718418 -148.365972 180)
		(property "Reference" "C76"
			(at 0 0 180)
			(layer "F.SilkS")
			(hide yes)
			(effects
				(font
					(size 1.27 1.27)
				)
			)
		)
		(property "Value" "SCD01U25V2KX-3GP"
			(at 1.1811 -2.7051 180)
			(unlocked yes)
			(layer "F.Fab")
			(hide yes)
			(effects
				(font
					(size 1.016 1.016)
					(thickness 0.1524)
				)
			)
		)
		(property "Device Type" "C402H22"
			(at 1.1811 -4.2291 180)
			(unlocked yes)
			(layer "F.Fab")
			(hide yes)
			(effects
				(font
					(size 1.016 1.016)
					(thickness 0.1524)
				)
			)
		)
		(duplicate_pad_numbers_are_jumpers no)
		(fp_rect
			(start -0.4318 0.9525)
			(end 0.4318 -0.9525)
			(stroke
				(width 0)
				(type default)
			)
			(fill no)
			(layer "F.CrtYd")
		)
		(fp_rect
			(start -0.4318 0.9525)
			(end 0.4318 -0.9525)
			(stroke
				(width 0)
				(type default)
			)
			(fill no)
			(layer "F.Fab")
		)
		(pad "1" smd custom
			(at 0 -0.4445 180)
			(size 0.1524 0.1524)
			(layers "F.Cu" "F.Mask" "F.Paste")
			(net "P3V3_STBY")
			(options
				(clearance outline)
				(anchor circle)
			)
			(primitives
				(gr_poly
					(pts
						(arc
							(start 0.3048 -0.2032)
							(mid 0.275042 -0.275042)
							(end 0.2032 -0.3048)
						)
						(arc
							(start -0.2032 -0.3048)
							(mid -0.275042 -0.275042)
							(end -0.3048 -0.2032)
						)
						(arc
							(start -0.3048 0.2032)
							(mid -0.275042 0.275042)
							(end -0.2032 0.3048)
						)
						(arc
							(start 0.2032 0.3048)
							(mid 0.275042 0.275042)
							(end 0.3048 0.2032)
						)
					)
					(width 0)
					(fill yes)
				)
			)
		)
		(pad "2" smd custom
			(at 0 0.4445 180)
			(size 0.1524 0.1524)
			(layers "F.Cu" "F.Mask" "F.Paste")
			(net "GND")
			(options
				(clearance outline)
				(anchor circle)
			)
			(primitives
				(gr_poly
					(pts
						(arc
							(start 0.3048 -0.2032)
							(mid 0.275042 -0.275042)
							(end 0.2032 -0.3048)
						)
						(arc
							(start -0.2032 -0.3048)
							(mid -0.275042 -0.275042)
							(end -0.3048 -0.2032)
						)
						(arc
							(start -0.3048 0.2032)
							(mid -0.275042 0.275042)
							(end -0.2032 0.3048)
						)
						(arc
							(start 0.2032 0.3048)
							(mid 0.275042 0.275042)
							(end 0.3048 0.2032)
						)
					)
					(width 0)
					(fill yes)
				)
			)
		)
	)
	(footprint ""
		(layer "F.Cu")
		(at 182.884318 -121.136156 180)
		(property "Reference" "R806"
			(at 0 0 180)
			(layer "F.SilkS")
			(hide yes)
			(effects
				(font
					(size 1.27 1.27)
				)
			)
		)
		(property "Value" "4K7R2F-GP"
			(at 0.064008 -3.993896 180)
			(unlocked yes)
			(layer "F.Fab")
			(hide yes)
			(effects
				(font
					(size 1.016 1.016)
					(thickness 0.1524)
				)
			)
		)
		(property "Device Type" "R402H16"
			(at 0.064008 -5.517896 180)
			(unlocked yes)
			(layer "F.Fab")
			(hide yes)
			(effects
				(font
					(size 1.016 1.016)
					(thickness 0.1524)
				)
			)
		)
		(duplicate_pad_numbers_are_jumpers no)
		(fp_line
			(start 0.508 -0.9398)
			(end -0.508 -0.9398)
			(stroke
				(width 0.1524)
				(type default)
			)
			(layer "F.SilkS")
		)
		(fp_line
			(start -0.508 -0.9398)
			(end -0.508 0.9398)
			(stroke
				(width 0.1524)
				(type default)
			)
			(layer "F.SilkS")
		)
		(fp_rect
			(start -0.508 0.9398)
			(end 0.508 -0.9398)
			(stroke
				(width 0)
				(type default)
			)
			(fill no)
			(layer "F.CrtYd")
		)
		(fp_rect
			(start -0.508 0.9398)
			(end 0.508 -0.9398)
			(stroke
				(width 0)
				(type default)
			)
			(fill no)
			(layer "F.Fab")
		)
		(pad "1" smd custom
			(at 0 -0.4445 180)
			(size 0.1397 0.1397)
			(layers "F.Cu" "F.Mask" "F.Paste")
			(net "P3V3_M2")
			(options
				(clearance outline)
				(anchor circle)
			)
			(primitives
				(gr_poly
					(pts
						(arc
							(start -0.1778 -0.2794)
							(mid -0.249642 -0.249642)
							(end -0.2794 -0.1778)
						)
						(arc
							(start -0.2794 0.1778)
							(mid -0.249642 0.249642)
							(end -0.1778 0.2794)
						)
						(arc
							(start 0.1778 0.2794)
							(mid 0.249642 0.249642)
							(end 0.2794 0.1778)
						)
						(arc
							(start 0.2794 -0.1778)
							(mid 0.249642 -0.249642)
							(end 0.1778 -0.2794)
						)
					)
					(width 0)
					(fill yes)
				)
			)
		)
		(pad "2" smd custom
			(at 0 0.4445 180)
			(size 0.1397 0.1397)
			(layers "F.Cu" "F.Mask" "F.Paste")
			(net "M2_2_CLKREQ#")
			(options
				(clearance outline)
				(anchor circle)
			)
			(primitives
				(gr_poly
					(pts
						(arc
							(start -0.1778 -0.2794)
							(mid -0.249642 -0.249642)
							(end -0.2794 -0.1778)
						)
						(arc
							(start -0.2794 0.1778)
							(mid -0.249642 0.249642)
							(end -0.1778 0.2794)
						)
						(arc
							(start 0.1778 0.2794)
							(mid 0.249642 0.249642)
							(end 0.2794 0.1778)
						)
						(arc
							(start 0.2794 -0.1778)
							(mid 0.249642 -0.249642)
							(end 0.1778 -0.2794)
						)
					)
					(width 0)
					(fill yes)
				)
			)
		)
	)
	(footprint ""
		(layer "F.Cu")
		(at 88.788494 -128.989074 90)
		(property "Reference" "R420"
			(at 0 0 90)
			(layer "F.SilkS")
			(hide yes)
			(effects
				(font
					(size 1.27 1.27)
				)
			)
		)
		(property "Value" "4K7R2F-GP"
			(at 0.064008 -3.993896 90)
			(unlocked yes)
			(layer "F.Fab")
			(hide yes)
			(effects
				(font
					(size 1.016 1.016)
					(thickness 0.1524)
				)
			)
		)
		(property "Device Type" "R402H16"
			(at 0.064008 -5.517896 90)
			(unlocked yes)
			(layer "F.Fab")
			(hide yes)
			(effects
				(font
					(size 1.016 1.016)
					(thickness 0.1524)
				)
			)
		)
		(duplicate_pad_numbers_are_jumpers no)
		(fp_line
			(start 0.508 -0.9398)
			(end -0.508 -0.9398)
			(stroke
				(width 0.1524)
				(type default)
			)
			(layer "F.SilkS")
		)
		(fp_line
			(start -0.508 -0.9398)
			(end -0.508 0.9398)
			(stroke
				(width 0.1524)
				(type default)
			)
			(layer "F.SilkS")
		)
		(fp_rect
			(start -0.508 0.9398)
			(end 0.508 -0.9398)
			(stroke
				(width 0)
				(type default)
			)
			(fill no)
			(layer "F.CrtYd")
		)
		(fp_rect
			(start -0.508 0.9398)
			(end 0.508 -0.9398)
			(stroke
				(width 0)
				(type default)
			)
			(fill no)
			(layer "F.Fab")
		)
		(pad "1" smd custom
			(at 0 -0.4445 90)
			(size 0.1397 0.1397)
			(layers "F.Cu" "F.Mask" "F.Paste")
			(net "P3V3_STBY")
			(options
				(clearance outline)
				(anchor circle)
			)
			(primitives
				(gr_poly
					(pts
						(arc
							(start -0.1778 -0.2794)
							(mid -0.249642 -0.249642)
							(end -0.2794 -0.1778)
						)
						(arc
							(start -0.2794 0.1778)
							(mid -0.249642 0.249642)
							(end -0.1778 0.2794)
						)
						(arc
							(start 0.1778 0.2794)
							(mid 0.249642 0.249642)
							(end 0.2794 0.1778)
						)
						(arc
							(start 0.2794 -0.1778)
							(mid 0.249642 -0.249642)
							(end 0.1778 -0.2794)
						)
					)
					(width 0)
					(fill yes)
				)
			)
		)
		(pad "2" smd custom
			(at 0 0.4445 90)
			(size 0.1397 0.1397)
			(layers "F.Cu" "F.Mask" "F.Paste")
			(net "UART_SEL_MUX")
			(options
				(clearance outline)
				(anchor circle)
			)
			(primitives
				(gr_poly
					(pts
						(arc
							(start -0.1778 -0.2794)
							(mid -0.249642 -0.249642)
							(end -0.2794 -0.1778)
						)
						(arc
							(start -0.2794 0.1778)
							(mid -0.249642 0.249642)
							(end -0.1778 0.2794)
						)
						(arc
							(start 0.1778 0.2794)
							(mid 0.249642 0.249642)
							(end 0.2794 0.1778)
						)
						(arc
							(start 0.2794 -0.1778)
							(mid 0.249642 -0.249642)
							(end 0.1778 -0.2794)
						)
					)
					(width 0)
					(fill yes)
				)
			)
		)
	)
	(footprint ""
		(layer "F.Cu")
		(at 60.849002 -136.942068 -90)
		(property "Reference" "R354"
			(at 0 0 270)
			(layer "F.SilkS")
			(hide yes)
			(effects
				(font
					(size 1.27 1.27)
				)
			)
		)
		(property "Value" "4K7R2F-GP"
			(at 0.064008 -3.993896 270)
			(unlocked yes)
			(layer "F.Fab")
			(hide yes)
			(effects
				(font
					(size 1.016 1.016)
					(thickness 0.1524)
				)
			)
		)
		(property "Device Type" "R402H16"
			(at 0.064008 -5.517896 270)
			(unlocked yes)
			(layer "F.Fab")
			(hide yes)
			(effects
				(font
					(size 1.016 1.016)
					(thickness 0.1524)
				)
			)
		)
		(duplicate_pad_numbers_are_jumpers no)
		(fp_line
			(start -0.508 -0.9398)
			(end -0.508 0.9398)
			(stroke
				(width 0.1524)
				(type default)
			)
			(layer "F.SilkS")
		)
		(fp_line
			(start 0.508 -0.9398)
			(end -0.508 -0.9398)
			(stroke
				(width 0.1524)
				(type default)
			)
			(layer "F.SilkS")
		)
		(fp_rect
			(start -0.508 0.9398)
			(end 0.508 -0.9398)
			(stroke
				(width 0)
				(type default)
			)
			(fill no)
			(layer "F.CrtYd")
		)
		(fp_rect
			(start -0.508 0.9398)
			(end 0.508 -0.9398)
			(stroke
				(width 0)
				(type default)
			)
			(fill no)
			(layer "F.Fab")
		)
		(pad "1" smd custom
			(at 0 -0.4445 270)
			(size 0.1397 0.1397)
			(layers "F.Cu" "F.Mask" "F.Paste")
			(net "SLOTID_0")
			(options
				(clearance outline)
				(anchor circle)
			)
			(primitives
				(gr_poly
					(pts
						(arc
							(start -0.1778 -0.2794)
							(mid -0.249642 -0.249642)
							(end -0.2794 -0.1778)
						)
						(arc
							(start -0.2794 0.1778)
							(mid -0.249642 0.249642)
							(end -0.1778 0.2794)
						)
						(arc
							(start 0.1778 0.2794)
							(mid 0.249642 0.249642)
							(end 0.2794 0.1778)
						)
						(arc
							(start 0.2794 -0.1778)
							(mid 0.249642 -0.249642)
							(end 0.1778 -0.2794)
						)
					)
					(width 0)
					(fill yes)
				)
			)
		)
		(pad "2" smd custom
			(at 0 0.4445 270)
			(size 0.1397 0.1397)
			(layers "F.Cu" "F.Mask" "F.Paste")
			(net "GND")
			(options
				(clearance outline)
				(anchor circle)
			)
			(primitives
				(gr_poly
					(pts
						(arc
							(start -0.1778 -0.2794)
							(mid -0.249642 -0.249642)
							(end -0.2794 -0.1778)
						)
						(arc
							(start -0.2794 0.1778)
							(mid -0.249642 0.249642)
							(end -0.1778 0.2794)
						)
						(arc
							(start 0.1778 0.2794)
							(mid 0.249642 0.249642)
							(end 0.2794 0.1778)
						)
						(arc
							(start 0.2794 -0.1778)
							(mid 0.249642 -0.249642)
							(end 0.1778 -0.2794)
						)
					)
					(width 0)
					(fill yes)
				)
			)
		)
	)
	(footprint ""
		(layer "F.Cu")
		(at 31.2674 -162.7378 180)
		(property "Reference" "C103"
			(at 0 0 180)
			(layer "F.SilkS")
			(hide yes)
			(effects
				(font
					(size 1.27 1.27)
				)
			)
		)
		(property "Value" "SCD1U16V2KX-3GP"
			(at 1.1811 -2.7051 180)
			(unlocked yes)
			(layer "F.Fab")
			(hide yes)
			(effects
				(font
					(size 1.016 1.016)
					(thickness 0.1524)
				)
			)
		)
		(property "Device Type" "C402H22"
			(at 1.1811 -4.2291 180)
			(unlocked yes)
			(layer "F.Fab")
			(hide yes)
			(effects
				(font
					(size 1.016 1.016)
					(thickness 0.1524)
				)
			)
		)
		(duplicate_pad_numbers_are_jumpers no)
		(fp_rect
			(start -0.4318 0.9525)
			(end 0.4318 -0.9525)
			(stroke
				(width 0)
				(type default)
			)
			(fill no)
			(layer "F.CrtYd")
		)
		(fp_rect
			(start -0.4318 0.9525)
			(end 0.4318 -0.9525)
			(stroke
				(width 0)
				(type default)
			)
			(fill no)
			(layer "F.Fab")
		)
		(pad "1" smd custom
			(at 0 -0.4445 180)
			(size 0.1524 0.1524)
			(layers "F.Cu" "F.Mask" "F.Paste")
			(net "V1PLLAV11")
			(options
				(clearance outline)
				(anchor circle)
			)
			(primitives
				(gr_poly
					(pts
						(arc
							(start 0.3048 -0.2032)
							(mid 0.275042 -0.275042)
							(end 0.2032 -0.3048)
						)
						(arc
							(start -0.2032 -0.3048)
							(mid -0.275042 -0.275042)
							(end -0.3048 -0.2032)
						)
						(arc
							(start -0.3048 0.2032)
							(mid -0.275042 0.275042)
							(end -0.2032 0.3048)
						)
						(arc
							(start 0.2032 0.3048)
							(mid 0.275042 0.275042)
							(end 0.3048 0.2032)
						)
					)
					(width 0)
					(fill yes)
				)
			)
		)
		(pad "2" smd custom
			(at 0 0.4445 180)
			(size 0.1524 0.1524)
			(layers "F.Cu" "F.Mask" "F.Paste")
			(net "GND")
			(options
				(clearance outline)
				(anchor circle)
			)
			(primitives
				(gr_poly
					(pts
						(arc
							(start 0.3048 -0.2032)
							(mid 0.275042 -0.275042)
							(end 0.2032 -0.3048)
						)
						(arc
							(start -0.2032 -0.3048)
							(mid -0.275042 -0.275042)
							(end -0.3048 -0.2032)
						)
						(arc
							(start -0.3048 0.2032)
							(mid -0.275042 0.275042)
							(end -0.2032 0.3048)
						)
						(arc
							(start 0.2032 0.3048)
							(mid 0.275042 0.275042)
							(end 0.3048 0.2032)
						)
					)
					(width 0)
					(fill yes)
				)
			)
		)
	)
	(footprint ""
		(layer "F.Cu")
		(at 98.414332 -18.402046 180)
		(property "Reference" "R46"
			(at 0 0 180)
			(layer "F.SilkS")
			(hide yes)
			(effects
				(font
					(size 1.27 1.27)
				)
			)
		)
		(property "Value" "0R2J-2-GP"
			(at 0.064008 -3.993896 180)
			(unlocked yes)
			(layer "F.Fab")
			(hide yes)
			(effects
				(font
					(size 1.016 1.016)
					(thickness 0.1524)
				)
			)
		)
		(property "Device Type" "R402H16"
			(at 0.064008 -5.517896 180)
			(unlocked yes)
			(layer "F.Fab")
			(hide yes)
			(effects
				(font
					(size 1.016 1.016)
					(thickness 0.1524)
				)
			)
		)
		(duplicate_pad_numbers_are_jumpers no)
		(fp_line
			(start 0.508 -0.9398)
			(end -0.508 -0.9398)
			(stroke
				(width 0.1524)
				(type default)
			)
			(layer "F.SilkS")
		)
		(fp_line
			(start -0.508 -0.9398)
			(end -0.508 0.9398)
			(stroke
				(width 0.1524)
				(type default)
			)
			(layer "F.SilkS")
		)
		(fp_rect
			(start -0.508 0.9398)
			(end 0.508 -0.9398)
			(stroke
				(width 0)
				(type default)
			)
			(fill no)
			(layer "F.CrtYd")
		)
		(fp_rect
			(start -0.508 0.9398)
			(end 0.508 -0.9398)
			(stroke
				(width 0)
				(type default)
			)
			(fill no)
			(layer "F.Fab")
		)
		(pad "1" smd custom
			(at 0 -0.4445 180)
			(size 0.1397 0.1397)
			(layers "F.Cu" "F.Mask" "F.Paste")
			(net "USB_P1_F_DN1")
			(options
				(clearance outline)
				(anchor circle)
			)
			(primitives
				(gr_poly
					(pts
						(arc
							(start -0.1778 -0.2794)
							(mid -0.249642 -0.249642)
							(end -0.2794 -0.1778)
						)
						(arc
							(start -0.2794 0.1778)
							(mid -0.249642 0.249642)
							(end -0.1778 0.2794)
						)
						(arc
							(start 0.1778 0.2794)
							(mid 0.249642 0.249642)
							(end 0.2794 0.1778)
						)
						(arc
							(start 0.2794 -0.1778)
							(mid 0.249642 -0.249642)
							(end 0.1778 -0.2794)
						)
					)
					(width 0)
					(fill yes)
				)
			)
		)
		(pad "2" smd custom
			(at 0 0.4445 180)
			(size 0.1397 0.1397)
			(layers "F.Cu" "F.Mask" "F.Paste")
			(net "USB_P1_DN")
			(options
				(clearance outline)
				(anchor circle)
			)
			(primitives
				(gr_poly
					(pts
						(arc
							(start -0.1778 -0.2794)
							(mid -0.249642 -0.249642)
							(end -0.2794 -0.1778)
						)
						(arc
							(start -0.2794 0.1778)
							(mid -0.249642 0.249642)
							(end -0.1778 0.2794)
						)
						(arc
							(start 0.1778 0.2794)
							(mid 0.249642 0.249642)
							(end 0.2794 0.1778)
						)
						(arc
							(start 0.2794 -0.1778)
							(mid 0.249642 -0.249642)
							(end 0.1778 -0.2794)
						)
					)
					(width 0)
					(fill yes)
				)
			)
		)
	)
	(footprint ""
		(layer "F.Cu")
		(at 216.261188 -36.833556 -90)
		(property "Reference" "C160"
			(at 0 0 270)
			(layer "F.SilkS")
			(hide yes)
			(effects
				(font
					(size 1.27 1.27)
				)
			)
		)
		(property "Value" "SCD1U50V3KX-GP"
			(at 0 -2.8194 270)
			(unlocked yes)
			(layer "F.Fab")
			(hide yes)
			(effects
				(font
					(size 1.016 1.016)
					(thickness 0.1524)
				)
			)
		)
		(property "Device Type" "C603H36"
			(at 0 -4.3434 270)
			(unlocked yes)
			(layer "F.Fab")
			(hide yes)
			(effects
				(font
					(size 1.016 1.016)
					(thickness 0.1524)
				)
			)
		)
		(duplicate_pad_numbers_are_jumpers no)
		(fp_line
			(start 0.508 0)
			(end -0.508 0)
			(stroke
				(width 0.2032)
				(type default)
			)
			(layer "F.SilkS")
		)
		(fp_rect
			(start -0.5842 1.3335)
			(end 0.5842 -1.3335)
			(stroke
				(width 0)
				(type default)
			)
			(fill no)
			(layer "F.CrtYd")
		)
		(fp_rect
			(start -0.5842 1.3335)
			(end 0.5842 -1.3335)
			(stroke
				(width 0)
				(type default)
			)
			(fill no)
			(layer "F.Fab")
		)
		(pad "1" smd custom
			(at 0 -0.762 270)
			(size 0.2159 0.2159)
			(layers "F.Cu" "F.Mask" "F.Paste")
			(net "P5V_STBY")
			(options
				(clearance outline)
				(anchor circle)
			)
			(primitives
				(gr_poly
					(pts
						(arc
							(start -0.3302 -0.4318)
							(mid -0.402042 -0.402042)
							(end -0.4318 -0.3302)
						)
						(arc
							(start -0.4318 0.3302)
							(mid -0.402042 0.402042)
							(end -0.3302 0.4318)
						)
						(arc
							(start 0.3302 0.4318)
							(mid 0.402042 0.402042)
							(end 0.4318 0.3302)
						)
						(arc
							(start 0.4318 -0.3302)
							(mid 0.402042 -0.402042)
							(end 0.3302 -0.4318)
						)
					)
					(width 0)
					(fill yes)
				)
			)
		)
		(pad "2" smd custom
			(at 0 0.762 270)
			(size 0.2159 0.2159)
			(layers "F.Cu" "F.Mask" "F.Paste")
			(net "P5V_LL_R")
			(options
				(clearance outline)
				(anchor circle)
			)
			(primitives
				(gr_poly
					(pts
						(arc
							(start -0.3302 -0.4318)
							(mid -0.402042 -0.402042)
							(end -0.4318 -0.3302)
						)
						(arc
							(start -0.4318 0.3302)
							(mid -0.402042 0.402042)
							(end -0.3302 0.4318)
						)
						(arc
							(start 0.3302 0.4318)
							(mid 0.402042 0.402042)
							(end 0.4318 0.3302)
						)
						(arc
							(start 0.4318 -0.3302)
							(mid 0.402042 -0.402042)
							(end 0.3302 -0.4318)
						)
					)
					(width 0)
					(fill yes)
				)
			)
		)
	)
	(footprint ""
		(layer "F.Cu")
		(at 69.52488 -182.73268 90)
		(property "Reference" "R509"
			(at 0 0 90)
			(layer "F.SilkS")
			(hide yes)
			(effects
				(font
					(size 1.27 1.27)
				)
			)
		)
		(property "Value" "4K75R2F-1-GP"
			(at 0.064008 -3.993896 90)
			(unlocked yes)
			(layer "F.Fab")
			(hide yes)
			(effects
				(font
					(size 1.016 1.016)
					(thickness 0.1524)
				)
			)
		)
		(property "Device Type" "R402H16"
			(at 0.064008 -5.517896 90)
			(unlocked yes)
			(layer "F.Fab")
			(hide yes)
			(effects
				(font
					(size 1.016 1.016)
					(thickness 0.1524)
				)
			)
		)
		(duplicate_pad_numbers_are_jumpers no)
		(fp_line
			(start 0.508 -0.9398)
			(end -0.508 -0.9398)
			(stroke
				(width 0.1524)
				(type default)
			)
			(layer "F.SilkS")
		)
		(fp_line
			(start -0.508 -0.9398)
			(end -0.508 0.9398)
			(stroke
				(width 0.1524)
				(type default)
			)
			(layer "F.SilkS")
		)
		(fp_rect
			(start -0.508 0.9398)
			(end 0.508 -0.9398)
			(stroke
				(width 0)
				(type default)
			)
			(fill no)
			(layer "F.CrtYd")
		)
		(fp_rect
			(start -0.508 0.9398)
			(end 0.508 -0.9398)
			(stroke
				(width 0)
				(type default)
			)
			(fill no)
			(layer "F.Fab")
		)
		(pad "1" smd custom
			(at 0 -0.4445 90)
			(size 0.1397 0.1397)
			(layers "F.Cu" "F.Mask" "F.Paste")
			(net "P3V3_STBY")
			(options
				(clearance outline)
				(anchor circle)
			)
			(primitives
				(gr_poly
					(pts
						(arc
							(start -0.1778 -0.2794)
							(mid -0.249642 -0.249642)
							(end -0.2794 -0.1778)
						)
						(arc
							(start -0.2794 0.1778)
							(mid -0.249642 0.249642)
							(end -0.1778 0.2794)
						)
						(arc
							(start 0.1778 0.2794)
							(mid 0.249642 0.249642)
							(end 0.2794 0.1778)
						)
						(arc
							(start 0.2794 -0.1778)
							(mid 0.249642 -0.249642)
							(end 0.1778 -0.2794)
						)
					)
					(width 0)
					(fill yes)
				)
			)
		)
		(pad "2" smd custom
			(at 0 0.4445 90)
			(size 0.1397 0.1397)
			(layers "F.Cu" "F.Mask" "F.Paste")
			(net "TPS74801_P2V5_STBY_EN")
			(options
				(clearance outline)
				(anchor circle)
			)
			(primitives
				(gr_poly
					(pts
						(arc
							(start -0.1778 -0.2794)
							(mid -0.249642 -0.249642)
							(end -0.2794 -0.1778)
						)
						(arc
							(start -0.2794 0.1778)
							(mid -0.249642 0.249642)
							(end -0.1778 0.2794)
						)
						(arc
							(start 0.1778 0.2794)
							(mid 0.249642 0.249642)
							(end 0.2794 0.1778)
						)
						(arc
							(start 0.2794 -0.1778)
							(mid 0.249642 -0.249642)
							(end 0.1778 -0.2794)
						)
					)
					(width 0)
					(fill yes)
				)
			)
		)
	)
	(footprint ""
		(layer "F.Cu")
		(at 134.873492 -18.143474)
		(property "Reference" "D1"
			(at 0 0 0)
			(layer "F.SilkS")
			(hide yes)
			(effects
				(font
					(size 1.27 1.27)
				)
			)
		)
		(property "Value" "SMF15A-GP"
			(at -2.0955 1.2192 0)
			(unlocked yes)
			(layer "F.Fab")
			(hide yes)
			(effects
				(font
					(size 1.016 1.016)
					(thickness 0.1524)
				)
			)
		)
		(property "Device Type" "SOD123AK-2H43"
			(at -2.0955 -0.3048 0)
			(unlocked yes)
			(layer "F.Fab")
			(hide yes)
			(effects
				(font
					(size 1.016 1.016)
					(thickness 0.1524)
				)
			)
		)
		(duplicate_pad_numbers_are_jumpers no)
		(fp_line
			(start -1.1557 -2.7686)
			(end -1.1557 2.7686)
			(stroke
				(width 0.1524)
				(type default)
			)
			(layer "F.SilkS")
		)
		(fp_line
			(start -1.1557 2.7686)
			(end 1.1557 2.7686)
			(stroke
				(width 0.1524)
				(type default)
			)
			(layer "F.SilkS")
		)
		(fp_line
			(start 1.1557 -2.7686)
			(end -1.1557 -2.7686)
			(stroke
				(width 0.1524)
				(type default)
			)
			(layer "F.SilkS")
		)
		(fp_line
			(start 1.1557 2.7686)
			(end 1.1557 -2.7686)
			(stroke
				(width 0.1524)
				(type default)
			)
			(layer "F.SilkS")
		)
		(fp_line
			(start 1.1557 2.921)
			(end -1.1557 2.921)
			(stroke
				(width 0.508)
				(type default)
			)
			(layer "F.SilkS")
		)
		(fp_poly
			(pts
				(xy -0.4572 1.8669) (xy -0.4572 1.397) (xy -0.9017 1.397) (xy -0.9017 -1.397) (xy -0.4572 -1.397)
				(xy -0.4572 -1.8669) (xy 0.4572 -1.8669) (xy 0.4572 -1.397) (xy 0.9017 -1.397) (xy 0.9017 1.397)
				(xy 0.4572 1.397) (xy 0.4572 1.8669)
			)
			(stroke
				(width 0)
				(type default)
			)
			(fill no)
			(layer "F.CrtYd")
		)
		(fp_poly
			(pts
				(xy -1.4097 2.8448) (xy -1.4097 -2.8448) (xy 1.4097 -2.8448) (xy 1.4097 1.3716) (xy 0.9017 1.3716)
				(xy 0.9017 -1.397) (xy 0.4572 -1.397) (xy 0.4572 -1.8669) (xy -0.4572 -1.8669) (xy -0.4572 -1.397)
				(xy -0.9017 -1.397) (xy -0.9017 1.397) (xy -0.4572 1.397) (xy -0.4572 1.8669) (xy 0.4572 1.8669)
				(xy 0.4572 1.397) (xy 0.9017 1.397) (xy 0.9017 1.3843) (xy 1.4097 1.3843) (xy 1.4097 2.8448)
			)
			(stroke
				(width 0)
				(type default)
			)
			(fill no)
			(layer "F.CrtYd")
		)
		(fp_rect
			(start -1.4097 2.8448)
			(end 1.4097 -2.8448)
			(stroke
				(width 0)
				(type default)
			)
			(fill no)
			(layer "F.Fab")
		)
		(pad "A" smd rect
			(at 0 -1.75768)
			(size 1.143 1.4986)
			(layers "F.Cu" "F.Mask" "F.Paste")
			(net "GND")
		)
		(pad "K" smd rect
			(at 0 1.75768)
			(size 1.143 1.4986)
			(layers "F.Cu" "F.Mask" "F.Paste")
			(net "P12V_IOM")
		)
	)
	(footprint ""
		(layer "F.Cu")
		(at 10.771124 -135.285988 90)
		(property "Reference" "R224"
			(at 0 0 90)
			(layer "F.SilkS")
			(hide yes)
			(effects
				(font
					(size 1.27 1.27)
				)
			)
		)
		(property "Value" "4K7R2F-GP"
			(at 0.064008 -3.993896 90)
			(unlocked yes)
			(layer "F.Fab")
			(hide yes)
			(effects
				(font
					(size 1.016 1.016)
					(thickness 0.1524)
				)
			)
		)
		(property "Device Type" "R402H16"
			(at 0.064008 -5.517896 90)
			(unlocked yes)
			(layer "F.Fab")
			(hide yes)
			(effects
				(font
					(size 1.016 1.016)
					(thickness 0.1524)
				)
			)
		)
		(duplicate_pad_numbers_are_jumpers no)
		(fp_line
			(start 0.508 -0.9398)
			(end -0.508 -0.9398)
			(stroke
				(width 0.1524)
				(type default)
			)
			(layer "F.SilkS")
		)
		(fp_line
			(start -0.508 -0.9398)
			(end -0.508 0.9398)
			(stroke
				(width 0.1524)
				(type default)
			)
			(layer "F.SilkS")
		)
		(fp_rect
			(start -0.508 0.9398)
			(end 0.508 -0.9398)
			(stroke
				(width 0)
				(type default)
			)
			(fill no)
			(layer "F.CrtYd")
		)
		(fp_rect
			(start -0.508 0.9398)
			(end 0.508 -0.9398)
			(stroke
				(width 0)
				(type default)
			)
			(fill no)
			(layer "F.Fab")
		)
		(pad "1" smd custom
			(at 0 -0.4445 90)
			(size 0.1397 0.1397)
			(layers "F.Cu" "F.Mask" "F.Paste")
			(net "MEM_PAR")
			(options
				(clearance outline)
				(anchor circle)
			)
			(primitives
				(gr_poly
					(pts
						(arc
							(start -0.1778 -0.2794)
							(mid -0.249642 -0.249642)
							(end -0.2794 -0.1778)
						)
						(arc
							(start -0.2794 0.1778)
							(mid -0.249642 0.249642)
							(end -0.1778 0.2794)
						)
						(arc
							(start 0.1778 0.2794)
							(mid 0.249642 0.249642)
							(end 0.2794 0.1778)
						)
						(arc
							(start 0.2794 -0.1778)
							(mid 0.249642 -0.249642)
							(end 0.1778 -0.2794)
						)
					)
					(width 0)
					(fill yes)
				)
			)
		)
		(pad "2" smd custom
			(at 0 0.4445 90)
			(size 0.1397 0.1397)
			(layers "F.Cu" "F.Mask" "F.Paste")
			(net "P1V2_STBY")
			(options
				(clearance outline)
				(anchor circle)
			)
			(primitives
				(gr_poly
					(pts
						(arc
							(start -0.1778 -0.2794)
							(mid -0.249642 -0.249642)
							(end -0.2794 -0.1778)
						)
						(arc
							(start -0.2794 0.1778)
							(mid -0.249642 0.249642)
							(end -0.1778 0.2794)
						)
						(arc
							(start 0.1778 0.2794)
							(mid 0.249642 0.249642)
							(end 0.2794 0.1778)
						)
						(arc
							(start 0.2794 -0.1778)
							(mid 0.249642 -0.249642)
							(end 0.1778 -0.2794)
						)
					)
					(width 0)
					(fill yes)
				)
			)
		)
	)
	(footprint ""
		(layer "F.Cu")
		(at 63.119 -165.735 90)
		(property "Reference" "Q3"
			(at 0 0 90)
			(layer "F.SilkS")
			(hide yes)
			(effects
				(font
					(size 1.27 1.27)
				)
			)
		)
		(property "Value" "MMBT3904-3-GP"
			(at 0.10287 -10.29843 90)
			(unlocked yes)
			(layer "F.Fab")
			(hide yes)
			(effects
				(font
					(size 1.016 1.016)
					(thickness 0.1524)
				)
			)
		)
		(property "Device Type" "SOT23CBE2D4H44"
			(at 0.10287 -12.20343 90)
			(unlocked yes)
			(layer "F.Fab")
			(hide yes)
			(effects
				(font
					(size 1.016 1.016)
					(thickness 0.1524)
				)
			)
		)
		(duplicate_pad_numbers_are_jumpers no)
		(fp_line
			(start 1.651 -1.778)
			(end -1.651 -1.778)
			(stroke
				(width 0.1524)
				(type default)
			)
			(layer "F.SilkS")
		)
		(fp_line
			(start -1.651 -1.778)
			(end -1.651 1.778)
			(stroke
				(width 0.1524)
				(type default)
			)
			(layer "F.SilkS")
		)
		(fp_line
			(start 1.651 1.778)
			(end 1.651 -1.778)
			(stroke
				(width 0.1524)
				(type default)
			)
			(layer "F.SilkS")
		)
		(fp_line
			(start -1.651 1.778)
			(end 1.651 1.778)
			(stroke
				(width 0.1524)
				(type default)
			)
			(layer "F.SilkS")
		)
		(fp_poly
			(pts
				(xy -1.778 1.8796) (xy -1.778 -1.8796) (xy 1.778 -1.8796) (xy 1.778 1.8796)
			)
			(stroke
				(width 0)
				(type default)
			)
			(fill no)
			(layer "F.CrtYd")
		)
		(fp_poly
			(pts
				(xy -1.778 1.8796) (xy -1.778 -1.8796) (xy 1.778 -1.8796) (xy 1.778 1.8796)
			)
			(stroke
				(width 0)
				(type default)
			)
			(fill no)
			(layer "F.Fab")
		)
		(pad "B" smd custom
			(at -0.98425 0.9525 90)
			(size 0.1905 0.1905)
			(layers "F.Cu" "F.Mask" "F.Paste")
			(net "FM_TPM_PRSNT_RST_N_R")
			(options
				(clearance outline)
				(anchor circle)
			)
			(primitives
				(gr_poly
					(pts
						(arc
							(start -0.1778 0.5715)
							(mid -0.321484 0.511984)
							(end -0.381 0.3683)
						)
						(arc
							(start -0.381 -0.3683)
							(mid -0.321484 -0.511984)
							(end -0.1778 -0.5715)
						)
						(arc
							(start 0.1778 -0.5715)
							(mid 0.321484 -0.511984)
							(end 0.381 -0.3683)
						)
						(arc
							(start 0.381 0.3683)
							(mid 0.321484 0.511984)
							(end 0.1778 0.5715)
						)
					)
					(width 0)
					(fill yes)
				)
			)
		)
		(pad "C" smd custom
			(at 0 -0.9525 90)
			(size 0.1905 0.1905)
			(layers "F.Cu" "F.Mask" "F.Paste")
			(net "FM_TPM_PRSNT_RST")
			(options
				(clearance outline)
				(anchor circle)
			)
			(primitives
				(gr_poly
					(pts
						(arc
							(start -0.1778 0.5715)
							(mid -0.321484 0.511984)
							(end -0.381 0.3683)
						)
						(arc
							(start -0.381 -0.3683)
							(mid -0.321484 -0.511984)
							(end -0.1778 -0.5715)
						)
						(arc
							(start 0.1778 -0.5715)
							(mid 0.321484 -0.511984)
							(end 0.381 -0.3683)
						)
						(arc
							(start 0.381 0.3683)
							(mid 0.321484 0.511984)
							(end 0.1778 0.5715)
						)
					)
					(width 0)
					(fill yes)
				)
			)
		)
		(pad "E" smd custom
			(at 0.98425 0.9525 90)
			(size 0.1905 0.1905)
			(layers "F.Cu" "F.Mask" "F.Paste")
			(net "GND")
			(options
				(clearance outline)
				(anchor circle)
			)
			(primitives
				(gr_poly
					(pts
						(arc
							(start -0.1778 0.5715)
							(mid -0.321484 0.511984)
							(end -0.381 0.3683)
						)
						(arc
							(start -0.381 -0.3683)
							(mid -0.321484 -0.511984)
							(end -0.1778 -0.5715)
						)
						(arc
							(start 0.1778 -0.5715)
							(mid 0.321484 -0.511984)
							(end 0.381 -0.3683)
						)
						(arc
							(start 0.381 0.3683)
							(mid 0.321484 0.511984)
							(end 0.1778 0.5715)
						)
					)
					(width 0)
					(fill yes)
				)
			)
		)
	)
	(footprint ""
		(layer "F.Cu")
		(at 118.872 -8.9916 90)
		(property "Reference" "U35"
			(at 0 0 90)
			(layer "F.SilkS")
			(hide yes)
			(effects
				(font
					(size 1.27 1.27)
				)
			)
		)
		(property "Value" "ADM1278-2ACPZ-RL-1-GP"
			(at -4.7625 -7.4422 90)
			(unlocked yes)
			(layer "F.Fab")
			(hide yes)
			(effects
				(font
					(size 1.016 1.016)
					(thickness 0.1524)
				)
			)
		)
		(property "Device Type" "QFN32-G3D45-UH32"
			(at -4.7625 -8.9662 90)
			(unlocked yes)
			(layer "F.Fab")
			(hide yes)
			(effects
				(font
					(size 1.016 1.016)
					(thickness 0.1524)
				)
			)
		)
		(duplicate_pad_numbers_are_jumpers no)
		(fp_line
			(start -0.250698 -3.7973)
			(end -0.250698 -3.2893)
			(stroke
				(width 0.1524)
				(type default)
			)
			(layer "F.SilkS")
		)
		(fp_line
			(start -3.5179 -3.5179)
			(end -2.2479 -3.5179)
			(stroke
				(width 0.1524)
				(type default)
			)
			(layer "F.SilkS")
		)
		(fp_line
			(start -3.5179 -2.2479)
			(end -3.5179 -3.5179)
			(stroke
				(width 0.1524)
				(type default)
			)
			(layer "F.SilkS")
		)
		(fp_line
			(start -4.0513 -1.24968)
			(end -3.2893 -1.24968)
			(stroke
				(width 0.1524)
				(type default)
			)
			(layer "F.SilkS")
		)
		(fp_line
			(start 4.0513 -0.749808)
			(end 3.2893 -0.749808)
			(stroke
				(width 0.1524)
				(type default)
			)
			(layer "F.SilkS")
		)
		(fp_line
			(start -3.7973 1.24968)
			(end -3.2893 1.24968)
			(stroke
				(width 0.1524)
				(type default)
			)
			(layer "F.SilkS")
		)
		(fp_line
			(start 3.7973 1.749552)
			(end 3.2893 1.749552)
			(stroke
				(width 0.1524)
				(type default)
			)
			(layer "F.SilkS")
		)
		(fp_line
			(start 3.5179 2.2479)
			(end 3.5179 3.5179)
			(stroke
				(width 0.1524)
				(type default)
			)
			(layer "F.SilkS")
		)
		(fp_line
			(start -3.5179 2.2479)
			(end -3.5179 3.5179)
			(stroke
				(width 0.1524)
				(type default)
			)
			(layer "F.SilkS")
		)
		(fp_line
			(start 3.5179 3.5179)
			(end 2.2479 3.5179)
			(stroke
				(width 0.1524)
				(type default)
			)
			(layer "F.SilkS")
		)
		(fp_line
			(start -3.5179 3.5179)
			(end -2.2479 3.5179)
			(stroke
				(width 0.1524)
				(type default)
			)
			(layer "F.SilkS")
		)
		(fp_line
			(start -0.250698 4.0513)
			(end -0.250698 3.2893)
			(stroke
				(width 0.1524)
				(type default)
			)
			(layer "F.SilkS")
		)
		(fp_poly
			(pts
				(xy 2.2479 -3.5179) (xy 3.5179 -2.2479) (xy 3.5179 -3.5179)
			)
			(stroke
				(width 0)
				(type default)
			)
			(fill yes)
			(layer "F.SilkS")
		)
		(fp_rect
			(start -2.5019 2.5019)
			(end 2.5019 -2.5019)
			(stroke
				(width 0)
				(type default)
			)
			(fill no)
			(layer "F.CrtYd")
		)
		(fp_poly
			(pts
				(xy -3.5179 3.5179) (xy -3.5179 -3.5179) (xy 3.5179 -3.5179) (xy 3.5179 3.5179) (xy -2.49682 3.5179)
				(xy -2.49682 2.5019) (xy 2.5019 2.5019) (xy 2.5019 -2.5019) (xy -2.5019 -2.5019) (xy -2.5019 3.5179)
			)
			(stroke
				(width 0)
				(type default)
			)
			(fill no)
			(layer "F.CrtYd")
		)
		(fp_rect
			(start -3.5179 3.5179)
			(end 3.5179 -3.5179)
			(stroke
				(width 0)
				(type default)
			)
			(fill no)
			(layer "F.Fab")
		)
		(pad "1" smd rect
			(at 1.75006 -2.5527 90)
			(size 0.3048 0.9144)
			(layers "F.Cu" "F.Mask" "F.Paste")
			(net "MB0_PSET_R")
		)
		(pad "2" smd rect
			(at 1.249934 -2.4765 90)
			(size 0.3048 1.0668)
			(layers "F.Cu" "F.Mask" "F.Paste")
			(net "MB0_VCAP_R")
		)
		(pad "3" smd rect
			(at 0.750062 -2.4765 90)
			(size 0.3048 1.0668)
			(layers "F.Cu" "F.Mask" "F.Paste")
			(net "MB0_ISET_R")
		)
		(pad "4" smd rect
			(at 0.249936 -2.4765 90)
			(size 0.3048 1.0668)
			(layers "F.Cu" "F.Mask" "F.Paste")
			(net "MB0_ISTART_R")
		)
		(pad "5" smd rect
			(at -0.249936 -2.4765 90)
			(size 0.3048 1.0668)
			(layers "F.Cu" "F.Mask" "F.Paste")
			(net "MB0_TIME_R")
		)
		(pad "6" smd rect
			(at -0.750062 -2.4765 90)
			(size 0.3048 1.0668)
			(layers "F.Cu" "F.Mask" "F.Paste")
			(net "Net_527")
		)
		(pad "7" smd rect
			(at -1.249934 -2.4765 90)
			(size 0.3048 1.0668)
			(layers "F.Cu" "F.Mask" "F.Paste")
			(net "MB0_CM_ADR1_R")
		)
		(pad "8" smd rect
			(at -1.75006 -2.5527 90)
			(size 0.3048 0.9144)
			(layers "F.Cu" "F.Mask" "F.Paste")
			(net "MB0_CM_ADR2_R")
		)
		(pad "9" smd rect
			(at -2.5527 -1.75006 90)
			(size 0.9144 0.3048)
			(layers "F.Cu" "F.Mask" "F.Paste")
			(net "MB0_SPISS_PD")
		)
		(pad "10" smd rect
			(at -2.4765 -1.249934 90)
			(size 1.0668 0.3048)
			(layers "F.Cu" "F.Mask" "F.Paste")
			(net "Net_531")
		)
		(pad "11" smd rect
			(at -2.4765 -0.750062 90)
			(size 1.0668 0.3048)
			(layers "F.Cu" "F.Mask" "F.Paste")
			(net "Net_530")
		)
		(pad "12" smd rect
			(at -2.4765 -0.249936 90)
			(size 1.0668 0.3048)
			(layers "F.Cu" "F.Mask" "F.Paste")
			(net "MB0_HS_ENABLE")
		)
		(pad "13" smd rect
			(at -2.4765 0.249936 90)
			(size 1.0668 0.3048)
			(layers "F.Cu" "F.Mask" "F.Paste")
			(net "Net_529")
		)
		(pad "14" smd rect
			(at -2.4765 0.750062 90)
			(size 1.0668 0.3048)
			(layers "F.Cu" "F.Mask" "F.Paste")
			(net "Net_528")
		)
		(pad "15" smd rect
			(at -2.4765 1.249934 90)
			(size 1.0668 0.3048)
			(layers "F.Cu" "F.Mask" "F.Paste")
			(net "HSW_SDA")
		)
		(pad "16" smd rect
			(at -2.5527 1.75006 90)
			(size 0.9144 0.3048)
			(layers "F.Cu" "F.Mask" "F.Paste")
			(net "HSW_SCL")
		)
		(pad "17" smd rect
			(at -1.75006 2.5527 90)
			(size 0.3048 0.9144)
			(layers "F.Cu" "F.Mask" "F.Paste")
			(net "MB0_RETRY_R")
		)
		(pad "18" smd rect
			(at -1.249934 2.4765 90)
			(size 0.3048 1.0668)
			(layers "F.Cu" "F.Mask" "F.Paste")
			(net "P12V_IOM_PGOOD")
		)
		(pad "19" smd rect
			(at -0.750062 2.4765 90)
			(size 0.3048 1.0668)
			(layers "F.Cu" "F.Mask" "F.Paste")
			(net "Net_532")
		)
		(pad "20" smd rect
			(at -0.249936 2.4765 90)
			(size 0.3048 1.0668)
			(layers "F.Cu" "F.Mask" "F.Paste")
			(net "MB0_CM_VOUT_R")
		)
		(pad "21" smd rect
			(at 0.249936 2.4765 90)
			(size 0.3048 1.0668)
			(layers "F.Cu" "F.Mask" "F.Paste")
			(net "MB0_P12V_PWGIN_R")
		)
		(pad "22" smd rect
			(at 0.750062 2.4765 90)
			(size 0.3048 1.0668)
			(layers "F.Cu" "F.Mask" "F.Paste")
			(net "AGND_CURRENT_MON")
		)
		(pad "23" smd rect
			(at 1.249934 2.4765 90)
			(size 0.3048 1.0668)
			(layers "F.Cu" "F.Mask" "F.Paste")
			(net "GND")
		)
		(pad "24" smd rect
			(at 1.75006 2.5527 90)
			(size 0.3048 0.9144)
			(layers "F.Cu" "F.Mask" "F.Paste")
			(net "MB0_CM_GATE")
		)
		(pad "25" smd rect
			(at 2.5527 1.75006 90)
			(size 0.9144 0.3048)
			(layers "F.Cu" "F.Mask" "F.Paste")
			(net "MB0_TEMP")
		)
		(pad "26" smd rect
			(at 2.4765 1.249934 90)
			(size 1.0668 0.3048)
			(layers "F.Cu" "F.Mask" "F.Paste")
			(net "MB0_CM_SENSE_N")
		)
		(pad "27" smd rect
			(at 2.4765 0.750062 90)
			(size 1.0668 0.3048)
			(layers "F.Cu" "F.Mask" "F.Paste")
			(net "ADM1278_HS_N")
		)
		(pad "28" smd rect
			(at 2.4765 0.249936 90)
			(size 1.0668 0.3048)
			(layers "F.Cu" "F.Mask" "F.Paste")
			(net "ADM1278_HS_P")
		)
		(pad "29" smd rect
			(at 2.4765 -0.249936 90)
			(size 1.0668 0.3048)
			(layers "F.Cu" "F.Mask" "F.Paste")
			(net "MB0_CM_SENSE_P")
		)
		(pad "30" smd rect
			(at 2.4765 -0.750062 90)
			(size 1.0668 0.3048)
			(layers "F.Cu" "F.Mask" "F.Paste")
			(net "MB0_VCC")
		)
		(pad "31" smd rect
			(at 2.4765 -1.249934 90)
			(size 1.0668 0.3048)
			(layers "F.Cu" "F.Mask" "F.Paste")
			(net "MB0_CM_UV_R")
		)
		(pad "32" smd rect
			(at 2.5527 -1.75006 90)
			(size 0.9144 0.3048)
			(layers "F.Cu" "F.Mask" "F.Paste")
			(net "MB0_CM_OV_R")
		)
		(pad "33" smd rect
			(at 0 0 90)
			(size 3.4544 3.4544)
			(layers "F.Cu" "F.Mask" "F.Paste")
			(net "AGND_CURRENT_MON")
		)
	)
	(footprint ""
		(layer "F.Cu")
		(at 156.475938 -16.029178 90)
		(property "Reference" "C203"
			(at 0 0 90)
			(layer "F.SilkS")
			(hide yes)
			(effects
				(font
					(size 1.27 1.27)
				)
			)
		)
		(property "Value" "SCD1U16V2KX-3GP"
			(at 1.1811 -2.7051 90)
			(unlocked yes)
			(layer "F.Fab")
			(hide yes)
			(effects
				(font
					(size 1.016 1.016)
					(thickness 0.1524)
				)
			)
		)
		(property "Device Type" "C402H22"
			(at 1.1811 -4.2291 90)
			(unlocked yes)
			(layer "F.Fab")
			(hide yes)
			(effects
				(font
					(size 1.016 1.016)
					(thickness 0.1524)
				)
			)
		)
		(duplicate_pad_numbers_are_jumpers no)
		(fp_rect
			(start -0.4318 0.9525)
			(end 0.4318 -0.9525)
			(stroke
				(width 0)
				(type default)
			)
			(fill no)
			(layer "F.CrtYd")
		)
		(fp_rect
			(start -0.4318 0.9525)
			(end 0.4318 -0.9525)
			(stroke
				(width 0)
				(type default)
			)
			(fill no)
			(layer "F.Fab")
		)
		(pad "1" smd custom
			(at 0 -0.4445 90)
			(size 0.1524 0.1524)
			(layers "F.Cu" "F.Mask" "F.Paste")
			(net "P12V_STBY_VIN_PU4")
			(options
				(clearance outline)
				(anchor circle)
			)
			(primitives
				(gr_poly
					(pts
						(arc
							(start 0.3048 -0.2032)
							(mid 0.275042 -0.275042)
							(end 0.2032 -0.3048)
						)
						(arc
							(start -0.2032 -0.3048)
							(mid -0.275042 -0.275042)
							(end -0.3048 -0.2032)
						)
						(arc
							(start -0.3048 0.2032)
							(mid -0.275042 0.275042)
							(end -0.2032 0.3048)
						)
						(arc
							(start 0.2032 0.3048)
							(mid 0.275042 0.275042)
							(end 0.3048 0.2032)
						)
					)
					(width 0)
					(fill yes)
				)
			)
		)
		(pad "2" smd custom
			(at 0 0.4445 90)
			(size 0.1524 0.1524)
			(layers "F.Cu" "F.Mask" "F.Paste")
			(net "GND")
			(options
				(clearance outline)
				(anchor circle)
			)
			(primitives
				(gr_poly
					(pts
						(arc
							(start 0.3048 -0.2032)
							(mid 0.275042 -0.275042)
							(end 0.2032 -0.3048)
						)
						(arc
							(start -0.2032 -0.3048)
							(mid -0.275042 -0.275042)
							(end -0.3048 -0.2032)
						)
						(arc
							(start -0.3048 0.2032)
							(mid -0.275042 0.275042)
							(end -0.2032 0.3048)
						)
						(arc
							(start 0.2032 0.3048)
							(mid 0.275042 0.275042)
							(end 0.3048 0.2032)
						)
					)
					(width 0)
					(fill yes)
				)
			)
		)
	)
	(footprint ""
		(layer "F.Cu")
		(at 47.380398 -131.490974 180)
		(property "Reference" "R265"
			(at 0 0 180)
			(layer "F.SilkS")
			(hide yes)
			(effects
				(font
					(size 1.27 1.27)
				)
			)
		)
		(property "Value" "4K7R2F-GP"
			(at 0.064008 -3.993896 180)
			(unlocked yes)
			(layer "F.Fab")
			(hide yes)
			(effects
				(font
					(size 1.016 1.016)
					(thickness 0.1524)
				)
			)
		)
		(property "Device Type" "R402H16"
			(at 0.064008 -5.517896 180)
			(unlocked yes)
			(layer "F.Fab")
			(hide yes)
			(effects
				(font
					(size 1.016 1.016)
					(thickness 0.1524)
				)
			)
		)
		(duplicate_pad_numbers_are_jumpers no)
		(fp_line
			(start 0.508 -0.9398)
			(end -0.508 -0.9398)
			(stroke
				(width 0.1524)
				(type default)
			)
			(layer "F.SilkS")
		)
		(fp_line
			(start -0.508 -0.9398)
			(end -0.508 0.9398)
			(stroke
				(width 0.1524)
				(type default)
			)
			(layer "F.SilkS")
		)
		(fp_rect
			(start -0.508 0.9398)
			(end 0.508 -0.9398)
			(stroke
				(width 0)
				(type default)
			)
			(fill no)
			(layer "F.CrtYd")
		)
		(fp_rect
			(start -0.508 0.9398)
			(end 0.508 -0.9398)
			(stroke
				(width 0)
				(type default)
			)
			(fill no)
			(layer "F.Fab")
		)
		(pad "1" smd custom
			(at 0 -0.4445 180)
			(size 0.1397 0.1397)
			(layers "F.Cu" "F.Mask" "F.Paste")
			(net "P3V3_STBY")
			(options
				(clearance outline)
				(anchor circle)
			)
			(primitives
				(gr_poly
					(pts
						(arc
							(start -0.1778 -0.2794)
							(mid -0.249642 -0.249642)
							(end -0.2794 -0.1778)
						)
						(arc
							(start -0.2794 0.1778)
							(mid -0.249642 0.249642)
							(end -0.1778 0.2794)
						)
						(arc
							(start 0.1778 0.2794)
							(mid 0.249642 0.249642)
							(end 0.2794 0.1778)
						)
						(arc
							(start 0.2794 -0.1778)
							(mid 0.249642 -0.249642)
							(end 0.1778 -0.2794)
						)
					)
					(width 0)
					(fill yes)
				)
			)
		)
		(pad "2" smd custom
			(at 0 0.4445 180)
			(size 0.1397 0.1397)
			(layers "F.Cu" "F.Mask" "F.Paste")
			(net "BMC_GPIOY3")
			(options
				(clearance outline)
				(anchor circle)
			)
			(primitives
				(gr_poly
					(pts
						(arc
							(start -0.1778 -0.2794)
							(mid -0.249642 -0.249642)
							(end -0.2794 -0.1778)
						)
						(arc
							(start -0.2794 0.1778)
							(mid -0.249642 0.249642)
							(end -0.1778 0.2794)
						)
						(arc
							(start 0.1778 0.2794)
							(mid 0.249642 0.249642)
							(end 0.2794 0.1778)
						)
						(arc
							(start 0.2794 -0.1778)
							(mid 0.249642 -0.249642)
							(end 0.1778 -0.2794)
						)
					)
					(width 0)
					(fill yes)
				)
			)
		)
	)
	(footprint ""
		(layer "F.Cu")
		(at 45.913802 -119.34952 -90)
		(property "Reference" "R83"
			(at 0 0 270)
			(layer "F.SilkS")
			(hide yes)
			(effects
				(font
					(size 1.27 1.27)
				)
			)
		)
		(property "Value" "2K2R2J-2-GP"
			(at 0.064008 -3.993896 270)
			(unlocked yes)
			(layer "F.Fab")
			(hide yes)
			(effects
				(font
					(size 1.016 1.016)
					(thickness 0.1524)
				)
			)
		)
		(property "Device Type" "R402H16"
			(at 0.064008 -5.517896 270)
			(unlocked yes)
			(layer "F.Fab")
			(hide yes)
			(effects
				(font
					(size 1.016 1.016)
					(thickness 0.1524)
				)
			)
		)
		(duplicate_pad_numbers_are_jumpers no)
		(fp_line
			(start -0.508 -0.9398)
			(end -0.508 0.9398)
			(stroke
				(width 0.1524)
				(type default)
			)
			(layer "F.SilkS")
		)
		(fp_line
			(start 0.508 -0.9398)
			(end -0.508 -0.9398)
			(stroke
				(width 0.1524)
				(type default)
			)
			(layer "F.SilkS")
		)
		(fp_rect
			(start -0.508 0.9398)
			(end 0.508 -0.9398)
			(stroke
				(width 0)
				(type default)
			)
			(fill no)
			(layer "F.CrtYd")
		)
		(fp_rect
			(start -0.508 0.9398)
			(end 0.508 -0.9398)
			(stroke
				(width 0)
				(type default)
			)
			(fill no)
			(layer "F.Fab")
		)
		(pad "1" smd custom
			(at 0 -0.4445 270)
			(size 0.1397 0.1397)
			(layers "F.Cu" "F.Mask" "F.Paste")
			(net "P3V3_STBY")
			(options
				(clearance outline)
				(anchor circle)
			)
			(primitives
				(gr_poly
					(pts
						(arc
							(start -0.1778 -0.2794)
							(mid -0.249642 -0.249642)
							(end -0.2794 -0.1778)
						)
						(arc
							(start -0.2794 0.1778)
							(mid -0.249642 0.249642)
							(end -0.1778 0.2794)
						)
						(arc
							(start 0.1778 0.2794)
							(mid 0.249642 0.249642)
							(end 0.2794 0.1778)
						)
						(arc
							(start 0.2794 -0.1778)
							(mid 0.249642 -0.249642)
							(end 0.1778 -0.2794)
						)
					)
					(width 0)
					(fill yes)
				)
			)
		)
		(pad "2" smd custom
			(at 0 0.4445 270)
			(size 0.1397 0.1397)
			(layers "F.Cu" "F.Mask" "F.Paste")
			(net "FLA0_SPI_RST")
			(options
				(clearance outline)
				(anchor circle)
			)
			(primitives
				(gr_poly
					(pts
						(arc
							(start -0.1778 -0.2794)
							(mid -0.249642 -0.249642)
							(end -0.2794 -0.1778)
						)
						(arc
							(start -0.2794 0.1778)
							(mid -0.249642 0.249642)
							(end -0.1778 0.2794)
						)
						(arc
							(start 0.1778 0.2794)
							(mid 0.249642 0.249642)
							(end 0.2794 0.1778)
						)
						(arc
							(start 0.2794 -0.1778)
							(mid 0.249642 -0.249642)
							(end 0.1778 -0.2794)
						)
					)
					(width 0)
					(fill yes)
				)
			)
		)
	)
	(footprint ""
		(layer "F.Cu")
		(at 61.2394 -138.2014)
		(property "Reference" "TP77"
			(at 0 0 0)
			(layer "F.SilkS")
			(hide yes)
			(effects
				(font
					(size 1.27 1.27)
				)
			)
		)
		(property "Value" "TPAD28-2-GP"
			(at -0.0127 -1.6637 0)
			(unlocked yes)
			(layer "F.Fab")
			(hide yes)
			(effects
				(font
					(size 1.016 1.016)
					(thickness 0.1524)
				)
			)
		)
		(property "Device Type" "TPAD28"
			(at -0.0127 -3.1877 0)
			(unlocked yes)
			(layer "F.Fab")
			(hide yes)
			(effects
				(font
					(size 1.016 1.016)
					(thickness 0.1524)
				)
			)
		)
		(duplicate_pad_numbers_are_jumpers no)
		(fp_poly
			(pts
				(arc
					(start 0.3556 0)
					(mid -0.3556 0)
					(end 0.3556 0)
				)
			)
			(stroke
				(width 0)
				(type default)
			)
			(fill no)
			(layer "F.CrtYd")
		)
		(fp_poly
			(pts
				(arc
					(start 0.6096 0)
					(mid -0.6096 0)
					(end 0.6096 0)
				)
			)
			(stroke
				(width 0)
				(type default)
			)
			(fill no)
			(layer "F.Fab")
		)
		(pad "1" smd circle
			(at 0 0)
			(size 0.7112 0.7112)
			(layers "F.Cu" "F.Mask" "F.Paste")
			(net "TP_BMC_GPIOI7")
		)
	)
	(footprint ""
		(layer "F.Cu")
		(at 55.245 -130.064764 -90)
		(property "Reference" "R146"
			(at 0 0 270)
			(layer "F.SilkS")
			(hide yes)
			(effects
				(font
					(size 1.27 1.27)
				)
			)
		)
		(property "Value" "100KR2F-L1-GP"
			(at 0.064008 -3.993896 270)
			(unlocked yes)
			(layer "F.Fab")
			(hide yes)
			(effects
				(font
					(size 1.016 1.016)
					(thickness 0.1524)
				)
			)
		)
		(property "Device Type" "R402H16"
			(at 0.064008 -5.517896 270)
			(unlocked yes)
			(layer "F.Fab")
			(hide yes)
			(effects
				(font
					(size 1.016 1.016)
					(thickness 0.1524)
				)
			)
		)
		(duplicate_pad_numbers_are_jumpers no)
		(fp_line
			(start -0.508 -0.9398)
			(end -0.508 0.9398)
			(stroke
				(width 0.1524)
				(type default)
			)
			(layer "F.SilkS")
		)
		(fp_line
			(start 0.508 -0.9398)
			(end -0.508 -0.9398)
			(stroke
				(width 0.1524)
				(type default)
			)
			(layer "F.SilkS")
		)
		(fp_rect
			(start -0.508 0.9398)
			(end 0.508 -0.9398)
			(stroke
				(width 0)
				(type default)
			)
			(fill no)
			(layer "F.CrtYd")
		)
		(fp_rect
			(start -0.508 0.9398)
			(end 0.508 -0.9398)
			(stroke
				(width 0)
				(type default)
			)
			(fill no)
			(layer "F.Fab")
		)
		(pad "1" smd custom
			(at 0 -0.4445 270)
			(size 0.1397 0.1397)
			(layers "F.Cu" "F.Mask" "F.Paste")
			(net "LPC_CPU_CLKOUT0")
			(options
				(clearance outline)
				(anchor circle)
			)
			(primitives
				(gr_poly
					(pts
						(arc
							(start -0.1778 -0.2794)
							(mid -0.249642 -0.249642)
							(end -0.2794 -0.1778)
						)
						(arc
							(start -0.2794 0.1778)
							(mid -0.249642 0.249642)
							(end -0.1778 0.2794)
						)
						(arc
							(start 0.1778 0.2794)
							(mid 0.249642 0.249642)
							(end 0.2794 0.1778)
						)
						(arc
							(start 0.2794 -0.1778)
							(mid 0.249642 -0.249642)
							(end 0.1778 -0.2794)
						)
					)
					(width 0)
					(fill yes)
				)
			)
		)
		(pad "2" smd custom
			(at 0 0.4445 270)
			(size 0.1397 0.1397)
			(layers "F.Cu" "F.Mask" "F.Paste")
			(net "GND")
			(options
				(clearance outline)
				(anchor circle)
			)
			(primitives
				(gr_poly
					(pts
						(arc
							(start -0.1778 -0.2794)
							(mid -0.249642 -0.249642)
							(end -0.2794 -0.1778)
						)
						(arc
							(start -0.2794 0.1778)
							(mid -0.249642 0.249642)
							(end -0.1778 0.2794)
						)
						(arc
							(start 0.1778 0.2794)
							(mid 0.249642 0.249642)
							(end 0.2794 0.1778)
						)
						(arc
							(start 0.2794 -0.1778)
							(mid 0.249642 -0.249642)
							(end 0.1778 -0.2794)
						)
					)
					(width 0)
					(fill yes)
				)
			)
		)
	)
	(footprint ""
		(layer "F.Cu")
		(at 46.348396 -131.823714 180)
		(property "Reference" "R264"
			(at 0 0 180)
			(layer "F.SilkS")
			(hide yes)
			(effects
				(font
					(size 1.27 1.27)
				)
			)
		)
		(property "Value" "4K7R2F-GP"
			(at 0.064008 -3.993896 180)
			(unlocked yes)
			(layer "F.Fab")
			(hide yes)
			(effects
				(font
					(size 1.016 1.016)
					(thickness 0.1524)
				)
			)
		)
		(property "Device Type" "R402H16"
			(at 0.064008 -5.517896 180)
			(unlocked yes)
			(layer "F.Fab")
			(hide yes)
			(effects
				(font
					(size 1.016 1.016)
					(thickness 0.1524)
				)
			)
		)
		(duplicate_pad_numbers_are_jumpers no)
		(fp_line
			(start 0.508 -0.9398)
			(end -0.508 -0.9398)
			(stroke
				(width 0.1524)
				(type default)
			)
			(layer "F.SilkS")
		)
		(fp_line
			(start -0.508 -0.9398)
			(end -0.508 0.9398)
			(stroke
				(width 0.1524)
				(type default)
			)
			(layer "F.SilkS")
		)
		(fp_rect
			(start -0.508 0.9398)
			(end 0.508 -0.9398)
			(stroke
				(width 0)
				(type default)
			)
			(fill no)
			(layer "F.CrtYd")
		)
		(fp_rect
			(start -0.508 0.9398)
			(end 0.508 -0.9398)
			(stroke
				(width 0)
				(type default)
			)
			(fill no)
			(layer "F.Fab")
		)
		(pad "1" smd custom
			(at 0 -0.4445 180)
			(size 0.1397 0.1397)
			(layers "F.Cu" "F.Mask" "F.Paste")
			(net "P3V3_STBY")
			(options
				(clearance outline)
				(anchor circle)
			)
			(primitives
				(gr_poly
					(pts
						(arc
							(start -0.1778 -0.2794)
							(mid -0.249642 -0.249642)
							(end -0.2794 -0.1778)
						)
						(arc
							(start -0.2794 0.1778)
							(mid -0.249642 0.249642)
							(end -0.1778 0.2794)
						)
						(arc
							(start 0.1778 0.2794)
							(mid 0.249642 0.249642)
							(end 0.2794 0.1778)
						)
						(arc
							(start 0.2794 -0.1778)
							(mid 0.249642 -0.249642)
							(end 0.1778 -0.2794)
						)
					)
					(width 0)
					(fill yes)
				)
			)
		)
		(pad "2" smd custom
			(at 0 0.4445 180)
			(size 0.1397 0.1397)
			(layers "F.Cu" "F.Mask" "F.Paste")
			(net "BMC_GPIOY2")
			(options
				(clearance outline)
				(anchor circle)
			)
			(primitives
				(gr_poly
					(pts
						(arc
							(start -0.1778 -0.2794)
							(mid -0.249642 -0.249642)
							(end -0.2794 -0.1778)
						)
						(arc
							(start -0.2794 0.1778)
							(mid -0.249642 0.249642)
							(end -0.1778 0.2794)
						)
						(arc
							(start 0.1778 0.2794)
							(mid 0.249642 0.249642)
							(end 0.2794 0.1778)
						)
						(arc
							(start 0.2794 -0.1778)
							(mid 0.249642 -0.249642)
							(end 0.1778 -0.2794)
						)
					)
					(width 0)
					(fill yes)
				)
			)
		)
	)
	(footprint ""
		(layer "F.Cu")
		(at 64.11595 -144.08404 90)
		(property "Reference" "R181"
			(at 0 0 90)
			(layer "F.SilkS")
			(hide yes)
			(effects
				(font
					(size 1.27 1.27)
				)
			)
		)
		(property "Value" "2K2R2F-GP"
			(at 0.064008 -3.993896 90)
			(unlocked yes)
			(layer "F.Fab")
			(hide yes)
			(effects
				(font
					(size 1.016 1.016)
					(thickness 0.1524)
				)
			)
		)
		(property "Device Type" "R402H16"
			(at 0.064008 -5.517896 90)
			(unlocked yes)
			(layer "F.Fab")
			(hide yes)
			(effects
				(font
					(size 1.016 1.016)
					(thickness 0.1524)
				)
			)
		)
		(duplicate_pad_numbers_are_jumpers no)
		(fp_line
			(start 0.508 -0.9398)
			(end -0.508 -0.9398)
			(stroke
				(width 0.1524)
				(type default)
			)
			(layer "F.SilkS")
		)
		(fp_line
			(start -0.508 -0.9398)
			(end -0.508 0.9398)
			(stroke
				(width 0.1524)
				(type default)
			)
			(layer "F.SilkS")
		)
		(fp_rect
			(start -0.508 0.9398)
			(end 0.508 -0.9398)
			(stroke
				(width 0)
				(type default)
			)
			(fill no)
			(layer "F.CrtYd")
		)
		(fp_rect
			(start -0.508 0.9398)
			(end 0.508 -0.9398)
			(stroke
				(width 0)
				(type default)
			)
			(fill no)
			(layer "F.Fab")
		)
		(pad "1" smd custom
			(at 0 -0.4445 90)
			(size 0.1397 0.1397)
			(layers "F.Cu" "F.Mask" "F.Paste")
			(net "I2C_SCC_SCL_OUT")
			(options
				(clearance outline)
				(anchor circle)
			)
			(primitives
				(gr_poly
					(pts
						(arc
							(start -0.1778 -0.2794)
							(mid -0.249642 -0.249642)
							(end -0.2794 -0.1778)
						)
						(arc
							(start -0.2794 0.1778)
							(mid -0.249642 0.249642)
							(end -0.1778 0.2794)
						)
						(arc
							(start 0.1778 0.2794)
							(mid 0.249642 0.249642)
							(end 0.2794 0.1778)
						)
						(arc
							(start 0.2794 -0.1778)
							(mid 0.249642 -0.249642)
							(end 0.1778 -0.2794)
						)
					)
					(width 0)
					(fill yes)
				)
			)
		)
		(pad "2" smd custom
			(at 0 0.4445 90)
			(size 0.1397 0.1397)
			(layers "F.Cu" "F.Mask" "F.Paste")
			(net "P3V3_STBY")
			(options
				(clearance outline)
				(anchor circle)
			)
			(primitives
				(gr_poly
					(pts
						(arc
							(start -0.1778 -0.2794)
							(mid -0.249642 -0.249642)
							(end -0.2794 -0.1778)
						)
						(arc
							(start -0.2794 0.1778)
							(mid -0.249642 0.249642)
							(end -0.1778 0.2794)
						)
						(arc
							(start 0.1778 0.2794)
							(mid 0.249642 0.249642)
							(end 0.2794 0.1778)
						)
						(arc
							(start 0.2794 -0.1778)
							(mid 0.249642 -0.249642)
							(end 0.1778 -0.2794)
						)
					)
					(width 0)
					(fill yes)
				)
			)
		)
	)
	(footprint ""
		(layer "F.Cu")
		(at 90.59672 -149.190456 180)
		(property "Reference" "R24"
			(at 0 0 180)
			(layer "F.SilkS")
			(hide yes)
			(effects
				(font
					(size 1.27 1.27)
				)
			)
		)
		(property "Value" "10KR2F-2-GP"
			(at 0.064008 -3.993896 180)
			(unlocked yes)
			(layer "F.Fab")
			(hide yes)
			(effects
				(font
					(size 1.016 1.016)
					(thickness 0.1524)
				)
			)
		)
		(property "Device Type" "R402H16"
			(at 0.064008 -5.517896 180)
			(unlocked yes)
			(layer "F.Fab")
			(hide yes)
			(effects
				(font
					(size 1.016 1.016)
					(thickness 0.1524)
				)
			)
		)
		(duplicate_pad_numbers_are_jumpers no)
		(fp_line
			(start 0.508 -0.9398)
			(end -0.508 -0.9398)
			(stroke
				(width 0.1524)
				(type default)
			)
			(layer "F.SilkS")
		)
		(fp_line
			(start -0.508 -0.9398)
			(end -0.508 0.9398)
			(stroke
				(width 0.1524)
				(type default)
			)
			(layer "F.SilkS")
		)
		(fp_rect
			(start -0.508 0.9398)
			(end 0.508 -0.9398)
			(stroke
				(width 0)
				(type default)
			)
			(fill no)
			(layer "F.CrtYd")
		)
		(fp_rect
			(start -0.508 0.9398)
			(end 0.508 -0.9398)
			(stroke
				(width 0)
				(type default)
			)
			(fill no)
			(layer "F.Fab")
		)
		(pad "1" smd custom
			(at 0 -0.4445 180)
			(size 0.1397 0.1397)
			(layers "F.Cu" "F.Mask" "F.Paste")
			(net "P3V3_STBY")
			(options
				(clearance outline)
				(anchor circle)
			)
			(primitives
				(gr_poly
					(pts
						(arc
							(start -0.1778 -0.2794)
							(mid -0.249642 -0.249642)
							(end -0.2794 -0.1778)
						)
						(arc
							(start -0.2794 0.1778)
							(mid -0.249642 0.249642)
							(end -0.1778 0.2794)
						)
						(arc
							(start 0.1778 0.2794)
							(mid 0.249642 0.249642)
							(end 0.2794 0.1778)
						)
						(arc
							(start 0.2794 -0.1778)
							(mid 0.249642 -0.249642)
							(end 0.1778 -0.2794)
						)
					)
					(width 0)
					(fill yes)
				)
			)
		)
		(pad "2" smd custom
			(at 0 0.4445 180)
			(size 0.1397 0.1397)
			(layers "F.Cu" "F.Mask" "F.Paste")
			(net "USB_OCS_N1")
			(options
				(clearance outline)
				(anchor circle)
			)
			(primitives
				(gr_poly
					(pts
						(arc
							(start -0.1778 -0.2794)
							(mid -0.249642 -0.249642)
							(end -0.2794 -0.1778)
						)
						(arc
							(start -0.2794 0.1778)
							(mid -0.249642 0.249642)
							(end -0.1778 0.2794)
						)
						(arc
							(start 0.1778 0.2794)
							(mid 0.249642 0.249642)
							(end 0.2794 0.1778)
						)
						(arc
							(start 0.2794 -0.1778)
							(mid 0.249642 -0.249642)
							(end 0.1778 -0.2794)
						)
					)
					(width 0)
					(fill yes)
				)
			)
		)
	)
	(footprint ""
		(layer "F.Cu")
		(at 59.845956 -154.934412)
		(property "Reference" "TP50"
			(at 0 0 0)
			(layer "F.SilkS")
			(hide yes)
			(effects
				(font
					(size 1.27 1.27)
				)
			)
		)
		(property "Value" "TPAD28-2-GP"
			(at -0.0127 -1.6637 0)
			(unlocked yes)
			(layer "F.Fab")
			(hide yes)
			(effects
				(font
					(size 1.016 1.016)
					(thickness 0.1524)
				)
			)
		)
		(property "Device Type" "TPAD28"
			(at -0.0127 -3.1877 0)
			(unlocked yes)
			(layer "F.Fab")
			(hide yes)
			(effects
				(font
					(size 1.016 1.016)
					(thickness 0.1524)
				)
			)
		)
		(duplicate_pad_numbers_are_jumpers no)
		(fp_poly
			(pts
				(arc
					(start 0.3556 0)
					(mid -0.3556 0)
					(end 0.3556 0)
				)
			)
			(stroke
				(width 0)
				(type default)
			)
			(fill no)
			(layer "F.CrtYd")
		)
		(fp_poly
			(pts
				(arc
					(start 0.6096 0)
					(mid -0.6096 0)
					(end 0.6096 0)
				)
			)
			(stroke
				(width 0)
				(type default)
			)
			(fill no)
			(layer "F.Fab")
		)
		(pad "1" smd circle
			(at 0 0)
			(size 0.7112 0.7112)
			(layers "F.Cu" "F.Mask" "F.Paste")
			(net "TP_BMC_GPIOT0")
		)
	)
	(footprint ""
		(layer "F.Cu")
		(at 223.123506 -102.291642 180)
		(property "Reference" "C659"
			(at 0 0 180)
			(layer "F.SilkS")
			(hide yes)
			(effects
				(font
					(size 1.27 1.27)
				)
			)
		)
		(property "Value" "SCD1U16V2KX-3GP"
			(at 1.1811 -2.7051 180)
			(unlocked yes)
			(layer "F.Fab")
			(hide yes)
			(effects
				(font
					(size 1.016 1.016)
					(thickness 0.1524)
				)
			)
		)
		(property "Device Type" "C402H22"
			(at 1.1811 -4.2291 180)
			(unlocked yes)
			(layer "F.Fab")
			(hide yes)
			(effects
				(font
					(size 1.016 1.016)
					(thickness 0.1524)
				)
			)
		)
		(duplicate_pad_numbers_are_jumpers no)
		(fp_rect
			(start -0.4318 0.9525)
			(end 0.4318 -0.9525)
			(stroke
				(width 0)
				(type default)
			)
			(fill no)
			(layer "F.CrtYd")
		)
		(fp_rect
			(start -0.4318 0.9525)
			(end 0.4318 -0.9525)
			(stroke
				(width 0)
				(type default)
			)
			(fill no)
			(layer "F.Fab")
		)
		(pad "1" smd custom
			(at 0 -0.4445 180)
			(size 0.1524 0.1524)
			(layers "F.Cu" "F.Mask" "F.Paste")
			(net "P12V_STBY_VIN_U81")
			(options
				(clearance outline)
				(anchor circle)
			)
			(primitives
				(gr_poly
					(pts
						(arc
							(start 0.3048 -0.2032)
							(mid 0.275042 -0.275042)
							(end 0.2032 -0.3048)
						)
						(arc
							(start -0.2032 -0.3048)
							(mid -0.275042 -0.275042)
							(end -0.3048 -0.2032)
						)
						(arc
							(start -0.3048 0.2032)
							(mid -0.275042 0.275042)
							(end -0.2032 0.3048)
						)
						(arc
							(start 0.2032 0.3048)
							(mid 0.275042 0.275042)
							(end 0.3048 0.2032)
						)
					)
					(width 0)
					(fill yes)
				)
			)
		)
		(pad "2" smd custom
			(at 0 0.4445 180)
			(size 0.1524 0.1524)
			(layers "F.Cu" "F.Mask" "F.Paste")
			(net "GND")
			(options
				(clearance outline)
				(anchor circle)
			)
			(primitives
				(gr_poly
					(pts
						(arc
							(start 0.3048 -0.2032)
							(mid 0.275042 -0.275042)
							(end 0.2032 -0.3048)
						)
						(arc
							(start -0.2032 -0.3048)
							(mid -0.275042 -0.275042)
							(end -0.3048 -0.2032)
						)
						(arc
							(start -0.3048 0.2032)
							(mid -0.275042 0.275042)
							(end -0.2032 0.3048)
						)
						(arc
							(start 0.2032 0.3048)
							(mid 0.275042 0.275042)
							(end 0.3048 0.2032)
						)
					)
					(width 0)
					(fill yes)
				)
			)
		)
	)
	(footprint ""
		(layer "F.Cu")
		(at 22.014942 -129.1082 180)
		(property "Reference" "R213"
			(at 0 0 180)
			(layer "F.SilkS")
			(hide yes)
			(effects
				(font
					(size 1.27 1.27)
				)
			)
		)
		(property "Value" "120R2F-GP"
			(at 0.064008 -3.993896 180)
			(unlocked yes)
			(layer "F.Fab")
			(hide yes)
			(effects
				(font
					(size 1.016 1.016)
					(thickness 0.1524)
				)
			)
		)
		(property "Device Type" "R402H16"
			(at 0.064008 -5.517896 180)
			(unlocked yes)
			(layer "F.Fab")
			(hide yes)
			(effects
				(font
					(size 1.016 1.016)
					(thickness 0.1524)
				)
			)
		)
		(duplicate_pad_numbers_are_jumpers no)
		(fp_line
			(start 0.508 -0.9398)
			(end -0.508 -0.9398)
			(stroke
				(width 0.1524)
				(type default)
			)
			(layer "F.SilkS")
		)
		(fp_line
			(start -0.508 -0.9398)
			(end -0.508 0.9398)
			(stroke
				(width 0.1524)
				(type default)
			)
			(layer "F.SilkS")
		)
		(fp_rect
			(start -0.508 0.9398)
			(end 0.508 -0.9398)
			(stroke
				(width 0)
				(type default)
			)
			(fill no)
			(layer "F.CrtYd")
		)
		(fp_rect
			(start -0.508 0.9398)
			(end 0.508 -0.9398)
			(stroke
				(width 0)
				(type default)
			)
			(fill no)
			(layer "F.Fab")
		)
		(pad "1" smd custom
			(at 0 -0.4445 180)
			(size 0.1397 0.1397)
			(layers "F.Cu" "F.Mask" "F.Paste")
			(net "GND")
			(options
				(clearance outline)
				(anchor circle)
			)
			(primitives
				(gr_poly
					(pts
						(arc
							(start -0.1778 -0.2794)
							(mid -0.249642 -0.249642)
							(end -0.2794 -0.1778)
						)
						(arc
							(start -0.2794 0.1778)
							(mid -0.249642 0.249642)
							(end -0.1778 0.2794)
						)
						(arc
							(start 0.1778 0.2794)
							(mid 0.249642 0.249642)
							(end 0.2794 0.1778)
						)
						(arc
							(start 0.2794 -0.1778)
							(mid 0.249642 -0.249642)
							(end 0.1778 -0.2794)
						)
					)
					(width 0)
					(fill yes)
				)
			)
		)
		(pad "2" smd custom
			(at 0 0.4445 180)
			(size 0.1397 0.1397)
			(layers "F.Cu" "F.Mask" "F.Paste")
			(net "DDR4_ALERT")
			(options
				(clearance outline)
				(anchor circle)
			)
			(primitives
				(gr_poly
					(pts
						(arc
							(start -0.1778 -0.2794)
							(mid -0.249642 -0.249642)
							(end -0.2794 -0.1778)
						)
						(arc
							(start -0.2794 0.1778)
							(mid -0.249642 0.249642)
							(end -0.1778 0.2794)
						)
						(arc
							(start 0.1778 0.2794)
							(mid 0.249642 0.249642)
							(end 0.2794 0.1778)
						)
						(arc
							(start 0.2794 -0.1778)
							(mid 0.249642 -0.249642)
							(end 0.1778 -0.2794)
						)
					)
					(width 0)
					(fill yes)
				)
			)
		)
	)
	(footprint ""
		(layer "F.Cu")
		(at 72.22998 -164.586412 90)
		(property "Reference" "R541"
			(at 0 0 90)
			(layer "F.SilkS")
			(hide yes)
			(effects
				(font
					(size 1.27 1.27)
				)
			)
		)
		(property "Value" "4K75R2F-1-GP"
			(at 0.064008 -3.993896 90)
			(unlocked yes)
			(layer "F.Fab")
			(hide yes)
			(effects
				(font
					(size 1.016 1.016)
					(thickness 0.1524)
				)
			)
		)
		(property "Device Type" "R402H16"
			(at 0.064008 -5.517896 90)
			(unlocked yes)
			(layer "F.Fab")
			(hide yes)
			(effects
				(font
					(size 1.016 1.016)
					(thickness 0.1524)
				)
			)
		)
		(duplicate_pad_numbers_are_jumpers no)
		(fp_line
			(start 0.508 -0.9398)
			(end -0.508 -0.9398)
			(stroke
				(width 0.1524)
				(type default)
			)
			(layer "F.SilkS")
		)
		(fp_line
			(start -0.508 -0.9398)
			(end -0.508 0.9398)
			(stroke
				(width 0.1524)
				(type default)
			)
			(layer "F.SilkS")
		)
		(fp_rect
			(start -0.508 0.9398)
			(end 0.508 -0.9398)
			(stroke
				(width 0)
				(type default)
			)
			(fill no)
			(layer "F.CrtYd")
		)
		(fp_rect
			(start -0.508 0.9398)
			(end 0.508 -0.9398)
			(stroke
				(width 0)
				(type default)
			)
			(fill no)
			(layer "F.Fab")
		)
		(pad "1" smd custom
			(at 0 -0.4445 90)
			(size 0.1397 0.1397)
			(layers "F.Cu" "F.Mask" "F.Paste")
			(net "P3V3_STBY")
			(options
				(clearance outline)
				(anchor circle)
			)
			(primitives
				(gr_poly
					(pts
						(arc
							(start -0.1778 -0.2794)
							(mid -0.249642 -0.249642)
							(end -0.2794 -0.1778)
						)
						(arc
							(start -0.2794 0.1778)
							(mid -0.249642 0.249642)
							(end -0.1778 0.2794)
						)
						(arc
							(start 0.1778 0.2794)
							(mid 0.249642 0.249642)
							(end 0.2794 0.1778)
						)
						(arc
							(start 0.2794 -0.1778)
							(mid 0.249642 -0.249642)
							(end 0.1778 -0.2794)
						)
					)
					(width 0)
					(fill yes)
				)
			)
		)
		(pad "2" smd custom
			(at 0 0.4445 90)
			(size 0.1397 0.1397)
			(layers "F.Cu" "F.Mask" "F.Paste")
			(net "TPS74801_P1V15_STBY_EN")
			(options
				(clearance outline)
				(anchor circle)
			)
			(primitives
				(gr_poly
					(pts
						(arc
							(start -0.1778 -0.2794)
							(mid -0.249642 -0.249642)
							(end -0.2794 -0.1778)
						)
						(arc
							(start -0.2794 0.1778)
							(mid -0.249642 0.249642)
							(end -0.1778 0.2794)
						)
						(arc
							(start 0.1778 0.2794)
							(mid 0.249642 0.249642)
							(end 0.2794 0.1778)
						)
						(arc
							(start 0.2794 -0.1778)
							(mid 0.249642 -0.249642)
							(end 0.1778 -0.2794)
						)
					)
					(width 0)
					(fill yes)
				)
			)
		)
	)
	(footprint ""
		(layer "F.Cu")
		(at 39.1922 -179.12461)
		(property "Reference" "R491"
			(at 0 0 0)
			(layer "F.SilkS")
			(hide yes)
			(effects
				(font
					(size 1.27 1.27)
				)
			)
		)
		(property "Value" "15KR2F-GP"
			(at 0.064008 -3.993896 0)
			(unlocked yes)
			(layer "F.Fab")
			(hide yes)
			(effects
				(font
					(size 1.016 1.016)
					(thickness 0.1524)
				)
			)
		)
		(property "Device Type" "R402H16"
			(at 0.064008 -5.517896 0)
			(unlocked yes)
			(layer "F.Fab")
			(hide yes)
			(effects
				(font
					(size 1.016 1.016)
					(thickness 0.1524)
				)
			)
		)
		(duplicate_pad_numbers_are_jumpers no)
		(fp_line
			(start -0.508 -0.9398)
			(end -0.508 0.9398)
			(stroke
				(width 0.1524)
				(type default)
			)
			(layer "F.SilkS")
		)
		(fp_line
			(start 0.508 -0.9398)
			(end -0.508 -0.9398)
			(stroke
				(width 0.1524)
				(type default)
			)
			(layer "F.SilkS")
		)
		(fp_rect
			(start -0.508 0.9398)
			(end 0.508 -0.9398)
			(stroke
				(width 0)
				(type default)
			)
			(fill no)
			(layer "F.CrtYd")
		)
		(fp_rect
			(start -0.508 0.9398)
			(end 0.508 -0.9398)
			(stroke
				(width 0)
				(type default)
			)
			(fill no)
			(layer "F.Fab")
		)
		(pad "1" smd custom
			(at 0 -0.4445)
			(size 0.1397 0.1397)
			(layers "F.Cu" "F.Mask" "F.Paste")
			(net "PWRGD_P3V3_STBY")
			(options
				(clearance outline)
				(anchor circle)
			)
			(primitives
				(gr_poly
					(pts
						(arc
							(start -0.1778 -0.2794)
							(mid -0.249642 -0.249642)
							(end -0.2794 -0.1778)
						)
						(arc
							(start -0.2794 0.1778)
							(mid -0.249642 0.249642)
							(end -0.1778 0.2794)
						)
						(arc
							(start 0.1778 0.2794)
							(mid 0.249642 0.249642)
							(end 0.2794 0.1778)
						)
						(arc
							(start 0.2794 -0.1778)
							(mid 0.249642 -0.249642)
							(end 0.1778 -0.2794)
						)
					)
					(width 0)
					(fill yes)
				)
			)
		)
		(pad "2" smd custom
			(at 0 0.4445)
			(size 0.1397 0.1397)
			(layers "F.Cu" "F.Mask" "F.Paste")
			(net "GND")
			(options
				(clearance outline)
				(anchor circle)
			)
			(primitives
				(gr_poly
					(pts
						(arc
							(start -0.1778 -0.2794)
							(mid -0.249642 -0.249642)
							(end -0.2794 -0.1778)
						)
						(arc
							(start -0.2794 0.1778)
							(mid -0.249642 0.249642)
							(end -0.1778 0.2794)
						)
						(arc
							(start 0.1778 0.2794)
							(mid 0.249642 0.249642)
							(end 0.2794 0.1778)
						)
						(arc
							(start 0.2794 -0.1778)
							(mid 0.249642 -0.249642)
							(end 0.1778 -0.2794)
						)
					)
					(width 0)
					(fill yes)
				)
			)
		)
	)
	(footprint ""
		(layer "F.Cu")
		(at 41.719246 -177.14341)
		(property "Reference" "R485"
			(at 0 0 0)
			(layer "F.SilkS")
			(hide yes)
			(effects
				(font
					(size 1.27 1.27)
				)
			)
		)
		(property "Value" "0R2J-2-GP"
			(at 0.064008 -3.993896 0)
			(unlocked yes)
			(layer "F.Fab")
			(hide yes)
			(effects
				(font
					(size 1.016 1.016)
					(thickness 0.1524)
				)
			)
		)
		(property "Device Type" "R402H16"
			(at 0.064008 -5.517896 0)
			(unlocked yes)
			(layer "F.Fab")
			(hide yes)
			(effects
				(font
					(size 1.016 1.016)
					(thickness 0.1524)
				)
			)
		)
		(duplicate_pad_numbers_are_jumpers no)
		(fp_line
			(start -0.508 -0.9398)
			(end -0.508 0.9398)
			(stroke
				(width 0.1524)
				(type default)
			)
			(layer "F.SilkS")
		)
		(fp_line
			(start 0.508 -0.9398)
			(end -0.508 -0.9398)
			(stroke
				(width 0.1524)
				(type default)
			)
			(layer "F.SilkS")
		)
		(fp_rect
			(start -0.508 0.9398)
			(end 0.508 -0.9398)
			(stroke
				(width 0)
				(type default)
			)
			(fill no)
			(layer "F.CrtYd")
		)
		(fp_rect
			(start -0.508 0.9398)
			(end 0.508 -0.9398)
			(stroke
				(width 0)
				(type default)
			)
			(fill no)
			(layer "F.Fab")
		)
		(pad "1" smd custom
			(at 0 -0.4445)
			(size 0.1397 0.1397)
			(layers "F.Cu" "F.Mask" "F.Paste")
			(net "P3V3_STBY_EN")
			(options
				(clearance outline)
				(anchor circle)
			)
			(primitives
				(gr_poly
					(pts
						(arc
							(start -0.1778 -0.2794)
							(mid -0.249642 -0.249642)
							(end -0.2794 -0.1778)
						)
						(arc
							(start -0.2794 0.1778)
							(mid -0.249642 0.249642)
							(end -0.1778 0.2794)
						)
						(arc
							(start 0.1778 0.2794)
							(mid 0.249642 0.249642)
							(end 0.2794 0.1778)
						)
						(arc
							(start 0.2794 -0.1778)
							(mid 0.249642 -0.249642)
							(end 0.1778 -0.2794)
						)
					)
					(width 0)
					(fill yes)
				)
			)
		)
		(pad "2" smd custom
			(at 0 0.4445)
			(size 0.1397 0.1397)
			(layers "F.Cu" "F.Mask" "F.Paste")
			(net "PWRGD_P5V_STBY")
			(options
				(clearance outline)
				(anchor circle)
			)
			(primitives
				(gr_poly
					(pts
						(arc
							(start -0.1778 -0.2794)
							(mid -0.249642 -0.249642)
							(end -0.2794 -0.1778)
						)
						(arc
							(start -0.2794 0.1778)
							(mid -0.249642 0.249642)
							(end -0.1778 0.2794)
						)
						(arc
							(start 0.1778 0.2794)
							(mid 0.249642 0.249642)
							(end 0.2794 0.1778)
						)
						(arc
							(start 0.2794 -0.1778)
							(mid 0.249642 -0.249642)
							(end 0.1778 -0.2794)
						)
					)
					(width 0)
					(fill yes)
				)
			)
		)
	)
	(footprint ""
		(layer "F.Cu")
		(at 84.983828 -91.750896 90)
		(property "Reference" "VIA15"
			(at 0 0 90)
			(layer "F.SilkS")
			(hide yes)
			(effects
				(font
					(size 1.27 1.27)
				)
			)
		)
		(property "Value" "85OHM-8L-1D6MM-L16L18-GP"
			(at 4.064 0.6096 90)
			(unlocked yes)
			(layer "F.Fab")
			(hide yes)
			(effects
				(font
					(size 1.016 1.016)
					(thickness 0.1524)
				)
			)
		)
		(property "Device Type" "VIA-PCIE-4P-368076"
			(at 4.064 -0.9144 90)
			(unlocked yes)
			(layer "F.Fab")
			(hide yes)
			(effects
				(font
					(size 1.016 1.016)
					(thickness 0.1524)
				)
			)
		)
		(duplicate_pad_numbers_are_jumpers no)
		(fp_rect
			(start -1.8415 0.381)
			(end 1.8415 -0.381)
			(stroke
				(width 0)
				(type default)
			)
			(fill no)
			(layer "F.CrtYd")
		)
		(fp_rect
			(start -1.8415 0.381)
			(end 1.8415 -0.381)
			(stroke
				(width 0)
				(type default)
			)
			(fill no)
			(layer "F.Fab")
		)
		(pad "1" thru_hole circle
			(at -1.4605 0 90)
			(size 0.508 0.508)
			(drill 0.254)
			(layers "*.Cu" "*.Mask")
			(remove_unused_layers no)
			(net "GND")
			(clearance 0.127)
			(thermal_gap 0.127)
		)
		(pad "2" thru_hole circle
			(at -0.4445 0 90)
			(size 0.508 0.508)
			(drill 0.254)
			(layers "*.Cu" "*.Mask")
			(remove_unused_layers no)
			(net "PCIE_IOM_TO_COMP_22_DP")
			(clearance 0.127)
			(thermal_gap 0.127)
		)
		(pad "3" thru_hole circle
			(at 0.4445 0 90)
			(size 0.508 0.508)
			(drill 0.254)
			(layers "*.Cu" "*.Mask")
			(remove_unused_layers no)
			(net "PCIE_IOM_TO_COMP_22_DN")
			(clearance 0.127)
			(thermal_gap 0.127)
		)
		(pad "4" thru_hole circle
			(at 1.4605 0 90)
			(size 0.508 0.508)
			(drill 0.254)
			(layers "*.Cu" "*.Mask")
			(remove_unused_layers no)
			(net "GND")
			(clearance 0.127)
			(thermal_gap 0.127)
		)
	)
	(footprint ""
		(layer "F.Cu")
		(at 36.046156 -132.470652)
		(property "Reference" "R312"
			(at 0 0 0)
			(layer "F.SilkS")
			(hide yes)
			(effects
				(font
					(size 1.27 1.27)
				)
			)
		)
		(property "Value" "0R2J-2-GP"
			(at 0.064008 -3.993896 0)
			(unlocked yes)
			(layer "F.Fab")
			(hide yes)
			(effects
				(font
					(size 1.016 1.016)
					(thickness 0.1524)
				)
			)
		)
		(property "Device Type" "R402H16"
			(at 0.064008 -5.517896 0)
			(unlocked yes)
			(layer "F.Fab")
			(hide yes)
			(effects
				(font
					(size 1.016 1.016)
					(thickness 0.1524)
				)
			)
		)
		(duplicate_pad_numbers_are_jumpers no)
		(fp_line
			(start -0.508 -0.9398)
			(end -0.508 0.9398)
			(stroke
				(width 0.1524)
				(type default)
			)
			(layer "F.SilkS")
		)
		(fp_line
			(start 0.508 -0.9398)
			(end -0.508 -0.9398)
			(stroke
				(width 0.1524)
				(type default)
			)
			(layer "F.SilkS")
		)
		(fp_rect
			(start -0.508 0.9398)
			(end 0.508 -0.9398)
			(stroke
				(width 0)
				(type default)
			)
			(fill no)
			(layer "F.CrtYd")
		)
		(fp_rect
			(start -0.508 0.9398)
			(end 0.508 -0.9398)
			(stroke
				(width 0)
				(type default)
			)
			(fill no)
			(layer "F.Fab")
		)
		(pad "1" smd custom
			(at 0 -0.4445)
			(size 0.1397 0.1397)
			(layers "F.Cu" "F.Mask" "F.Paste")
			(net "CLKIN_24M_BMC")
			(options
				(clearance outline)
				(anchor circle)
			)
			(primitives
				(gr_poly
					(pts
						(arc
							(start -0.1778 -0.2794)
							(mid -0.249642 -0.249642)
							(end -0.2794 -0.1778)
						)
						(arc
							(start -0.2794 0.1778)
							(mid -0.249642 0.249642)
							(end -0.1778 0.2794)
						)
						(arc
							(start 0.1778 0.2794)
							(mid 0.249642 0.249642)
							(end 0.2794 0.1778)
						)
						(arc
							(start 0.2794 -0.1778)
							(mid 0.249642 -0.249642)
							(end 0.1778 -0.2794)
						)
					)
					(width 0)
					(fill yes)
				)
			)
		)
		(pad "2" smd custom
			(at 0 0.4445)
			(size 0.1397 0.1397)
			(layers "F.Cu" "F.Mask" "F.Paste")
			(net "OSC_OUT")
			(options
				(clearance outline)
				(anchor circle)
			)
			(primitives
				(gr_poly
					(pts
						(arc
							(start -0.1778 -0.2794)
							(mid -0.249642 -0.249642)
							(end -0.2794 -0.1778)
						)
						(arc
							(start -0.2794 0.1778)
							(mid -0.249642 0.249642)
							(end -0.1778 0.2794)
						)
						(arc
							(start 0.1778 0.2794)
							(mid 0.249642 0.249642)
							(end 0.2794 0.1778)
						)
						(arc
							(start 0.2794 -0.1778)
							(mid 0.249642 -0.249642)
							(end 0.1778 -0.2794)
						)
					)
					(width 0)
					(fill yes)
				)
			)
		)
	)
	(footprint ""
		(layer "F.Cu")
		(at 60.9092 -121.3612 -90)
		(property "Reference" "SKT2"
			(at 0 0 270)
			(layer "F.SilkS")
			(hide yes)
			(effects
				(font
					(size 1.27 1.27)
				)
			)
		)
		(property "Value" "SKT-SPI16P-GP-U"
			(at -8.9916 4.641596 270)
			(unlocked yes)
			(layer "F.Fab")
			(hide yes)
			(effects
				(font
					(size 1.016 1.016)
					(thickness 0.1524)
				)
			)
		)
		(property "Device Type" "SKT-SOIC16-153139H258"
			(at -8.9916 3.117596 270)
			(unlocked yes)
			(layer "F.Fab")
			(hide yes)
			(effects
				(font
					(size 1.016 1.016)
					(thickness 0.1524)
				)
			)
		)
		(duplicate_pad_numbers_are_jumpers no)
		(fp_line
			(start -7.8994 6.4008)
			(end 7.8994 6.4008)
			(stroke
				(width 0.1524)
				(type default)
			)
			(layer "F.SilkS")
		)
		(fp_line
			(start 7.8994 6.4008)
			(end 7.8994 -6.4008)
			(stroke
				(width 0.1524)
				(type default)
			)
			(layer "F.SilkS")
		)
		(fp_line
			(start 6.7183 0.0762)
			(end 7.8994 1.2573)
			(stroke
				(width 0.1524)
				(type default)
			)
			(layer "F.SilkS")
		)
		(fp_line
			(start 7.8867 -1.0922)
			(end 6.7183 0.0762)
			(stroke
				(width 0.1524)
				(type default)
			)
			(layer "F.SilkS")
		)
		(fp_line
			(start 7.7216 -6.223)
			(end 7.7216 -3.6576)
			(stroke
				(width 0.508)
				(type default)
			)
			(layer "F.SilkS")
		)
		(fp_line
			(start -7.8994 -6.4008)
			(end -7.8994 6.4008)
			(stroke
				(width 0.1524)
				(type default)
			)
			(layer "F.SilkS")
		)
		(fp_line
			(start 7.8994 -6.4008)
			(end -7.8994 -6.4008)
			(stroke
				(width 0.1524)
				(type default)
			)
			(layer "F.SilkS")
		)
		(fp_poly
			(pts
				(xy -4.699 -3.855466) (xy -4.699 3.855466) (xy 4.699 3.855466) (xy 4.699 -3.855466)
			)
			(stroke
				(width 0)
				(type default)
			)
			(fill yes)
			(layer "F.SilkS")
		)
		(fp_rect
			(start -8.1534 11.6078)
			(end 8.1534 6.4008)
			(stroke
				(width 0)
				(type default)
			)
			(fill no)
			(layer "F.CrtYd")
		)
		(fp_rect
			(start -8.1534 -6.4008)
			(end 8.1534 -12.5222)
			(stroke
				(width 0)
				(type default)
			)
			(fill no)
			(layer "F.CrtYd")
		)
		(fp_poly
			(pts
				(xy -8.1534 6.4008) (xy -8.1534 -6.4008) (xy -6.2484 -6.4008) (xy -6.2484 -2.6416) (xy -7.6454 -2.6416)
				(xy -7.6454 2.6416) (xy -6.2484 2.6416) (xy -6.2484 6.4008)
			)
			(stroke
				(width 0)
				(type default)
			)
			(fill no)
			(layer "F.CrtYd")
		)
		(fp_poly
			(pts
				(xy 6.2484 -6.4008) (xy 8.1534 -6.4008) (xy 8.1534 6.4008) (xy 6.2484 6.4008) (xy 6.2484 2.6416)
				(xy 7.6454 2.6416) (xy 7.6454 -2.6416) (xy 6.2484 -2.6416)
			)
			(stroke
				(width 0)
				(type default)
			)
			(fill no)
			(layer "F.CrtYd")
		)
		(fp_poly
			(pts
				(xy 6.2484 -6.4008) (xy -6.2484 -6.4008) (xy -6.2484 -2.6416) (xy -7.6454 -2.6416) (xy -7.6454 2.6416)
				(xy -6.2484 2.6416) (xy -6.2484 6.4008) (xy 6.2484 6.4008) (xy 6.2484 2.6416) (xy 7.6454 2.6416)
				(xy 7.6454 -2.6416) (xy 6.2484 -2.6416)
			)
			(stroke
				(width 0)
				(type default)
			)
			(fill no)
			(layer "F.CrtYd")
		)
		(fp_rect
			(start -8.1534 11.6078)
			(end 8.1534 -12.5222)
			(stroke
				(width 0)
				(type default)
			)
			(fill no)
			(layer "F.Fab")
		)
		(pad "1" smd rect
			(at 4.445 -4.896866 270)
			(size 0.508 1.6764)
			(layers "F.Cu" "F.Mask" "F.Paste")
			(net "PU_IBMC_BT_HOLD_N")
		)
		(pad "2" smd rect
			(at 3.175 -4.896866 270)
			(size 0.508 1.6764)
			(layers "F.Cu" "F.Mask" "F.Paste")
			(net "P3V3_STBY")
		)
		(pad "3" smd rect
			(at 1.905 -4.896866 270)
			(size 0.508 1.6764)
			(layers "F.Cu" "F.Mask" "F.Paste")
			(net "FLA1_SPI_RST")
		)
		(pad "4" smd rect
			(at 0.635 -4.896866 270)
			(size 0.508 1.6764)
			(layers "F.Cu" "F.Mask" "F.Paste")
			(net "Net_583")
		)
		(pad "5" smd rect
			(at -0.635 -4.896866 270)
			(size 0.508 1.6764)
			(layers "F.Cu" "F.Mask" "F.Paste")
			(net "Net_582")
		)
		(pad "6" smd rect
			(at -1.905 -4.896866 270)
			(size 0.508 1.6764)
			(layers "F.Cu" "F.Mask" "F.Paste")
			(net "Net_581")
		)
		(pad "7" smd rect
			(at -3.175 -4.896866 270)
			(size 0.508 1.6764)
			(layers "F.Cu" "F.Mask" "F.Paste")
			(net "FLA_CS_1_R")
		)
		(pad "8" smd rect
			(at -4.445 -4.896866 270)
			(size 0.508 1.6764)
			(layers "F.Cu" "F.Mask" "F.Paste")
			(net "BMC_SPI_MISO_R")
		)
		(pad "9" smd rect
			(at -4.445 4.896866 270)
			(size 0.508 1.6764)
			(layers "F.Cu" "F.Mask" "F.Paste")
			(net "FLA1_WP_N")
		)
		(pad "10" smd rect
			(at -3.175 4.896866 270)
			(size 0.508 1.6764)
			(layers "F.Cu" "F.Mask" "F.Paste")
			(net "GND")
		)
		(pad "11" smd rect
			(at -1.905 4.896866 270)
			(size 0.508 1.6764)
			(layers "F.Cu" "F.Mask" "F.Paste")
			(net "Net_587")
		)
		(pad "12" smd rect
			(at -0.635 4.896866 270)
			(size 0.508 1.6764)
			(layers "F.Cu" "F.Mask" "F.Paste")
			(net "Net_586")
		)
		(pad "13" smd rect
			(at 0.635 4.896866 270)
			(size 0.508 1.6764)
			(layers "F.Cu" "F.Mask" "F.Paste")
			(net "Net_585")
		)
		(pad "14" smd rect
			(at 1.905 4.896866 270)
			(size 0.508 1.6764)
			(layers "F.Cu" "F.Mask" "F.Paste")
			(net "Net_584")
		)
		(pad "15" smd rect
			(at 3.175 4.896866 270)
			(size 0.508 1.6764)
			(layers "F.Cu" "F.Mask" "F.Paste")
			(net "BMC_SPI_MOSI_R")
		)
		(pad "16" smd rect
			(at 4.445 4.896866 270)
			(size 0.508 1.6764)
			(layers "F.Cu" "F.Mask" "F.Paste")
			(net "BMC_SPI_CLK_R")
		)
	)
	(footprint ""
		(layer "F.Cu")
		(at 63.9826 -156.2354)
		(property "Reference" "R382"
			(at 0 0 0)
			(layer "F.SilkS")
			(hide yes)
			(effects
				(font
					(size 1.27 1.27)
				)
			)
		)
		(property "Value" "4K7R2F-GP"
			(at 0.064008 -3.993896 0)
			(unlocked yes)
			(layer "F.Fab")
			(hide yes)
			(effects
				(font
					(size 1.016 1.016)
					(thickness 0.1524)
				)
			)
		)
		(property "Device Type" "R402H16"
			(at 0.064008 -5.517896 0)
			(unlocked yes)
			(layer "F.Fab")
			(hide yes)
			(effects
				(font
					(size 1.016 1.016)
					(thickness 0.1524)
				)
			)
		)
		(duplicate_pad_numbers_are_jumpers no)
		(fp_line
			(start -0.508 -0.9398)
			(end -0.508 0.9398)
			(stroke
				(width 0.1524)
				(type default)
			)
			(layer "F.SilkS")
		)
		(fp_line
			(start 0.508 -0.9398)
			(end -0.508 -0.9398)
			(stroke
				(width 0.1524)
				(type default)
			)
			(layer "F.SilkS")
		)
		(fp_rect
			(start -0.508 0.9398)
			(end 0.508 -0.9398)
			(stroke
				(width 0)
				(type default)
			)
			(fill no)
			(layer "F.CrtYd")
		)
		(fp_rect
			(start -0.508 0.9398)
			(end 0.508 -0.9398)
			(stroke
				(width 0)
				(type default)
			)
			(fill no)
			(layer "F.Fab")
		)
		(pad "1" smd custom
			(at 0 -0.4445)
			(size 0.1397 0.1397)
			(layers "F.Cu" "F.Mask" "F.Paste")
			(net "P3V3_STBY")
			(options
				(clearance outline)
				(anchor circle)
			)
			(primitives
				(gr_poly
					(pts
						(arc
							(start -0.1778 -0.2794)
							(mid -0.249642 -0.249642)
							(end -0.2794 -0.1778)
						)
						(arc
							(start -0.2794 0.1778)
							(mid -0.249642 0.249642)
							(end -0.1778 0.2794)
						)
						(arc
							(start 0.1778 0.2794)
							(mid 0.249642 0.249642)
							(end 0.2794 0.1778)
						)
						(arc
							(start 0.2794 -0.1778)
							(mid 0.249642 -0.249642)
							(end 0.1778 -0.2794)
						)
					)
					(width 0)
					(fill yes)
				)
			)
		)
		(pad "2" smd custom
			(at 0 0.4445)
			(size 0.1397 0.1397)
			(layers "F.Cu" "F.Mask" "F.Paste")
			(net "NCSI_TXD1")
			(options
				(clearance outline)
				(anchor circle)
			)
			(primitives
				(gr_poly
					(pts
						(arc
							(start -0.1778 -0.2794)
							(mid -0.249642 -0.249642)
							(end -0.2794 -0.1778)
						)
						(arc
							(start -0.2794 0.1778)
							(mid -0.249642 0.249642)
							(end -0.1778 0.2794)
						)
						(arc
							(start 0.1778 0.2794)
							(mid 0.249642 0.249642)
							(end 0.2794 0.1778)
						)
						(arc
							(start 0.2794 -0.1778)
							(mid 0.249642 -0.249642)
							(end 0.1778 -0.2794)
						)
					)
					(width 0)
					(fill yes)
				)
			)
		)
	)
	(footprint ""
		(layer "F.Cu")
		(at 21.023072 -15.68577)
		(property "Reference" "D2"
			(at 0 0 0)
			(layer "F.SilkS")
			(hide yes)
			(effects
				(font
					(size 1.27 1.27)
				)
			)
		)
		(property "Value" "PESD5V0X1UAB-GP"
			(at 0 -4.690618 0)
			(unlocked yes)
			(layer "F.Fab")
			(hide yes)
			(effects
				(font
					(size 1.016 1.016)
					(thickness 0.1524)
				)
			)
		)
		(property "Device Type" "SOD523AKH26"
			(at 0 -6.214618 0)
			(unlocked yes)
			(layer "F.Fab")
			(hide yes)
			(effects
				(font
					(size 1.016 1.016)
					(thickness 0.1524)
				)
			)
		)
		(duplicate_pad_numbers_are_jumpers no)
		(fp_line
			(start -0.5334 -1.4478)
			(end 0.5334 -1.4478)
			(stroke
				(width 0.1524)
				(type default)
			)
			(layer "F.SilkS")
		)
		(fp_line
			(start -0.5334 1.524)
			(end -0.5334 -1.4478)
			(stroke
				(width 0.1524)
				(type default)
			)
			(layer "F.SilkS")
		)
		(fp_line
			(start 0.4064 1.651)
			(end -0.4064 1.651)
			(stroke
				(width 0.4064)
				(type default)
			)
			(layer "F.SilkS")
		)
		(fp_line
			(start 0.5334 -1.4478)
			(end 0.5334 1.524)
			(stroke
				(width 0.1524)
				(type default)
			)
			(layer "F.SilkS")
		)
		(fp_line
			(start 0.5334 1.524)
			(end -0.5334 1.524)
			(stroke
				(width 0.1524)
				(type default)
			)
			(layer "F.SilkS")
		)
		(fp_rect
			(start -0.6096 1.8542)
			(end 0.6096 -1.524)
			(stroke
				(width 0)
				(type default)
			)
			(fill no)
			(layer "F.CrtYd")
		)
		(fp_poly
			(pts
				(xy -0.6096 -1.524) (xy 0.6096 -1.524) (xy 0.6096 1.8542) (xy -0.6096 1.8542)
			)
			(stroke
				(width 0)
				(type default)
			)
			(fill no)
			(layer "F.Fab")
		)
		(pad "A" smd rect
			(at 0 -0.762)
			(size 0.5588 1.016)
			(layers "F.Cu" "F.Mask" "F.Paste")
			(net "GND")
		)
		(pad "K" smd rect
			(at 0 0.762)
			(size 0.5588 1.016)
			(layers "F.Cu" "F.Mask" "F.Paste")
			(net "FP_PWR_BTN_N")
		)
	)
	(footprint ""
		(layer "F.Cu")
		(at 151.013414 -7.945374)
		(property "Reference" "R522"
			(at 0 0 0)
			(layer "F.SilkS")
			(hide yes)
			(effects
				(font
					(size 1.27 1.27)
				)
			)
		)
		(property "Value" "0R2J-2-GP"
			(at 0.064008 -3.993896 0)
			(unlocked yes)
			(layer "F.Fab")
			(hide yes)
			(effects
				(font
					(size 1.016 1.016)
					(thickness 0.1524)
				)
			)
		)
		(property "Device Type" "R402H16"
			(at 0.064008 -5.517896 0)
			(unlocked yes)
			(layer "F.Fab")
			(hide yes)
			(effects
				(font
					(size 1.016 1.016)
					(thickness 0.1524)
				)
			)
		)
		(duplicate_pad_numbers_are_jumpers no)
		(fp_line
			(start -0.508 -0.9398)
			(end -0.508 0.9398)
			(stroke
				(width 0.1524)
				(type default)
			)
			(layer "F.SilkS")
		)
		(fp_line
			(start 0.508 -0.9398)
			(end -0.508 -0.9398)
			(stroke
				(width 0.1524)
				(type default)
			)
			(layer "F.SilkS")
		)
		(fp_rect
			(start -0.508 0.9398)
			(end 0.508 -0.9398)
			(stroke
				(width 0)
				(type default)
			)
			(fill no)
			(layer "F.CrtYd")
		)
		(fp_rect
			(start -0.508 0.9398)
			(end 0.508 -0.9398)
			(stroke
				(width 0)
				(type default)
			)
			(fill no)
			(layer "F.Fab")
		)
		(pad "1" smd custom
			(at 0 -0.4445)
			(size 0.1397 0.1397)
			(layers "F.Cu" "F.Mask" "F.Paste")
			(net "P1V8_STBY_EN_R")
			(options
				(clearance outline)
				(anchor circle)
			)
			(primitives
				(gr_poly
					(pts
						(arc
							(start -0.1778 -0.2794)
							(mid -0.249642 -0.249642)
							(end -0.2794 -0.1778)
						)
						(arc
							(start -0.2794 0.1778)
							(mid -0.249642 0.249642)
							(end -0.1778 0.2794)
						)
						(arc
							(start 0.1778 0.2794)
							(mid 0.249642 0.249642)
							(end 0.2794 0.1778)
						)
						(arc
							(start 0.2794 -0.1778)
							(mid 0.249642 -0.249642)
							(end 0.1778 -0.2794)
						)
					)
					(width 0)
					(fill yes)
				)
			)
		)
		(pad "2" smd custom
			(at 0 0.4445)
			(size 0.1397 0.1397)
			(layers "F.Cu" "F.Mask" "F.Paste")
			(net "PWRGD_P2V5_STBY")
			(options
				(clearance outline)
				(anchor circle)
			)
			(primitives
				(gr_poly
					(pts
						(arc
							(start -0.1778 -0.2794)
							(mid -0.249642 -0.249642)
							(end -0.2794 -0.1778)
						)
						(arc
							(start -0.2794 0.1778)
							(mid -0.249642 0.249642)
							(end -0.1778 0.2794)
						)
						(arc
							(start 0.1778 0.2794)
							(mid 0.249642 0.249642)
							(end 0.2794 0.1778)
						)
						(arc
							(start 0.2794 -0.1778)
							(mid 0.249642 -0.249642)
							(end 0.1778 -0.2794)
						)
					)
					(width 0)
					(fill yes)
				)
			)
		)
	)
	(footprint ""
		(layer "F.Cu")
		(at 96.2152 -147.8534 180)
		(property "Reference" "R34"
			(at 0 0 180)
			(layer "F.SilkS")
			(hide yes)
			(effects
				(font
					(size 1.27 1.27)
				)
			)
		)
		(property "Value" "4K7R2F-GP"
			(at 0.064008 -3.993896 180)
			(unlocked yes)
			(layer "F.Fab")
			(hide yes)
			(effects
				(font
					(size 1.016 1.016)
					(thickness 0.1524)
				)
			)
		)
		(property "Device Type" "R402H16"
			(at 0.064008 -5.517896 180)
			(unlocked yes)
			(layer "F.Fab")
			(hide yes)
			(effects
				(font
					(size 1.016 1.016)
					(thickness 0.1524)
				)
			)
		)
		(duplicate_pad_numbers_are_jumpers no)
		(fp_line
			(start 0.508 -0.9398)
			(end -0.508 -0.9398)
			(stroke
				(width 0.1524)
				(type default)
			)
			(layer "F.SilkS")
		)
		(fp_line
			(start -0.508 -0.9398)
			(end -0.508 0.9398)
			(stroke
				(width 0.1524)
				(type default)
			)
			(layer "F.SilkS")
		)
		(fp_rect
			(start -0.508 0.9398)
			(end 0.508 -0.9398)
			(stroke
				(width 0)
				(type default)
			)
			(fill no)
			(layer "F.CrtYd")
		)
		(fp_rect
			(start -0.508 0.9398)
			(end 0.508 -0.9398)
			(stroke
				(width 0)
				(type default)
			)
			(fill no)
			(layer "F.Fab")
		)
		(pad "1" smd custom
			(at 0 -0.4445 180)
			(size 0.1397 0.1397)
			(layers "F.Cu" "F.Mask" "F.Paste")
			(net "P3V3_STBY")
			(options
				(clearance outline)
				(anchor circle)
			)
			(primitives
				(gr_poly
					(pts
						(arc
							(start -0.1778 -0.2794)
							(mid -0.249642 -0.249642)
							(end -0.2794 -0.1778)
						)
						(arc
							(start -0.2794 0.1778)
							(mid -0.249642 0.249642)
							(end -0.1778 0.2794)
						)
						(arc
							(start 0.1778 0.2794)
							(mid 0.249642 0.249642)
							(end 0.2794 0.1778)
						)
						(arc
							(start 0.2794 -0.1778)
							(mid 0.249642 -0.249642)
							(end 0.1778 -0.2794)
						)
					)
					(width 0)
					(fill yes)
				)
			)
		)
		(pad "2" smd custom
			(at 0 0.4445 180)
			(size 0.1397 0.1397)
			(layers "F.Cu" "F.Mask" "F.Paste")
			(net "USB_EN_2")
			(options
				(clearance outline)
				(anchor circle)
			)
			(primitives
				(gr_poly
					(pts
						(arc
							(start -0.1778 -0.2794)
							(mid -0.249642 -0.249642)
							(end -0.2794 -0.1778)
						)
						(arc
							(start -0.2794 0.1778)
							(mid -0.249642 0.249642)
							(end -0.1778 0.2794)
						)
						(arc
							(start 0.1778 0.2794)
							(mid 0.249642 0.249642)
							(end 0.2794 0.1778)
						)
						(arc
							(start 0.2794 -0.1778)
							(mid 0.249642 -0.249642)
							(end 0.1778 -0.2794)
						)
					)
					(width 0)
					(fill yes)
				)
			)
		)
	)
	(footprint ""
		(layer "F.Cu")
		(at 87.884 -147.574 -90)
		(property "Reference" "R422"
			(at 0 0 270)
			(layer "F.SilkS")
			(hide yes)
			(effects
				(font
					(size 1.27 1.27)
				)
			)
		)
		(property "Value" "4K7R2F-GP"
			(at 0.064008 -3.993896 270)
			(unlocked yes)
			(layer "F.Fab")
			(hide yes)
			(effects
				(font
					(size 1.016 1.016)
					(thickness 0.1524)
				)
			)
		)
		(property "Device Type" "R402H16"
			(at 0.064008 -5.517896 270)
			(unlocked yes)
			(layer "F.Fab")
			(hide yes)
			(effects
				(font
					(size 1.016 1.016)
					(thickness 0.1524)
				)
			)
		)
		(duplicate_pad_numbers_are_jumpers no)
		(fp_line
			(start -0.508 -0.9398)
			(end -0.508 0.9398)
			(stroke
				(width 0.1524)
				(type default)
			)
			(layer "F.SilkS")
		)
		(fp_line
			(start 0.508 -0.9398)
			(end -0.508 -0.9398)
			(stroke
				(width 0.1524)
				(type default)
			)
			(layer "F.SilkS")
		)
		(fp_rect
			(start -0.508 0.9398)
			(end 0.508 -0.9398)
			(stroke
				(width 0)
				(type default)
			)
			(fill no)
			(layer "F.CrtYd")
		)
		(fp_rect
			(start -0.508 0.9398)
			(end 0.508 -0.9398)
			(stroke
				(width 0)
				(type default)
			)
			(fill no)
			(layer "F.Fab")
		)
		(pad "1" smd custom
			(at 0 -0.4445 270)
			(size 0.1397 0.1397)
			(layers "F.Cu" "F.Mask" "F.Paste")
			(net "P3V3_STBY")
			(options
				(clearance outline)
				(anchor circle)
			)
			(primitives
				(gr_poly
					(pts
						(arc
							(start -0.1778 -0.2794)
							(mid -0.249642 -0.249642)
							(end -0.2794 -0.1778)
						)
						(arc
							(start -0.2794 0.1778)
							(mid -0.249642 0.249642)
							(end -0.1778 0.2794)
						)
						(arc
							(start 0.1778 0.2794)
							(mid 0.249642 0.249642)
							(end 0.2794 0.1778)
						)
						(arc
							(start 0.2794 -0.1778)
							(mid 0.249642 -0.249642)
							(end 0.1778 -0.2794)
						)
					)
					(width 0)
					(fill yes)
				)
			)
		)
		(pad "2" smd custom
			(at 0 0.4445 270)
			(size 0.1397 0.1397)
			(layers "F.Cu" "F.Mask" "F.Paste")
			(net "IO_EXP0_RESET#_FLT")
			(options
				(clearance outline)
				(anchor circle)
			)
			(primitives
				(gr_poly
					(pts
						(arc
							(start -0.1778 -0.2794)
							(mid -0.249642 -0.249642)
							(end -0.2794 -0.1778)
						)
						(arc
							(start -0.2794 0.1778)
							(mid -0.249642 0.249642)
							(end -0.1778 0.2794)
						)
						(arc
							(start 0.1778 0.2794)
							(mid 0.249642 0.249642)
							(end 0.2794 0.1778)
						)
						(arc
							(start 0.2794 -0.1778)
							(mid 0.249642 -0.249642)
							(end 0.1778 -0.2794)
						)
					)
					(width 0)
					(fill yes)
				)
			)
		)
	)
	(footprint ""
		(layer "F.Cu")
		(at 94.488 -16.2306 180)
		(property "Reference" "D18"
			(at 0 0 180)
			(layer "F.SilkS")
			(hide yes)
			(effects
				(font
					(size 1.27 1.27)
				)
			)
		)
		(property "Value" "PESD5V0F1BL-GP"
			(at 1.8923 -1.5621 180)
			(unlocked yes)
			(layer "F.Fab")
			(hide yes)
			(effects
				(font
					(size 1.016 1.016)
					(thickness 0.1524)
				)
			)
		)
		(property "Device Type" "SOD882-10D6-1H20"
			(at 1.8923 -3.0861 180)
			(unlocked yes)
			(layer "F.Fab")
			(hide yes)
			(effects
				(font
					(size 1.016 1.016)
					(thickness 0.1524)
				)
			)
		)
		(duplicate_pad_numbers_are_jumpers no)
		(fp_line
			(start -0.3048 -0.9271)
			(end 0.3048 -0.9271)
			(stroke
				(width 0.254)
				(type default)
			)
			(layer "F.SilkS")
		)
		(fp_rect
			(start -0.2921 0.4953)
			(end 0.2921 -0.4953)
			(stroke
				(width 0)
				(type default)
			)
			(fill no)
			(layer "F.CrtYd")
		)
		(fp_poly
			(pts
				(xy -0.4318 0.8001) (xy -0.4318 -0.266192) (xy -0.2921 -0.266192) (xy -0.2921 0.4953) (xy 0.2921 0.4953)
				(xy 0.2921 -0.4953) (xy -0.2921 -0.4953) (xy -0.2921 -0.2667) (xy -0.4318 -0.2667) (xy -0.4318 -0.8001)
				(xy 0.4318 -0.8001) (xy 0.4318 0.8001)
			)
			(stroke
				(width 0)
				(type default)
			)
			(fill no)
			(layer "F.CrtYd")
		)
		(fp_rect
			(start -0.4318 0.8001)
			(end 0.4318 -0.8001)
			(stroke
				(width 0)
				(type default)
			)
			(fill no)
			(layer "F.Fab")
		)
		(pad "1" smd custom
			(at 0 -0.4445 180)
			(size 0.1143 0.1143)
			(layers "F.Cu" "F.Mask" "F.Paste")
			(net "GND")
			(options
				(clearance outline)
				(anchor circle)
			)
			(primitives
				(gr_poly
					(pts
						(arc
							(start -0.2032 0.2286)
							(mid -0.275042 0.198842)
							(end -0.3048 0.127)
						)
						(arc
							(start -0.3048 -0.127)
							(mid -0.275042 -0.198842)
							(end -0.2032 -0.2286)
						)
						(arc
							(start 0.2032 -0.2286)
							(mid 0.275042 -0.198842)
							(end 0.3048 -0.127)
						)
						(arc
							(start 0.3048 0.127)
							(mid 0.275042 0.198842)
							(end 0.2032 0.2286)
						)
					)
					(width 0)
					(fill yes)
				)
			)
		)
		(pad "2" smd custom
			(at 0 0.4445 180)
			(size 0.1143 0.1143)
			(layers "F.Cu" "F.Mask" "F.Paste")
			(net "USB_P1_F_DP1")
			(options
				(clearance outline)
				(anchor circle)
			)
			(primitives
				(gr_poly
					(pts
						(arc
							(start 0.2032 -0.2286)
							(mid 0.275042 -0.198842)
							(end 0.3048 -0.127)
						)
						(arc
							(start 0.3048 0.127)
							(mid 0.275042 0.198842)
							(end 0.2032 0.2286)
						)
						(arc
							(start -0.2032 0.2286)
							(mid -0.275042 0.198842)
							(end -0.3048 0.127)
						)
						(arc
							(start -0.3048 -0.127)
							(mid -0.275042 -0.198842)
							(end -0.2032 -0.2286)
						)
					)
					(width 0)
					(fill yes)
				)
			)
		)
	)
	(footprint ""
		(layer "F.Cu")
		(at 86.994238 -132.679694 180)
		(property "Reference" "R135"
			(at 0 0 180)
			(layer "F.SilkS")
			(hide yes)
			(effects
				(font
					(size 1.27 1.27)
				)
			)
		)
		(property "Value" "8K2R2J-3-GP"
			(at 0.064008 -3.993896 180)
			(unlocked yes)
			(layer "F.Fab")
			(hide yes)
			(effects
				(font
					(size 1.016 1.016)
					(thickness 0.1524)
				)
			)
		)
		(property "Device Type" "R402H16"
			(at 0.064008 -5.517896 180)
			(unlocked yes)
			(layer "F.Fab")
			(hide yes)
			(effects
				(font
					(size 1.016 1.016)
					(thickness 0.1524)
				)
			)
		)
		(duplicate_pad_numbers_are_jumpers no)
		(fp_line
			(start 0.508 -0.9398)
			(end -0.508 -0.9398)
			(stroke
				(width 0.1524)
				(type default)
			)
			(layer "F.SilkS")
		)
		(fp_line
			(start -0.508 -0.9398)
			(end -0.508 0.9398)
			(stroke
				(width 0.1524)
				(type default)
			)
			(layer "F.SilkS")
		)
		(fp_rect
			(start -0.508 0.9398)
			(end 0.508 -0.9398)
			(stroke
				(width 0)
				(type default)
			)
			(fill no)
			(layer "F.CrtYd")
		)
		(fp_rect
			(start -0.508 0.9398)
			(end 0.508 -0.9398)
			(stroke
				(width 0)
				(type default)
			)
			(fill no)
			(layer "F.Fab")
		)
		(pad "1" smd custom
			(at 0 -0.4445 180)
			(size 0.1397 0.1397)
			(layers "F.Cu" "F.Mask" "F.Paste")
			(net "P3V3_STBY")
			(options
				(clearance outline)
				(anchor circle)
			)
			(primitives
				(gr_poly
					(pts
						(arc
							(start -0.1778 -0.2794)
							(mid -0.249642 -0.249642)
							(end -0.2794 -0.1778)
						)
						(arc
							(start -0.2794 0.1778)
							(mid -0.249642 0.249642)
							(end -0.1778 0.2794)
						)
						(arc
							(start 0.1778 0.2794)
							(mid 0.249642 0.249642)
							(end 0.2794 0.1778)
						)
						(arc
							(start 0.2794 -0.1778)
							(mid 0.249642 -0.249642)
							(end 0.1778 -0.2794)
						)
					)
					(width 0)
					(fill yes)
				)
			)
		)
		(pad "2" smd custom
			(at 0 0.4445 180)
			(size 0.1397 0.1397)
			(layers "F.Cu" "F.Mask" "F.Paste")
			(net "EEPROM_A2")
			(options
				(clearance outline)
				(anchor circle)
			)
			(primitives
				(gr_poly
					(pts
						(arc
							(start -0.1778 -0.2794)
							(mid -0.249642 -0.249642)
							(end -0.2794 -0.1778)
						)
						(arc
							(start -0.2794 0.1778)
							(mid -0.249642 0.249642)
							(end -0.1778 0.2794)
						)
						(arc
							(start 0.1778 0.2794)
							(mid 0.249642 0.249642)
							(end 0.2794 0.1778)
						)
						(arc
							(start 0.2794 -0.1778)
							(mid 0.249642 -0.249642)
							(end 0.1778 -0.2794)
						)
					)
					(width 0)
					(fill yes)
				)
			)
		)
	)
	(footprint ""
		(layer "F.Cu")
		(at 148.235416 -10.532618 -90)
		(property "Reference" "R518"
			(at 0 0 270)
			(layer "F.SilkS")
			(hide yes)
			(effects
				(font
					(size 1.27 1.27)
				)
			)
		)
		(property "Value" "10KR2F-2-GP"
			(at 0.064008 -3.993896 270)
			(unlocked yes)
			(layer "F.Fab")
			(hide yes)
			(effects
				(font
					(size 1.016 1.016)
					(thickness 0.1524)
				)
			)
		)
		(property "Device Type" "R402H16"
			(at 0.064008 -5.517896 270)
			(unlocked yes)
			(layer "F.Fab")
			(hide yes)
			(effects
				(font
					(size 1.016 1.016)
					(thickness 0.1524)
				)
			)
		)
		(duplicate_pad_numbers_are_jumpers no)
		(fp_line
			(start -0.508 -0.9398)
			(end -0.508 0.9398)
			(stroke
				(width 0.1524)
				(type default)
			)
			(layer "F.SilkS")
		)
		(fp_line
			(start 0.508 -0.9398)
			(end -0.508 -0.9398)
			(stroke
				(width 0.1524)
				(type default)
			)
			(layer "F.SilkS")
		)
		(fp_rect
			(start -0.508 0.9398)
			(end 0.508 -0.9398)
			(stroke
				(width 0)
				(type default)
			)
			(fill no)
			(layer "F.CrtYd")
		)
		(fp_rect
			(start -0.508 0.9398)
			(end 0.508 -0.9398)
			(stroke
				(width 0)
				(type default)
			)
			(fill no)
			(layer "F.Fab")
		)
		(pad "1" smd custom
			(at 0 -0.4445 270)
			(size 0.1397 0.1397)
			(layers "F.Cu" "F.Mask" "F.Paste")
			(net "P1V8_STBY_VRG5")
			(options
				(clearance outline)
				(anchor circle)
			)
			(primitives
				(gr_poly
					(pts
						(arc
							(start -0.1778 -0.2794)
							(mid -0.249642 -0.249642)
							(end -0.2794 -0.1778)
						)
						(arc
							(start -0.2794 0.1778)
							(mid -0.249642 0.249642)
							(end -0.1778 0.2794)
						)
						(arc
							(start 0.1778 0.2794)
							(mid 0.249642 0.249642)
							(end 0.2794 0.1778)
						)
						(arc
							(start 0.2794 -0.1778)
							(mid 0.249642 -0.249642)
							(end 0.1778 -0.2794)
						)
					)
					(width 0)
					(fill yes)
				)
			)
		)
		(pad "2" smd custom
			(at 0 0.4445 270)
			(size 0.1397 0.1397)
			(layers "F.Cu" "F.Mask" "F.Paste")
			(net "PWRGD_P1V8_STBY")
			(options
				(clearance outline)
				(anchor circle)
			)
			(primitives
				(gr_poly
					(pts
						(arc
							(start -0.1778 -0.2794)
							(mid -0.249642 -0.249642)
							(end -0.2794 -0.1778)
						)
						(arc
							(start -0.2794 0.1778)
							(mid -0.249642 0.249642)
							(end -0.1778 0.2794)
						)
						(arc
							(start 0.1778 0.2794)
							(mid 0.249642 0.249642)
							(end 0.2794 0.1778)
						)
						(arc
							(start 0.2794 -0.1778)
							(mid 0.249642 -0.249642)
							(end 0.1778 -0.2794)
						)
					)
					(width 0)
					(fill yes)
				)
			)
		)
	)
	(footprint ""
		(layer "F.Cu")
		(at 43.675046 -175.72101 -90)
		(property "Reference" "R489"
			(at 0 0 270)
			(layer "F.SilkS")
			(hide yes)
			(effects
				(font
					(size 1.27 1.27)
				)
			)
		)
		(property "Value" "10R3F-GP"
			(at -0.0254 -2.5146 270)
			(unlocked yes)
			(layer "F.Fab")
			(hide yes)
			(effects
				(font
					(size 1.016 1.016)
					(thickness 0.1524)
				)
			)
		)
		(property "Device Type" "R603H22"
			(at -0.0254 -4.0386 270)
			(unlocked yes)
			(layer "F.Fab")
			(hide yes)
			(effects
				(font
					(size 1.016 1.016)
					(thickness 0.1524)
				)
			)
		)
		(duplicate_pad_numbers_are_jumpers no)
		(fp_line
			(start -0.4826 0)
			(end -0.2032 0)
			(stroke
				(width 0.2032)
				(type default)
			)
			(layer "F.SilkS")
		)
		(fp_line
			(start 0.2032 0)
			(end 0.4826 0)
			(stroke
				(width 0.2032)
				(type default)
			)
			(layer "F.SilkS")
		)
		(fp_rect
			(start -0.5842 1.3335)
			(end 0.5842 -1.3335)
			(stroke
				(width 0)
				(type default)
			)
			(fill no)
			(layer "F.CrtYd")
		)
		(fp_rect
			(start -0.5842 1.3335)
			(end 0.5842 -1.3335)
			(stroke
				(width 0)
				(type default)
			)
			(fill no)
			(layer "F.Fab")
		)
		(pad "1" smd custom
			(at 0 -0.762 270)
			(size 0.2159 0.2159)
			(layers "F.Cu" "F.Mask" "F.Paste")
			(net "P3V3_STBY_OUT")
			(options
				(clearance outline)
				(anchor circle)
			)
			(primitives
				(gr_poly
					(pts
						(arc
							(start -0.3302 -0.4318)
							(mid -0.402042 -0.402042)
							(end -0.4318 -0.3302)
						)
						(arc
							(start -0.4318 0.3302)
							(mid -0.402042 0.402042)
							(end -0.3302 0.4318)
						)
						(arc
							(start 0.3302 0.4318)
							(mid 0.402042 0.402042)
							(end 0.4318 0.3302)
						)
						(arc
							(start 0.4318 -0.3302)
							(mid 0.402042 -0.402042)
							(end 0.3302 -0.4318)
						)
					)
					(width 0)
					(fill yes)
				)
			)
		)
		(pad "2" smd custom
			(at 0 0.762 270)
			(size 0.2159 0.2159)
			(layers "F.Cu" "F.Mask" "F.Paste")
			(net "P3V3_STBY_VFB_R")
			(options
				(clearance outline)
				(anchor circle)
			)
			(primitives
				(gr_poly
					(pts
						(arc
							(start -0.3302 -0.4318)
							(mid -0.402042 -0.402042)
							(end -0.4318 -0.3302)
						)
						(arc
							(start -0.4318 0.3302)
							(mid -0.402042 0.402042)
							(end -0.3302 0.4318)
						)
						(arc
							(start 0.3302 0.4318)
							(mid 0.402042 0.402042)
							(end 0.4318 0.3302)
						)
						(arc
							(start 0.4318 -0.3302)
							(mid 0.402042 -0.402042)
							(end 0.3302 -0.4318)
						)
					)
					(width 0)
					(fill yes)
				)
			)
		)
	)
	(footprint ""
		(layer "F.Cu")
		(at 85.504274 -173.615604 180)
		(property "Reference" "C125"
			(at 0 0 180)
			(layer "F.SilkS")
			(hide yes)
			(effects
				(font
					(size 1.27 1.27)
				)
			)
		)
		(property "Value" "SCD1U25V2KX-2-GP"
			(at 1.1811 -2.7051 180)
			(unlocked yes)
			(layer "F.Fab")
			(hide yes)
			(effects
				(font
					(size 1.016 1.016)
					(thickness 0.1524)
				)
			)
		)
		(property "Device Type" "C402H22"
			(at 1.181354 -4.2291 180)
			(unlocked yes)
			(layer "F.Fab")
			(hide yes)
			(effects
				(font
					(size 1.016 1.016)
					(thickness 0.1524)
				)
			)
		)
		(duplicate_pad_numbers_are_jumpers no)
		(fp_rect
			(start -0.4318 0.9525)
			(end 0.4318 -0.9525)
			(stroke
				(width 0)
				(type default)
			)
			(fill no)
			(layer "F.CrtYd")
		)
		(fp_rect
			(start -0.4318 0.9525)
			(end 0.4318 -0.9525)
			(stroke
				(width 0)
				(type default)
			)
			(fill no)
			(layer "F.Fab")
		)
		(pad "1" smd custom
			(at 0 -0.4445 180)
			(size 0.1524 0.1524)
			(layers "F.Cu" "F.Mask" "F.Paste")
			(net "P3V3_STBY")
			(options
				(clearance outline)
				(anchor circle)
			)
			(primitives
				(gr_poly
					(pts
						(arc
							(start 0.3048 -0.2032)
							(mid 0.275042 -0.275042)
							(end 0.2032 -0.3048)
						)
						(arc
							(start -0.2032 -0.3048)
							(mid -0.275042 -0.275042)
							(end -0.3048 -0.2032)
						)
						(arc
							(start -0.3048 0.2032)
							(mid -0.275042 0.275042)
							(end -0.2032 0.3048)
						)
						(arc
							(start 0.2032 0.3048)
							(mid 0.275042 0.275042)
							(end 0.3048 0.2032)
						)
					)
					(width 0)
					(fill yes)
				)
			)
		)
		(pad "2" smd custom
			(at 0 0.4445 180)
			(size 0.1524 0.1524)
			(layers "F.Cu" "F.Mask" "F.Paste")
			(net "GND")
			(options
				(clearance outline)
				(anchor circle)
			)
			(primitives
				(gr_poly
					(pts
						(arc
							(start 0.3048 -0.2032)
							(mid 0.275042 -0.275042)
							(end 0.2032 -0.3048)
						)
						(arc
							(start -0.2032 -0.3048)
							(mid -0.275042 -0.275042)
							(end -0.3048 -0.2032)
						)
						(arc
							(start -0.3048 0.2032)
							(mid -0.275042 0.275042)
							(end -0.2032 0.3048)
						)
						(arc
							(start 0.2032 0.3048)
							(mid 0.275042 0.275042)
							(end 0.3048 0.2032)
						)
					)
					(width 0)
					(fill yes)
				)
			)
		)
	)
	(footprint ""
		(layer "F.Cu")
		(at 39.585646 -177.14341 180)
		(property "Reference" "R482"
			(at 0 0 180)
			(layer "F.SilkS")
			(hide yes)
			(effects
				(font
					(size 1.27 1.27)
				)
			)
		)
		(property "Value" "10KR2J-3-GP"
			(at 0.064008 -3.993896 180)
			(unlocked yes)
			(layer "F.Fab")
			(hide yes)
			(effects
				(font
					(size 1.016 1.016)
					(thickness 0.1524)
				)
			)
		)
		(property "Device Type" "R402H16"
			(at 0.064008 -5.517896 180)
			(unlocked yes)
			(layer "F.Fab")
			(hide yes)
			(effects
				(font
					(size 1.016 1.016)
					(thickness 0.1524)
				)
			)
		)
		(duplicate_pad_numbers_are_jumpers no)
		(fp_line
			(start 0.508 -0.9398)
			(end -0.508 -0.9398)
			(stroke
				(width 0.1524)
				(type default)
			)
			(layer "F.SilkS")
		)
		(fp_line
			(start -0.508 -0.9398)
			(end -0.508 0.9398)
			(stroke
				(width 0.1524)
				(type default)
			)
			(layer "F.SilkS")
		)
		(fp_rect
			(start -0.508 0.9398)
			(end 0.508 -0.9398)
			(stroke
				(width 0)
				(type default)
			)
			(fill no)
			(layer "F.CrtYd")
		)
		(fp_rect
			(start -0.508 0.9398)
			(end 0.508 -0.9398)
			(stroke
				(width 0)
				(type default)
			)
			(fill no)
			(layer "F.Fab")
		)
		(pad "1" smd custom
			(at 0 -0.4445 180)
			(size 0.1397 0.1397)
			(layers "F.Cu" "F.Mask" "F.Paste")
			(net "P12V_STBY")
			(options
				(clearance outline)
				(anchor circle)
			)
			(primitives
				(gr_poly
					(pts
						(arc
							(start -0.1778 -0.2794)
							(mid -0.249642 -0.249642)
							(end -0.2794 -0.1778)
						)
						(arc
							(start -0.2794 0.1778)
							(mid -0.249642 0.249642)
							(end -0.1778 0.2794)
						)
						(arc
							(start 0.1778 0.2794)
							(mid 0.249642 0.249642)
							(end 0.2794 0.1778)
						)
						(arc
							(start 0.2794 -0.1778)
							(mid 0.249642 -0.249642)
							(end 0.1778 -0.2794)
						)
					)
					(width 0)
					(fill yes)
				)
			)
		)
		(pad "2" smd custom
			(at 0 0.4445 180)
			(size 0.1397 0.1397)
			(layers "F.Cu" "F.Mask" "F.Paste")
			(net "P3V3_STBY_EN")
			(options
				(clearance outline)
				(anchor circle)
			)
			(primitives
				(gr_poly
					(pts
						(arc
							(start -0.1778 -0.2794)
							(mid -0.249642 -0.249642)
							(end -0.2794 -0.1778)
						)
						(arc
							(start -0.2794 0.1778)
							(mid -0.249642 0.249642)
							(end -0.1778 0.2794)
						)
						(arc
							(start 0.1778 0.2794)
							(mid 0.249642 0.249642)
							(end 0.2794 0.1778)
						)
						(arc
							(start 0.2794 -0.1778)
							(mid 0.249642 -0.249642)
							(end 0.1778 -0.2794)
						)
					)
					(width 0)
					(fill yes)
				)
			)
		)
	)
	(footprint ""
		(layer "F.Cu")
		(at 222.499936 -187.999878)
		(property "Reference" ""
			(at 0 0 0)
			(layer "F.SilkS")
			(hide yes)
			(effects
				(font
					(size 1.27 1.27)
				)
			)
		)
		(property "Value" "*"
			(at -6.38175 0.19685 0)
			(unlocked yes)
			(layer "F.Fab")
			(hide yes)
			(effects
				(font
					(size 1.016 1.016)
					(thickness 0.1524)
				)
			)
		)
		(duplicate_pad_numbers_are_jumpers no)
		(fp_poly
			(pts
				(arc
					(start 5.0673 0)
					(mid -5.0673 0)
					(end 5.0673 0)
				)
			)
			(stroke
				(width 0)
				(type default)
			)
			(fill no)
			(layer "B.CrtYd")
		)
		(fp_poly
			(pts
				(arc
					(start 5.0673 0)
					(mid -5.0673 0)
					(end 5.0673 0)
				)
			)
			(stroke
				(width 0)
				(type default)
			)
			(fill no)
			(layer "F.CrtYd")
		)
		(fp_poly
			(pts
				(arc
					(start 5.0673 0)
					(mid -5.0673 0)
					(end 5.0673 0)
				)
			)
			(stroke
				(width 0)
				(type default)
			)
			(fill no)
			(layer "B.Fab")
		)
		(fp_poly
			(pts
				(arc
					(start 5.0673 0)
					(mid -5.0673 0)
					(end 5.0673 0)
				)
			)
			(stroke
				(width 0)
				(type default)
			)
			(fill no)
			(layer "F.Fab")
		)
		(pad "1" thru_hole circle
			(at 0 0)
			(size 9.525 9.525)
			(drill 3.5052)
			(layers "*.Cu" "*.Mask")
			(remove_unused_layers no)
			(net "Net_34")
			(clearance -2.5019)
			(thermal_gap 0.3048)
			(padstack
				(mode front_inner_back)
				(layer "Inner"
					(shape circle)
					(size 3.9116 3.9116)
					(clearance 0.3048)
				)
				(layer "B.Cu"
					(shape circle)
					(size 9.525 9.525)
					(clearance -2.5019)
				)
			)
		)
	)
	(footprint ""
		(layer "F.Cu")
		(at 122.231404 -14.167612 90)
		(property "Reference" "C129"
			(at 0 0 90)
			(layer "F.SilkS")
			(hide yes)
			(effects
				(font
					(size 1.27 1.27)
				)
			)
		)
		(property "Value" "SC1KP50V2KX-1GP"
			(at 1.1811 -2.7051 90)
			(unlocked yes)
			(layer "F.Fab")
			(hide yes)
			(effects
				(font
					(size 1.016 1.016)
					(thickness 0.1524)
				)
			)
		)
		(property "Device Type" "C402H22"
			(at 1.1811 -4.2291 90)
			(unlocked yes)
			(layer "F.Fab")
			(hide yes)
			(effects
				(font
					(size 1.016 1.016)
					(thickness 0.1524)
				)
			)
		)
		(duplicate_pad_numbers_are_jumpers no)
		(fp_rect
			(start -0.4318 0.9525)
			(end 0.4318 -0.9525)
			(stroke
				(width 0)
				(type default)
			)
			(fill no)
			(layer "F.CrtYd")
		)
		(fp_rect
			(start -0.4318 0.9525)
			(end 0.4318 -0.9525)
			(stroke
				(width 0)
				(type default)
			)
			(fill no)
			(layer "F.Fab")
		)
		(pad "1" smd custom
			(at 0 -0.4445 90)
			(size 0.1524 0.1524)
			(layers "F.Cu" "F.Mask" "F.Paste")
			(net "MB0_TEMP")
			(options
				(clearance outline)
				(anchor circle)
			)
			(primitives
				(gr_poly
					(pts
						(arc
							(start 0.3048 -0.2032)
							(mid 0.275042 -0.275042)
							(end 0.2032 -0.3048)
						)
						(arc
							(start -0.2032 -0.3048)
							(mid -0.275042 -0.275042)
							(end -0.3048 -0.2032)
						)
						(arc
							(start -0.3048 0.2032)
							(mid -0.275042 0.275042)
							(end -0.2032 0.3048)
						)
						(arc
							(start 0.2032 0.3048)
							(mid 0.275042 0.275042)
							(end 0.3048 0.2032)
						)
					)
					(width 0)
					(fill yes)
				)
			)
		)
		(pad "2" smd custom
			(at 0 0.4445 90)
			(size 0.1524 0.1524)
			(layers "F.Cu" "F.Mask" "F.Paste")
			(net "GND")
			(options
				(clearance outline)
				(anchor circle)
			)
			(primitives
				(gr_poly
					(pts
						(arc
							(start 0.3048 -0.2032)
							(mid 0.275042 -0.275042)
							(end 0.2032 -0.3048)
						)
						(arc
							(start -0.2032 -0.3048)
							(mid -0.275042 -0.275042)
							(end -0.3048 -0.2032)
						)
						(arc
							(start -0.3048 0.2032)
							(mid -0.275042 0.275042)
							(end -0.2032 0.3048)
						)
						(arc
							(start 0.2032 0.3048)
							(mid 0.275042 0.275042)
							(end 0.3048 0.2032)
						)
					)
					(width 0)
					(fill yes)
				)
			)
		)
	)
	(footprint ""
		(layer "F.Cu")
		(at 68.5038 -116.3828 -90)
		(property "Reference" "R268"
			(at 0 0 270)
			(layer "F.SilkS")
			(hide yes)
			(effects
				(font
					(size 1.27 1.27)
				)
			)
		)
		(property "Value" "2K2R2J-2-GP"
			(at 0.064008 -3.993896 270)
			(unlocked yes)
			(layer "F.Fab")
			(hide yes)
			(effects
				(font
					(size 1.016 1.016)
					(thickness 0.1524)
				)
			)
		)
		(property "Device Type" "R402H16"
			(at 0.064008 -5.517896 270)
			(unlocked yes)
			(layer "F.Fab")
			(hide yes)
			(effects
				(font
					(size 1.016 1.016)
					(thickness 0.1524)
				)
			)
		)
		(duplicate_pad_numbers_are_jumpers no)
		(fp_line
			(start -0.508 -0.9398)
			(end -0.508 0.9398)
			(stroke
				(width 0.1524)
				(type default)
			)
			(layer "F.SilkS")
		)
		(fp_line
			(start 0.508 -0.9398)
			(end -0.508 -0.9398)
			(stroke
				(width 0.1524)
				(type default)
			)
			(layer "F.SilkS")
		)
		(fp_rect
			(start -0.508 0.9398)
			(end 0.508 -0.9398)
			(stroke
				(width 0)
				(type default)
			)
			(fill no)
			(layer "F.CrtYd")
		)
		(fp_rect
			(start -0.508 0.9398)
			(end 0.508 -0.9398)
			(stroke
				(width 0)
				(type default)
			)
			(fill no)
			(layer "F.Fab")
		)
		(pad "1" smd custom
			(at 0 -0.4445 270)
			(size 0.1397 0.1397)
			(layers "F.Cu" "F.Mask" "F.Paste")
			(net "P3V3_STBY")
			(options
				(clearance outline)
				(anchor circle)
			)
			(primitives
				(gr_poly
					(pts
						(arc
							(start -0.1778 -0.2794)
							(mid -0.249642 -0.249642)
							(end -0.2794 -0.1778)
						)
						(arc
							(start -0.2794 0.1778)
							(mid -0.249642 0.249642)
							(end -0.1778 0.2794)
						)
						(arc
							(start 0.1778 0.2794)
							(mid 0.249642 0.249642)
							(end 0.2794 0.1778)
						)
						(arc
							(start 0.2794 -0.1778)
							(mid 0.249642 -0.249642)
							(end 0.1778 -0.2794)
						)
					)
					(width 0)
					(fill yes)
				)
			)
		)
		(pad "2" smd custom
			(at 0 0.4445 270)
			(size 0.1397 0.1397)
			(layers "F.Cu" "F.Mask" "F.Paste")
			(net "PU_IBMC_BT_HOLD_N")
			(options
				(clearance outline)
				(anchor circle)
			)
			(primitives
				(gr_poly
					(pts
						(arc
							(start -0.1778 -0.2794)
							(mid -0.249642 -0.249642)
							(end -0.2794 -0.1778)
						)
						(arc
							(start -0.2794 0.1778)
							(mid -0.249642 0.249642)
							(end -0.1778 0.2794)
						)
						(arc
							(start 0.1778 0.2794)
							(mid 0.249642 0.249642)
							(end 0.2794 0.1778)
						)
						(arc
							(start 0.2794 -0.1778)
							(mid 0.249642 -0.249642)
							(end 0.1778 -0.2794)
						)
					)
					(width 0)
					(fill yes)
				)
			)
		)
	)
	(footprint ""
		(layer "F.Cu")
		(at 74.423016 -174.78248 -90)
		(property "Reference" "C190"
			(at 0 0 270)
			(layer "F.SilkS")
			(hide yes)
			(effects
				(font
					(size 1.27 1.27)
				)
			)
		)
		(property "Value" "SC1KP50V2KX-1GP"
			(at 1.1811 -2.7051 270)
			(unlocked yes)
			(layer "F.Fab")
			(hide yes)
			(effects
				(font
					(size 1.016 1.016)
					(thickness 0.1524)
				)
			)
		)
		(property "Device Type" "C402H22"
			(at 1.1811 -4.2291 270)
			(unlocked yes)
			(layer "F.Fab")
			(hide yes)
			(effects
				(font
					(size 1.016 1.016)
					(thickness 0.1524)
				)
			)
		)
		(duplicate_pad_numbers_are_jumpers no)
		(fp_rect
			(start -0.4318 0.9525)
			(end 0.4318 -0.9525)
			(stroke
				(width 0)
				(type default)
			)
			(fill no)
			(layer "F.CrtYd")
		)
		(fp_rect
			(start -0.4318 0.9525)
			(end 0.4318 -0.9525)
			(stroke
				(width 0)
				(type default)
			)
			(fill no)
			(layer "F.Fab")
		)
		(pad "1" smd custom
			(at 0 -0.4445 270)
			(size 0.1524 0.1524)
			(layers "F.Cu" "F.Mask" "F.Paste")
			(net "TPS74801_P2V5_STBY_OUT")
			(options
				(clearance outline)
				(anchor circle)
			)
			(primitives
				(gr_poly
					(pts
						(arc
							(start 0.3048 -0.2032)
							(mid 0.275042 -0.275042)
							(end 0.2032 -0.3048)
						)
						(arc
							(start -0.2032 -0.3048)
							(mid -0.275042 -0.275042)
							(end -0.3048 -0.2032)
						)
						(arc
							(start -0.3048 0.2032)
							(mid -0.275042 0.275042)
							(end -0.2032 0.3048)
						)
						(arc
							(start 0.2032 0.3048)
							(mid 0.275042 0.275042)
							(end 0.3048 0.2032)
						)
					)
					(width 0)
					(fill yes)
				)
			)
		)
		(pad "2" smd custom
			(at 0 0.4445 270)
			(size 0.1524 0.1524)
			(layers "F.Cu" "F.Mask" "F.Paste")
			(net "TPS74801_P2V5_STBY_FB")
			(options
				(clearance outline)
				(anchor circle)
			)
			(primitives
				(gr_poly
					(pts
						(arc
							(start 0.3048 -0.2032)
							(mid 0.275042 -0.275042)
							(end 0.2032 -0.3048)
						)
						(arc
							(start -0.2032 -0.3048)
							(mid -0.275042 -0.275042)
							(end -0.3048 -0.2032)
						)
						(arc
							(start -0.3048 0.2032)
							(mid -0.275042 0.275042)
							(end -0.2032 0.3048)
						)
						(arc
							(start 0.2032 0.3048)
							(mid 0.275042 0.275042)
							(end 0.3048 0.2032)
						)
					)
					(width 0)
					(fill yes)
				)
			)
		)
	)
	(footprint ""
		(layer "F.Cu")
		(at 11.806936 -170.6372 -90)
		(property "Reference" "C233"
			(at 0 0 270)
			(layer "F.SilkS")
			(hide yes)
			(effects
				(font
					(size 1.27 1.27)
				)
			)
		)
		(property "Value" "SCD1U16V2KX-3GP"
			(at 1.1811 -2.7051 270)
			(unlocked yes)
			(layer "F.Fab")
			(hide yes)
			(effects
				(font
					(size 1.016 1.016)
					(thickness 0.1524)
				)
			)
		)
		(property "Device Type" "C402H22"
			(at 1.1811 -4.2291 270)
			(unlocked yes)
			(layer "F.Fab")
			(hide yes)
			(effects
				(font
					(size 1.016 1.016)
					(thickness 0.1524)
				)
			)
		)
		(duplicate_pad_numbers_are_jumpers no)
		(fp_rect
			(start -0.4318 0.9525)
			(end 0.4318 -0.9525)
			(stroke
				(width 0)
				(type default)
			)
			(fill no)
			(layer "F.CrtYd")
		)
		(fp_rect
			(start -0.4318 0.9525)
			(end 0.4318 -0.9525)
			(stroke
				(width 0)
				(type default)
			)
			(fill no)
			(layer "F.Fab")
		)
		(pad "1" smd custom
			(at 0 -0.4445 270)
			(size 0.1524 0.1524)
			(layers "F.Cu" "F.Mask" "F.Paste")
			(net "TPS74801_P1V2_STBY_EN")
			(options
				(clearance outline)
				(anchor circle)
			)
			(primitives
				(gr_poly
					(pts
						(arc
							(start 0.3048 -0.2032)
							(mid 0.275042 -0.275042)
							(end 0.2032 -0.3048)
						)
						(arc
							(start -0.2032 -0.3048)
							(mid -0.275042 -0.275042)
							(end -0.3048 -0.2032)
						)
						(arc
							(start -0.3048 0.2032)
							(mid -0.275042 0.275042)
							(end -0.2032 0.3048)
						)
						(arc
							(start 0.2032 0.3048)
							(mid 0.275042 0.275042)
							(end 0.3048 0.2032)
						)
					)
					(width 0)
					(fill yes)
				)
			)
		)
		(pad "2" smd custom
			(at 0 0.4445 270)
			(size 0.1524 0.1524)
			(layers "F.Cu" "F.Mask" "F.Paste")
			(net "GND")
			(options
				(clearance outline)
				(anchor circle)
			)
			(primitives
				(gr_poly
					(pts
						(arc
							(start 0.3048 -0.2032)
							(mid 0.275042 -0.275042)
							(end 0.2032 -0.3048)
						)
						(arc
							(start -0.2032 -0.3048)
							(mid -0.275042 -0.275042)
							(end -0.3048 -0.2032)
						)
						(arc
							(start -0.3048 0.2032)
							(mid -0.275042 0.275042)
							(end -0.2032 0.3048)
						)
						(arc
							(start 0.2032 0.3048)
							(mid 0.275042 0.275042)
							(end 0.3048 0.2032)
						)
					)
					(width 0)
					(fill yes)
				)
			)
		)
	)
	(footprint ""
		(layer "F.Cu")
		(at 182.4482 -99.695)
		(property "Reference" "R557"
			(at 0 0 0)
			(layer "F.SilkS")
			(hide yes)
			(effects
				(font
					(size 1.27 1.27)
				)
			)
		)
		(property "Value" "0R2J-2-GP"
			(at 0.064008 -3.993896 0)
			(unlocked yes)
			(layer "F.Fab")
			(hide yes)
			(effects
				(font
					(size 1.016 1.016)
					(thickness 0.1524)
				)
			)
		)
		(property "Device Type" "R402H16"
			(at 0.064008 -5.517896 0)
			(unlocked yes)
			(layer "F.Fab")
			(hide yes)
			(effects
				(font
					(size 1.016 1.016)
					(thickness 0.1524)
				)
			)
		)
		(duplicate_pad_numbers_are_jumpers no)
		(fp_line
			(start -0.508 -0.9398)
			(end -0.508 0.9398)
			(stroke
				(width 0.1524)
				(type default)
			)
			(layer "F.SilkS")
		)
		(fp_line
			(start 0.508 -0.9398)
			(end -0.508 -0.9398)
			(stroke
				(width 0.1524)
				(type default)
			)
			(layer "F.SilkS")
		)
		(fp_rect
			(start -0.508 0.9398)
			(end 0.508 -0.9398)
			(stroke
				(width 0)
				(type default)
			)
			(fill no)
			(layer "F.CrtYd")
		)
		(fp_rect
			(start -0.508 0.9398)
			(end 0.508 -0.9398)
			(stroke
				(width 0)
				(type default)
			)
			(fill no)
			(layer "F.Fab")
		)
		(pad "1" smd custom
			(at 0 -0.4445)
			(size 0.1397 0.1397)
			(layers "F.Cu" "F.Mask" "F.Paste")
			(net "TEMP_1_SCL")
			(options
				(clearance outline)
				(anchor circle)
			)
			(primitives
				(gr_poly
					(pts
						(arc
							(start -0.1778 -0.2794)
							(mid -0.249642 -0.249642)
							(end -0.2794 -0.1778)
						)
						(arc
							(start -0.2794 0.1778)
							(mid -0.249642 0.249642)
							(end -0.1778 0.2794)
						)
						(arc
							(start 0.1778 0.2794)
							(mid 0.249642 0.249642)
							(end 0.2794 0.1778)
						)
						(arc
							(start 0.2794 -0.1778)
							(mid 0.249642 -0.249642)
							(end 0.1778 -0.2794)
						)
					)
					(width 0)
					(fill yes)
				)
			)
		)
		(pad "2" smd custom
			(at 0 0.4445)
			(size 0.1397 0.1397)
			(layers "F.Cu" "F.Mask" "F.Paste")
			(net "I2C_IOM_SCL")
			(options
				(clearance outline)
				(anchor circle)
			)
			(primitives
				(gr_poly
					(pts
						(arc
							(start -0.1778 -0.2794)
							(mid -0.249642 -0.249642)
							(end -0.2794 -0.1778)
						)
						(arc
							(start -0.2794 0.1778)
							(mid -0.249642 0.249642)
							(end -0.1778 0.2794)
						)
						(arc
							(start 0.1778 0.2794)
							(mid 0.249642 0.249642)
							(end 0.2794 0.1778)
						)
						(arc
							(start 0.2794 -0.1778)
							(mid 0.249642 -0.249642)
							(end 0.1778 -0.2794)
						)
					)
					(width 0)
					(fill yes)
				)
			)
		)
	)
	(footprint ""
		(layer "F.Cu")
		(at 184.2008 -111.0234)
		(property "Reference" "R546"
			(at 0 0 0)
			(layer "F.SilkS")
			(hide yes)
			(effects
				(font
					(size 1.27 1.27)
				)
			)
		)
		(property "Value" "4K7R2F-GP"
			(at 0.064008 -3.993896 0)
			(unlocked yes)
			(layer "F.Fab")
			(hide yes)
			(effects
				(font
					(size 1.016 1.016)
					(thickness 0.1524)
				)
			)
		)
		(property "Device Type" "R402H16"
			(at 0.064008 -5.517896 0)
			(unlocked yes)
			(layer "F.Fab")
			(hide yes)
			(effects
				(font
					(size 1.016 1.016)
					(thickness 0.1524)
				)
			)
		)
		(duplicate_pad_numbers_are_jumpers no)
		(fp_line
			(start -0.508 -0.9398)
			(end -0.508 0.9398)
			(stroke
				(width 0.1524)
				(type default)
			)
			(layer "F.SilkS")
		)
		(fp_line
			(start 0.508 -0.9398)
			(end -0.508 -0.9398)
			(stroke
				(width 0.1524)
				(type default)
			)
			(layer "F.SilkS")
		)
		(fp_rect
			(start -0.508 0.9398)
			(end 0.508 -0.9398)
			(stroke
				(width 0)
				(type default)
			)
			(fill no)
			(layer "F.CrtYd")
		)
		(fp_rect
			(start -0.508 0.9398)
			(end 0.508 -0.9398)
			(stroke
				(width 0)
				(type default)
			)
			(fill no)
			(layer "F.Fab")
		)
		(pad "1" smd custom
			(at 0 -0.4445)
			(size 0.1397 0.1397)
			(layers "F.Cu" "F.Mask" "F.Paste")
			(net "P3V3_STBY")
			(options
				(clearance outline)
				(anchor circle)
			)
			(primitives
				(gr_poly
					(pts
						(arc
							(start -0.1778 -0.2794)
							(mid -0.249642 -0.249642)
							(end -0.2794 -0.1778)
						)
						(arc
							(start -0.2794 0.1778)
							(mid -0.249642 0.249642)
							(end -0.1778 0.2794)
						)
						(arc
							(start 0.1778 0.2794)
							(mid 0.249642 0.249642)
							(end 0.2794 0.1778)
						)
						(arc
							(start 0.2794 -0.1778)
							(mid 0.249642 -0.249642)
							(end 0.1778 -0.2794)
						)
					)
					(width 0)
					(fill yes)
				)
			)
		)
		(pad "2" smd custom
			(at 0 0.4445)
			(size 0.1397 0.1397)
			(layers "F.Cu" "F.Mask" "F.Paste")
			(net "TEMP_1_A1")
			(options
				(clearance outline)
				(anchor circle)
			)
			(primitives
				(gr_poly
					(pts
						(arc
							(start -0.1778 -0.2794)
							(mid -0.249642 -0.249642)
							(end -0.2794 -0.1778)
						)
						(arc
							(start -0.2794 0.1778)
							(mid -0.249642 0.249642)
							(end -0.1778 0.2794)
						)
						(arc
							(start 0.1778 0.2794)
							(mid 0.249642 0.249642)
							(end 0.2794 0.1778)
						)
						(arc
							(start 0.2794 -0.1778)
							(mid 0.249642 -0.249642)
							(end 0.1778 -0.2794)
						)
					)
					(width 0)
					(fill yes)
				)
			)
		)
	)
	(footprint ""
		(layer "F.Cu")
		(at 82.457544 -160.376616 180)
		(property "Reference" "C235"
			(at 0 0 180)
			(layer "F.SilkS")
			(hide yes)
			(effects
				(font
					(size 1.27 1.27)
				)
			)
		)
		(property "Value" "SC10U6D3V5KX-4GP"
			(at -0.0762 -6.1214 180)
			(unlocked yes)
			(layer "F.Fab")
			(hide yes)
			(effects
				(font
					(size 1.016 1.016)
					(thickness 0.1524)
				)
			)
		)
		(property "Device Type" "C805H58"
			(at -0.0762 -8.1534 180)
			(unlocked yes)
			(layer "F.Fab")
			(hide yes)
			(effects
				(font
					(size 1.016 1.016)
					(thickness 0.1524)
				)
			)
		)
		(duplicate_pad_numbers_are_jumpers no)
		(fp_line
			(start 0.635 0)
			(end -0.635 0)
			(stroke
				(width 0.508)
				(type default)
			)
			(layer "F.SilkS")
		)
		(fp_rect
			(start -0.9652 1.778)
			(end 0.9652 -1.778)
			(stroke
				(width 0)
				(type default)
			)
			(fill no)
			(layer "F.CrtYd")
		)
		(fp_poly
			(pts
				(xy -0.9652 -1.778) (xy 0.9652 -1.778) (xy 0.9652 1.778) (xy -0.9652 1.778)
			)
			(stroke
				(width 0)
				(type default)
			)
			(fill no)
			(layer "F.Fab")
		)
		(pad "1" smd rect
			(at 0 -0.9652 180)
			(size 1.397 1.143)
			(layers "F.Cu" "F.Mask" "F.Paste")
			(net "TPS74801_P1V15_STBY_OUT")
		)
		(pad "2" smd rect
			(at 0 0.9652 180)
			(size 1.397 1.143)
			(layers "F.Cu" "F.Mask" "F.Paste")
			(net "GND")
		)
	)
	(footprint ""
		(layer "F.Cu")
		(at 171.106338 -9.120378 -90)
		(property "Reference" "G4"
			(at 0 0 270)
			(layer "F.SilkS")
			(hide yes)
			(effects
				(font
					(size 1.27 1.27)
				)
			)
		)
		(property "Value" "GAP-CLOSE-PWR-4-GP"
			(at -2.4638 -0.5461 270)
			(unlocked yes)
			(layer "F.Fab")
			(hide yes)
			(effects
				(font
					(size 1.016 1.016)
					(thickness 0.1524)
				)
			)
		)
		(property "Device Type" "GAP-CLOSE-PWR-4"
			(at -2.4638 -2.0701 270)
			(unlocked yes)
			(layer "F.Fab")
			(hide yes)
			(effects
				(font
					(size 1.016 1.016)
					(thickness 0.1524)
				)
			)
		)
		(duplicate_pad_numbers_are_jumpers no)
		(fp_rect
			(start -0.2794 0.254)
			(end 0.2794 -0.254)
			(stroke
				(width 0)
				(type default)
			)
			(fill no)
			(layer "F.CrtYd")
		)
		(fp_rect
			(start -0.2794 0.254)
			(end 0.2794 -0.254)
			(stroke
				(width 0)
				(type default)
			)
			(fill no)
			(layer "F.Fab")
		)
		(pad "1" smd rect
			(at -0.0635 0 270)
			(size 0.1778 0.254)
			(layers "F.Cu" "F.Mask" "F.Paste")
			(net "P1V8_STBY")
		)
		(pad "2" smd rect
			(at 0.0635 0 270)
			(size 0.1778 0.254)
			(layers "F.Cu" "F.Mask" "F.Paste")
			(net "P1V8_STBY_CC")
		)
	)
	(footprint ""
		(layer "F.Cu")
		(at 182.642764 -139.977622 -135)
		(property "Reference" "VIA59"
			(at 0 0 225)
			(layer "F.SilkS")
			(hide yes)
			(effects
				(font
					(size 1.27 1.27)
				)
			)
		)
		(property "Value" "85OHM-8L-1D6MM-L16L18-GP"
			(at 4.064105 0.609655 225)
			(unlocked yes)
			(layer "F.Fab")
			(hide yes)
			(effects
				(font
					(size 1.016 1.016)
					(thickness 0.1524)
				)
			)
		)
		(property "Device Type" "VIA-PCIE-4P-368076"
			(at 4.064105 -0.914474 225)
			(unlocked yes)
			(layer "F.Fab")
			(hide yes)
			(effects
				(font
					(size 1.016 1.016)
					(thickness 0.1524)
				)
			)
		)
		(duplicate_pad_numbers_are_jumpers no)
		(fp_poly
			(pts
				(xy -1.841491 -0.381057) (xy 1.841509 -0.381058) (xy 1.841508 0.380942) (xy -1.841491 0.380942)
			)
			(stroke
				(width 0)
				(type default)
			)
			(fill no)
			(layer "F.CrtYd")
		)
		(fp_poly
			(pts
				(xy -1.841491 -0.381057) (xy 1.841509 -0.381058) (xy 1.841508 0.380942) (xy -1.841491 0.380942)
			)
			(stroke
				(width 0)
				(type default)
			)
			(fill no)
			(layer "F.Fab")
		)
		(pad "1" thru_hole circle
			(at -1.460499 0 225)
			(size 0.508 0.508)
			(drill 0.254)
			(layers "*.Cu" "*.Mask")
			(remove_unused_layers no)
			(net "GND")
			(clearance 0.127)
			(thermal_gap 0.127)
		)
		(pad "2" thru_hole circle
			(at -0.4445 0 225)
			(size 0.508 0.508)
			(drill 0.254)
			(layers "*.Cu" "*.Mask")
			(remove_unused_layers no)
			(net "PCIE_IOM_TO_COMP_12_DP")
			(clearance 0.127)
			(thermal_gap 0.127)
		)
		(pad "3" thru_hole circle
			(at 0.4445 0 225)
			(size 0.508 0.508)
			(drill 0.254)
			(layers "*.Cu" "*.Mask")
			(remove_unused_layers no)
			(net "PCIE_IOM_TO_COMP_12_DN")
			(clearance 0.127)
			(thermal_gap 0.127)
		)
		(pad "4" thru_hole circle
			(at 1.460499 0 225)
			(size 0.508 0.508)
			(drill 0.254)
			(layers "*.Cu" "*.Mask")
			(remove_unused_layers no)
			(net "GND")
			(clearance 0.127)
			(thermal_gap 0.127)
		)
	)
	(footprint ""
		(layer "F.Cu")
		(at 27.419046 -152.340056 -90)
		(property "Reference" "R769"
			(at 0 0 270)
			(layer "F.SilkS")
			(hide yes)
			(effects
				(font
					(size 1.27 1.27)
				)
			)
		)
		(property "Value" "0R2J-2-GP"
			(at 0.064008 -3.993896 270)
			(unlocked yes)
			(layer "F.Fab")
			(hide yes)
			(effects
				(font
					(size 1.016 1.016)
					(thickness 0.1524)
				)
			)
		)
		(property "Device Type" "R402H16"
			(at 0.064008 -5.517896 270)
			(unlocked yes)
			(layer "F.Fab")
			(hide yes)
			(effects
				(font
					(size 1.016 1.016)
					(thickness 0.1524)
				)
			)
		)
		(duplicate_pad_numbers_are_jumpers no)
		(fp_line
			(start -0.508 -0.9398)
			(end -0.508 0.9398)
			(stroke
				(width 0.1524)
				(type default)
			)
			(layer "F.SilkS")
		)
		(fp_line
			(start 0.508 -0.9398)
			(end -0.508 -0.9398)
			(stroke
				(width 0.1524)
				(type default)
			)
			(layer "F.SilkS")
		)
		(fp_rect
			(start -0.508 0.9398)
			(end 0.508 -0.9398)
			(stroke
				(width 0)
				(type default)
			)
			(fill no)
			(layer "F.CrtYd")
		)
		(fp_rect
			(start -0.508 0.9398)
			(end 0.508 -0.9398)
			(stroke
				(width 0)
				(type default)
			)
			(fill no)
			(layer "F.Fab")
		)
		(pad "1" smd custom
			(at 0 -0.4445 270)
			(size 0.1397 0.1397)
			(layers "F.Cu" "F.Mask" "F.Paste")
			(net "DEBUG_GPIO_BMC_R_2")
			(options
				(clearance outline)
				(anchor circle)
			)
			(primitives
				(gr_poly
					(pts
						(arc
							(start -0.1778 -0.2794)
							(mid -0.249642 -0.249642)
							(end -0.2794 -0.1778)
						)
						(arc
							(start -0.2794 0.1778)
							(mid -0.249642 0.249642)
							(end -0.1778 0.2794)
						)
						(arc
							(start 0.1778 0.2794)
							(mid 0.249642 0.249642)
							(end 0.2794 0.1778)
						)
						(arc
							(start 0.2794 -0.1778)
							(mid 0.249642 -0.249642)
							(end 0.1778 -0.2794)
						)
					)
					(width 0)
					(fill yes)
				)
			)
		)
		(pad "2" smd custom
			(at 0 0.4445 270)
			(size 0.1397 0.1397)
			(layers "F.Cu" "F.Mask" "F.Paste")
			(net "DEBUG_GPIO_BMC_2")
			(options
				(clearance outline)
				(anchor circle)
			)
			(primitives
				(gr_poly
					(pts
						(arc
							(start -0.1778 -0.2794)
							(mid -0.249642 -0.249642)
							(end -0.2794 -0.1778)
						)
						(arc
							(start -0.2794 0.1778)
							(mid -0.249642 0.249642)
							(end -0.1778 0.2794)
						)
						(arc
							(start 0.1778 0.2794)
							(mid 0.249642 0.249642)
							(end 0.2794 0.1778)
						)
						(arc
							(start 0.2794 -0.1778)
							(mid 0.249642 -0.249642)
							(end 0.1778 -0.2794)
						)
					)
					(width 0)
					(fill yes)
				)
			)
		)
	)
	(footprint ""
		(layer "F.Cu")
		(at 122.231404 -15.128748 90)
		(property "Reference" "R432"
			(at 0 0 90)
			(layer "F.SilkS")
			(hide yes)
			(effects
				(font
					(size 1.27 1.27)
				)
			)
		)
		(property "Value" "100R2D-GP"
			(at 0.064008 -3.993896 90)
			(unlocked yes)
			(layer "F.Fab")
			(hide yes)
			(effects
				(font
					(size 1.016 1.016)
					(thickness 0.1524)
				)
			)
		)
		(property "Device Type" "R402H14"
			(at 0.064008 -5.517896 90)
			(unlocked yes)
			(layer "F.Fab")
			(hide yes)
			(effects
				(font
					(size 1.016 1.016)
					(thickness 0.1524)
				)
			)
		)
		(duplicate_pad_numbers_are_jumpers no)
		(fp_line
			(start 0.508 -0.9398)
			(end -0.508 -0.9398)
			(stroke
				(width 0.1524)
				(type default)
			)
			(layer "F.SilkS")
		)
		(fp_line
			(start -0.508 -0.9398)
			(end -0.508 0.9398)
			(stroke
				(width 0.1524)
				(type default)
			)
			(layer "F.SilkS")
		)
		(fp_rect
			(start -0.508 0.9398)
			(end 0.508 -0.9398)
			(stroke
				(width 0)
				(type default)
			)
			(fill no)
			(layer "F.CrtYd")
		)
		(fp_rect
			(start -0.508 0.9398)
			(end 0.508 -0.9398)
			(stroke
				(width 0)
				(type default)
			)
			(fill no)
			(layer "F.Fab")
		)
		(pad "1" smd custom
			(at 0 -0.4445 90)
			(size 0.1397 0.1397)
			(layers "F.Cu" "F.Mask" "F.Paste")
			(net "MB0_TEMP")
			(options
				(clearance outline)
				(anchor circle)
			)
			(primitives
				(gr_poly
					(pts
						(arc
							(start -0.1778 -0.2794)
							(mid -0.249642 -0.249642)
							(end -0.2794 -0.1778)
						)
						(arc
							(start -0.2794 0.1778)
							(mid -0.249642 0.249642)
							(end -0.1778 0.2794)
						)
						(arc
							(start 0.1778 0.2794)
							(mid 0.249642 0.249642)
							(end 0.2794 0.1778)
						)
						(arc
							(start 0.2794 -0.1778)
							(mid 0.249642 -0.249642)
							(end 0.1778 -0.2794)
						)
					)
					(width 0)
					(fill yes)
				)
			)
		)
		(pad "2" smd custom
			(at 0 0.4445 90)
			(size 0.1397 0.1397)
			(layers "F.Cu" "F.Mask" "F.Paste")
			(net "MB0_TEMP_C")
			(options
				(clearance outline)
				(anchor circle)
			)
			(primitives
				(gr_poly
					(pts
						(arc
							(start -0.1778 -0.2794)
							(mid -0.249642 -0.249642)
							(end -0.2794 -0.1778)
						)
						(arc
							(start -0.2794 0.1778)
							(mid -0.249642 0.249642)
							(end -0.1778 0.2794)
						)
						(arc
							(start 0.1778 0.2794)
							(mid 0.249642 0.249642)
							(end 0.2794 0.1778)
						)
						(arc
							(start 0.2794 -0.1778)
							(mid 0.249642 -0.249642)
							(end 0.1778 -0.2794)
						)
					)
					(width 0)
					(fill yes)
				)
			)
		)
	)
	(footprint ""
		(layer "F.Cu")
		(at 93.577156 -162.51428 90)
		(property "Reference" "C20"
			(at 0 0 90)
			(layer "F.SilkS")
			(hide yes)
			(effects
				(font
					(size 1.27 1.27)
				)
			)
		)
		(property "Value" "SC18P50V2JN-1-GP"
			(at 1.1811 -2.7051 90)
			(unlocked yes)
			(layer "F.Fab")
			(hide yes)
			(effects
				(font
					(size 1.016 1.016)
					(thickness 0.1524)
				)
			)
		)
		(property "Device Type" "C402H22"
			(at 1.1811 -4.2291 90)
			(unlocked yes)
			(layer "F.Fab")
			(hide yes)
			(effects
				(font
					(size 1.016 1.016)
					(thickness 0.1524)
				)
			)
		)
		(duplicate_pad_numbers_are_jumpers no)
		(fp_rect
			(start -0.4318 0.9525)
			(end 0.4318 -0.9525)
			(stroke
				(width 0)
				(type default)
			)
			(fill no)
			(layer "F.CrtYd")
		)
		(fp_rect
			(start -0.4318 0.9525)
			(end 0.4318 -0.9525)
			(stroke
				(width 0)
				(type default)
			)
			(fill no)
			(layer "F.Fab")
		)
		(pad "1" smd custom
			(at 0 -0.4445 90)
			(size 0.1524 0.1524)
			(layers "F.Cu" "F.Mask" "F.Paste")
			(net "USB_HUB_XTAL_OUT")
			(options
				(clearance outline)
				(anchor circle)
			)
			(primitives
				(gr_poly
					(pts
						(arc
							(start 0.3048 -0.2032)
							(mid 0.275042 -0.275042)
							(end 0.2032 -0.3048)
						)
						(arc
							(start -0.2032 -0.3048)
							(mid -0.275042 -0.275042)
							(end -0.3048 -0.2032)
						)
						(arc
							(start -0.3048 0.2032)
							(mid -0.275042 0.275042)
							(end -0.2032 0.3048)
						)
						(arc
							(start 0.2032 0.3048)
							(mid 0.275042 0.275042)
							(end 0.3048 0.2032)
						)
					)
					(width 0)
					(fill yes)
				)
			)
		)
		(pad "2" smd custom
			(at 0 0.4445 90)
			(size 0.1524 0.1524)
			(layers "F.Cu" "F.Mask" "F.Paste")
			(net "GND")
			(options
				(clearance outline)
				(anchor circle)
			)
			(primitives
				(gr_poly
					(pts
						(arc
							(start 0.3048 -0.2032)
							(mid 0.275042 -0.275042)
							(end 0.2032 -0.3048)
						)
						(arc
							(start -0.2032 -0.3048)
							(mid -0.275042 -0.275042)
							(end -0.3048 -0.2032)
						)
						(arc
							(start -0.3048 0.2032)
							(mid -0.275042 0.275042)
							(end -0.2032 0.3048)
						)
						(arc
							(start 0.2032 0.3048)
							(mid 0.275042 0.275042)
							(end 0.3048 0.2032)
						)
					)
					(width 0)
					(fill yes)
				)
			)
		)
	)
	(footprint ""
		(layer "F.Cu")
		(at 215.60028 -93.109288 90)
		(property "Reference" "C670"
			(at 0 0 90)
			(layer "F.SilkS")
			(hide yes)
			(effects
				(font
					(size 1.27 1.27)
				)
			)
		)
		(property "Value" "SC1U16V3KX-5GP"
			(at 0 -2.8194 90)
			(unlocked yes)
			(layer "F.Fab")
			(hide yes)
			(effects
				(font
					(size 1.016 1.016)
					(thickness 0.1524)
				)
			)
		)
		(property "Device Type" "C603H36"
			(at 0 -4.3434 90)
			(unlocked yes)
			(layer "F.Fab")
			(hide yes)
			(effects
				(font
					(size 1.016 1.016)
					(thickness 0.1524)
				)
			)
		)
		(duplicate_pad_numbers_are_jumpers no)
		(fp_line
			(start 0.508 0)
			(end -0.508 0)
			(stroke
				(width 0.2032)
				(type default)
			)
			(layer "F.SilkS")
		)
		(fp_rect
			(start -0.5842 1.3335)
			(end 0.5842 -1.3335)
			(stroke
				(width 0)
				(type default)
			)
			(fill no)
			(layer "F.CrtYd")
		)
		(fp_rect
			(start -0.5842 1.3335)
			(end 0.5842 -1.3335)
			(stroke
				(width 0)
				(type default)
			)
			(fill no)
			(layer "F.Fab")
		)
		(pad "1" smd custom
			(at 0 -0.762 90)
			(size 0.2159 0.2159)
			(layers "F.Cu" "F.Mask" "F.Paste")
			(net "GND")
			(options
				(clearance outline)
				(anchor circle)
			)
			(primitives
				(gr_poly
					(pts
						(arc
							(start -0.3302 -0.4318)
							(mid -0.402042 -0.402042)
							(end -0.4318 -0.3302)
						)
						(arc
							(start -0.4318 0.3302)
							(mid -0.402042 0.402042)
							(end -0.3302 0.4318)
						)
						(arc
							(start 0.3302 0.4318)
							(mid 0.402042 0.402042)
							(end 0.4318 0.3302)
						)
						(arc
							(start 0.4318 -0.3302)
							(mid 0.402042 -0.402042)
							(end 0.3302 -0.4318)
						)
					)
					(width 0)
					(fill yes)
				)
			)
		)
		(pad "2" smd custom
			(at 0 0.762 90)
			(size 0.2159 0.2159)
			(layers "F.Cu" "F.Mask" "F.Paste")
			(net "P3V3_M2_EN")
			(options
				(clearance outline)
				(anchor circle)
			)
			(primitives
				(gr_poly
					(pts
						(arc
							(start -0.3302 -0.4318)
							(mid -0.402042 -0.402042)
							(end -0.4318 -0.3302)
						)
						(arc
							(start -0.4318 0.3302)
							(mid -0.402042 0.402042)
							(end -0.3302 0.4318)
						)
						(arc
							(start 0.3302 0.4318)
							(mid 0.402042 0.402042)
							(end 0.4318 0.3302)
						)
						(arc
							(start 0.4318 -0.3302)
							(mid 0.402042 -0.402042)
							(end 0.3302 -0.4318)
						)
					)
					(width 0)
					(fill yes)
				)
			)
		)
	)
	(footprint ""
		(layer "F.Cu")
		(at 86.995 -148.717 90)
		(property "Reference" "R93"
			(at 0 0 90)
			(layer "F.SilkS")
			(hide yes)
			(effects
				(font
					(size 1.27 1.27)
				)
			)
		)
		(property "Value" "0R2J-2-GP"
			(at 0.064008 -3.993896 90)
			(unlocked yes)
			(layer "F.Fab")
			(hide yes)
			(effects
				(font
					(size 1.016 1.016)
					(thickness 0.1524)
				)
			)
		)
		(property "Device Type" "R402H16"
			(at 0.064008 -5.517896 90)
			(unlocked yes)
			(layer "F.Fab")
			(hide yes)
			(effects
				(font
					(size 1.016 1.016)
					(thickness 0.1524)
				)
			)
		)
		(duplicate_pad_numbers_are_jumpers no)
		(fp_line
			(start 0.508 -0.9398)
			(end -0.508 -0.9398)
			(stroke
				(width 0.1524)
				(type default)
			)
			(layer "F.SilkS")
		)
		(fp_line
			(start -0.508 -0.9398)
			(end -0.508 0.9398)
			(stroke
				(width 0.1524)
				(type default)
			)
			(layer "F.SilkS")
		)
		(fp_rect
			(start -0.508 0.9398)
			(end 0.508 -0.9398)
			(stroke
				(width 0)
				(type default)
			)
			(fill no)
			(layer "F.CrtYd")
		)
		(fp_rect
			(start -0.508 0.9398)
			(end 0.508 -0.9398)
			(stroke
				(width 0)
				(type default)
			)
			(fill no)
			(layer "F.Fab")
		)
		(pad "1" smd custom
			(at 0 -0.4445 90)
			(size 0.1397 0.1397)
			(layers "F.Cu" "F.Mask" "F.Paste")
			(net "I2C_BMC_COMP_SCL_OUT")
			(options
				(clearance outline)
				(anchor circle)
			)
			(primitives
				(gr_poly
					(pts
						(arc
							(start -0.1778 -0.2794)
							(mid -0.249642 -0.249642)
							(end -0.2794 -0.1778)
						)
						(arc
							(start -0.2794 0.1778)
							(mid -0.249642 0.249642)
							(end -0.1778 0.2794)
						)
						(arc
							(start 0.1778 0.2794)
							(mid 0.249642 0.249642)
							(end 0.2794 0.1778)
						)
						(arc
							(start 0.2794 -0.1778)
							(mid 0.249642 -0.249642)
							(end 0.1778 -0.2794)
						)
					)
					(width 0)
					(fill yes)
				)
			)
		)
		(pad "2" smd custom
			(at 0 0.4445 90)
			(size 0.1397 0.1397)
			(layers "F.Cu" "F.Mask" "F.Paste")
			(net "I2C_BMC_COMP_SCL_R")
			(options
				(clearance outline)
				(anchor circle)
			)
			(primitives
				(gr_poly
					(pts
						(arc
							(start -0.1778 -0.2794)
							(mid -0.249642 -0.249642)
							(end -0.2794 -0.1778)
						)
						(arc
							(start -0.2794 0.1778)
							(mid -0.249642 0.249642)
							(end -0.1778 0.2794)
						)
						(arc
							(start 0.1778 0.2794)
							(mid 0.249642 0.249642)
							(end 0.2794 0.1778)
						)
						(arc
							(start 0.2794 -0.1778)
							(mid 0.249642 -0.249642)
							(end 0.1778 -0.2794)
						)
					)
					(width 0)
					(fill yes)
				)
			)
		)
	)
	(footprint ""
		(layer "F.Cu")
		(at 204.399896 -129.599944)
		(property "Reference" "M1"
			(at 0 0 0)
			(layer "F.SilkS")
			(hide yes)
			(effects
				(font
					(size 1.27 1.27)
				)
			)
		)
		(property "Value" "SKT-MINI75P-11-GP"
			(at 12.6619 2.2733 0)
			(unlocked yes)
			(layer "F.Fab")
			(hide yes)
			(effects
				(font
					(size 1.016 1.016)
					(thickness 0.1524)
				)
			)
		)
		(property "Device Type" "MDT580M01001"
			(at 12.6619 0.7493 0)
			(unlocked yes)
			(layer "F.Fab")
			(hide yes)
			(effects
				(font
					(size 1.016 1.016)
					(thickness 0.1524)
				)
			)
		)
		(duplicate_pad_numbers_are_jumpers no)
		(fp_line
			(start -11.2522 -6.2992)
			(end 11.2522 -6.2992)
			(stroke
				(width 0.1524)
				(type default)
			)
			(layer "F.SilkS")
		)
		(fp_line
			(start -11.2522 3.302)
			(end -11.2522 -6.2992)
			(stroke
				(width 0.1524)
				(type default)
			)
			(layer "F.SilkS")
		)
		(fp_line
			(start -9.525 -6.3881)
			(end -9.017 -6.3881)
			(stroke
				(width 0.3302)
				(type default)
			)
			(layer "F.SilkS")
		)
		(fp_line
			(start 11.2522 -6.2992)
			(end 11.2522 3.302)
			(stroke
				(width 0.1524)
				(type default)
			)
			(layer "F.SilkS")
		)
		(fp_line
			(start 11.2522 3.302)
			(end -11.2522 3.302)
			(stroke
				(width 0.1524)
				(type default)
			)
			(layer "F.SilkS")
		)
		(fp_poly
			(pts
				(xy -9.273794 -6.315202) (xy -8.841994 -6.747002) (xy -9.705594 -6.747002)
			)
			(stroke
				(width 0)
				(type default)
			)
			(fill yes)
			(layer "F.SilkS")
		)
		(fp_rect
			(start -10.9982 2.8448)
			(end 10.9982 -5.6896)
			(stroke
				(width 0)
				(type default)
			)
			(fill no)
			(layer "F.CrtYd")
		)
		(fp_poly
			(pts
				(xy -11.5062 3.556) (xy -11.5062 -6.5532) (xy 11.5062 -6.5532) (xy 11.5062 -0.00635) (xy 10.9982 -0.00635)
				(xy 10.9982 -5.6896) (xy -10.9982 -5.6896) (xy -10.9982 2.8448) (xy 10.9982 2.8448) (xy 10.9982 0.00635)
				(xy 11.5062 0.00635) (xy 11.5062 3.556)
			)
			(stroke
				(width 0)
				(type default)
			)
			(fill no)
			(layer "F.CrtYd")
		)
		(fp_rect
			(start -11.5062 3.556)
			(end 11.5062 -6.5532)
			(stroke
				(width 0)
				(type default)
			)
			(fill no)
			(layer "F.Fab")
		)
		(pad "" np_thru_hole circle
			(at -9.99998 0)
			(size 0.254 0.254)
			(drill 1.1176)
			(layers "*.Cu" "*.Mask")
			(clearance 0.7874)
			(thermal_gap 0.7874)
		)
		(pad "" np_thru_hole circle
			(at 9.99998 0)
			(size 0.254 0.254)
			(drill 1.6002)
			(layers "*.Cu" "*.Mask")
			(clearance 1.0287)
			(thermal_gap 1.0287)
		)
		(pad "1" smd rect
			(at -9.249918 -5.275072)
			(size 0.3048 1.5494)
			(layers "F.Cu" "F.Mask" "F.Paste")
			(net "M2_1_PRESENT_N_R")
		)
		(pad "2" smd rect
			(at -8.999982 2.275078)
			(size 0.3048 1.5494)
			(layers "F.Cu" "F.Mask" "F.Paste")
			(net "P3V3_M2")
		)
		(pad "3" smd rect
			(at -8.750046 -5.275072)
			(size 0.3048 1.5494)
			(layers "F.Cu" "F.Mask" "F.Paste")
			(net "GND")
		)
		(pad "4" smd rect
			(at -8.50011 2.275078)
			(size 0.3048 1.5494)
			(layers "F.Cu" "F.Mask" "F.Paste")
			(net "P3V3_M2")
		)
		(pad "5" smd rect
			(at -8.24992 -5.275072)
			(size 0.3048 1.5494)
			(layers "F.Cu" "F.Mask" "F.Paste")
			(net "PCIE_IOM_TO_COMP_11_DN")
		)
		(pad "6" smd rect
			(at -7.999984 2.275078)
			(size 0.3048 1.5494)
			(layers "F.Cu" "F.Mask" "F.Paste")
			(net "Net_623")
		)
		(pad "7" smd rect
			(at -7.750048 -5.275072)
			(size 0.3048 1.5494)
			(layers "F.Cu" "F.Mask" "F.Paste")
			(net "PCIE_IOM_TO_COMP_11_DP")
		)
		(pad "8" smd rect
			(at -7.500112 2.275078)
			(size 0.3048 1.5494)
			(layers "F.Cu" "F.Mask" "F.Paste")
			(net "Net_624")
		)
		(pad "9" smd rect
			(at -7.249922 -5.275072)
			(size 0.3048 1.5494)
			(layers "F.Cu" "F.Mask" "F.Paste")
			(net "GND")
		)
		(pad "10" smd rect
			(at -6.999986 2.275078)
			(size 0.3048 1.5494)
			(layers "F.Cu" "F.Mask" "F.Paste")
			(net "M2_1_ACTIVE_N")
		)
		(pad "11" smd rect
			(at -6.75005 -5.275072)
			(size 0.3048 1.5494)
			(layers "F.Cu" "F.Mask" "F.Paste")
			(net "PCIE_COMP_TO_IOM_11_DN")
		)
		(pad "12" smd rect
			(at -6.500114 2.275078)
			(size 0.3048 1.5494)
			(layers "F.Cu" "F.Mask" "F.Paste")
			(net "P3V3_M2")
		)
		(pad "13" smd rect
			(at -6.249924 -5.275072)
			(size 0.3048 1.5494)
			(layers "F.Cu" "F.Mask" "F.Paste")
			(net "PCIE_COMP_TO_IOM_11_DP")
		)
		(pad "14" smd rect
			(at -5.999988 2.275078)
			(size 0.3048 1.5494)
			(layers "F.Cu" "F.Mask" "F.Paste")
			(net "P3V3_M2")
		)
		(pad "15" smd rect
			(at -5.750052 -5.275072)
			(size 0.3048 1.5494)
			(layers "F.Cu" "F.Mask" "F.Paste")
			(net "GND")
		)
		(pad "16" smd rect
			(at -5.500116 2.275078)
			(size 0.3048 1.5494)
			(layers "F.Cu" "F.Mask" "F.Paste")
			(net "P3V3_M2")
		)
		(pad "17" smd rect
			(at -5.249926 -5.275072)
			(size 0.3048 1.5494)
			(layers "F.Cu" "F.Mask" "F.Paste")
			(net "PCIE_IOM_TO_COMP_10_DN")
		)
		(pad "18" smd rect
			(at -4.99999 2.275078)
			(size 0.3048 1.5494)
			(layers "F.Cu" "F.Mask" "F.Paste")
			(net "P3V3_M2")
		)
		(pad "19" smd rect
			(at -4.750054 -5.275072)
			(size 0.3048 1.5494)
			(layers "F.Cu" "F.Mask" "F.Paste")
			(net "PCIE_IOM_TO_COMP_10_DP")
		)
		(pad "20" smd rect
			(at -4.500118 2.275078)
			(size 0.3048 1.5494)
			(layers "F.Cu" "F.Mask" "F.Paste")
			(net "Net_625")
		)
		(pad "21" smd rect
			(at -4.249928 -5.275072)
			(size 0.3048 1.5494)
			(layers "F.Cu" "F.Mask" "F.Paste")
			(net "GND")
		)
		(pad "22" smd rect
			(at -3.999992 2.275078)
			(size 0.3048 1.5494)
			(layers "F.Cu" "F.Mask" "F.Paste")
			(net "Net_626")
		)
		(pad "23" smd rect
			(at -3.750056 -5.275072)
			(size 0.3048 1.5494)
			(layers "F.Cu" "F.Mask" "F.Paste")
			(net "PCIE_COMP_TO_IOM_10_DN")
		)
		(pad "24" smd rect
			(at -3.50012 2.275078)
			(size 0.3048 1.5494)
			(layers "F.Cu" "F.Mask" "F.Paste")
			(net "Net_613")
		)
		(pad "25" smd rect
			(at -3.24993 -5.275072)
			(size 0.3048 1.5494)
			(layers "F.Cu" "F.Mask" "F.Paste")
			(net "PCIE_COMP_TO_IOM_10_DP")
		)
		(pad "26" smd rect
			(at -2.999994 2.275078)
			(size 0.3048 1.5494)
			(layers "F.Cu" "F.Mask" "F.Paste")
			(net "Net_614")
		)
		(pad "27" smd rect
			(at -2.750058 -5.275072)
			(size 0.3048 1.5494)
			(layers "F.Cu" "F.Mask" "F.Paste")
			(net "GND")
		)
		(pad "28" smd rect
			(at -2.500122 2.275078)
			(size 0.3048 1.5494)
			(layers "F.Cu" "F.Mask" "F.Paste")
			(net "Net_615")
		)
		(pad "29" smd rect
			(at -2.249932 -5.275072)
			(size 0.3048 1.5494)
			(layers "F.Cu" "F.Mask" "F.Paste")
			(net "PCIE_IOM_TO_COMP_9_DN")
		)
		(pad "30" smd rect
			(at -1.999996 2.275078)
			(size 0.3048 1.5494)
			(layers "F.Cu" "F.Mask" "F.Paste")
			(net "Net_616")
		)
		(pad "31" smd rect
			(at -1.75006 -5.275072)
			(size 0.3048 1.5494)
			(layers "F.Cu" "F.Mask" "F.Paste")
			(net "PCIE_IOM_TO_COMP_9_DP")
		)
		(pad "32" smd rect
			(at -1.500124 2.275078)
			(size 0.3048 1.5494)
			(layers "F.Cu" "F.Mask" "F.Paste")
			(net "Net_617")
		)
		(pad "33" smd rect
			(at -1.249934 -5.275072)
			(size 0.3048 1.5494)
			(layers "F.Cu" "F.Mask" "F.Paste")
			(net "GND")
		)
		(pad "34" smd rect
			(at -0.999998 2.275078)
			(size 0.3048 1.5494)
			(layers "F.Cu" "F.Mask" "F.Paste")
			(net "Net_618")
		)
		(pad "35" smd rect
			(at -0.750062 -5.275072)
			(size 0.3048 1.5494)
			(layers "F.Cu" "F.Mask" "F.Paste")
			(net "PCIE_COMP_TO_IOM_9_DN")
		)
		(pad "36" smd rect
			(at -0.500126 2.275078)
			(size 0.3048 1.5494)
			(layers "F.Cu" "F.Mask" "F.Paste")
			(net "Net_619")
		)
		(pad "37" smd rect
			(at -0.249936 -5.275072)
			(size 0.3048 1.5494)
			(layers "F.Cu" "F.Mask" "F.Paste")
			(net "PCIE_COMP_TO_IOM_9_DP")
		)
		(pad "38" smd rect
			(at 0 2.275078)
			(size 0.3048 1.5494)
			(layers "F.Cu" "F.Mask" "F.Paste")
			(net "Net_620")
		)
		(pad "39" smd rect
			(at 0.249936 -5.275072)
			(size 0.3048 1.5494)
			(layers "F.Cu" "F.Mask" "F.Paste")
			(net "GND")
		)
		(pad "40" smd rect
			(at 0.500126 2.275078)
			(size 0.3048 1.5494)
			(layers "F.Cu" "F.Mask" "F.Paste")
			(net "I2C_M2_1_1V8_SCL")
		)
		(pad "41" smd rect
			(at 0.750062 -5.275072)
			(size 0.3048 1.5494)
			(layers "F.Cu" "F.Mask" "F.Paste")
			(net "PCIE_IOM_TO_COMP_8_DN")
		)
		(pad "42" smd rect
			(at 0.999998 2.275078)
			(size 0.3048 1.5494)
			(layers "F.Cu" "F.Mask" "F.Paste")
			(net "I2C_M2_1_1V8_SDA")
		)
		(pad "43" smd rect
			(at 1.249934 -5.275072)
			(size 0.3048 1.5494)
			(layers "F.Cu" "F.Mask" "F.Paste")
			(net "PCIE_IOM_TO_COMP_8_DP")
		)
		(pad "44" smd rect
			(at 1.500124 2.275078)
			(size 0.3048 1.5494)
			(layers "F.Cu" "F.Mask" "F.Paste")
			(net "M2_1_ALERT#")
		)
		(pad "45" smd rect
			(at 1.75006 -5.275072)
			(size 0.3048 1.5494)
			(layers "F.Cu" "F.Mask" "F.Paste")
			(net "GND")
		)
		(pad "46" smd rect
			(at 1.999996 2.275078)
			(size 0.3048 1.5494)
			(layers "F.Cu" "F.Mask" "F.Paste")
			(net "Net_621")
		)
		(pad "47" smd rect
			(at 2.249932 -5.275072)
			(size 0.3048 1.5494)
			(layers "F.Cu" "F.Mask" "F.Paste")
			(net "PCIE_COMP_TO_IOM_8_DN")
		)
		(pad "48" smd rect
			(at 2.500122 2.275078)
			(size 0.3048 1.5494)
			(layers "F.Cu" "F.Mask" "F.Paste")
			(net "Net_622")
		)
		(pad "49" smd rect
			(at 2.750058 -5.275072)
			(size 0.3048 1.5494)
			(layers "F.Cu" "F.Mask" "F.Paste")
			(net "PCIE_COMP_TO_IOM_8_DP")
		)
		(pad "50" smd rect
			(at 2.999994 2.275078)
			(size 0.3048 1.5494)
			(layers "F.Cu" "F.Mask" "F.Paste")
			(net "PCIE_COMP_TO_IOM_RST_2")
		)
		(pad "51" smd rect
			(at 3.24993 -5.275072)
			(size 0.3048 1.5494)
			(layers "F.Cu" "F.Mask" "F.Paste")
			(net "GND")
		)
		(pad "52" smd rect
			(at 3.50012 2.275078)
			(size 0.3048 1.5494)
			(layers "F.Cu" "F.Mask" "F.Paste")
			(net "M2_1_CLKREQ#")
		)
		(pad "53" smd rect
			(at 3.750056 -5.275072)
			(size 0.3048 1.5494)
			(layers "F.Cu" "F.Mask" "F.Paste")
			(net "PCIE_COMP_TO_IOM_CLK_2_DN")
		)
		(pad "54" smd rect
			(at 3.999992 2.275078)
			(size 0.3048 1.5494)
			(layers "F.Cu" "F.Mask" "F.Paste")
			(net "Net_610")
		)
		(pad "55" smd rect
			(at 4.249928 -5.275072)
			(size 0.3048 1.5494)
			(layers "F.Cu" "F.Mask" "F.Paste")
			(net "PCIE_COMP_TO_IOM_CLK_2_DP")
		)
		(pad "56" smd rect
			(at 4.500118 2.275078)
			(size 0.3048 1.5494)
			(layers "F.Cu" "F.Mask" "F.Paste")
			(net "TP_M2_1_MFG_DAT")
		)
		(pad "57" smd rect
			(at 4.750054 -5.275072)
			(size 0.3048 1.5494)
			(layers "F.Cu" "F.Mask" "F.Paste")
			(net "GND")
		)
		(pad "58" smd rect
			(at 4.99999 2.275078)
			(size 0.3048 1.5494)
			(layers "F.Cu" "F.Mask" "F.Paste")
			(net "TP_M2_1_MFG_CLK")
		)
		(pad "67" smd rect
			(at 7.249922 -5.275072)
			(size 0.3048 1.5494)
			(layers "F.Cu" "F.Mask" "F.Paste")
			(net "Net_608")
		)
		(pad "68" smd rect
			(at 7.500112 2.275078)
			(size 0.3048 1.5494)
			(layers "F.Cu" "F.Mask" "F.Paste")
			(net "Net_611")
		)
		(pad "69" smd rect
			(at 7.750048 -5.275072)
			(size 0.3048 1.5494)
			(layers "F.Cu" "F.Mask" "F.Paste")
			(net "Net_609")
		)
		(pad "70" smd rect
			(at 7.999984 2.275078)
			(size 0.3048 1.5494)
			(layers "F.Cu" "F.Mask" "F.Paste")
			(net "P3V3_M2")
		)
		(pad "71" smd rect
			(at 8.24992 -5.275072)
			(size 0.3048 1.5494)
			(layers "F.Cu" "F.Mask" "F.Paste")
			(net "GND")
		)
		(pad "72" smd rect
			(at 8.50011 2.275078)
			(size 0.3048 1.5494)
			(layers "F.Cu" "F.Mask" "F.Paste")
			(net "P3V3_M2")
		)
		(pad "73" smd rect
			(at 8.750046 -5.275072)
			(size 0.3048 1.5494)
			(layers "F.Cu" "F.Mask" "F.Paste")
			(net "GND")
		)
		(pad "74" smd rect
			(at 8.999982 2.275078)
			(size 0.3048 1.5494)
			(layers "F.Cu" "F.Mask" "F.Paste")
			(net "P3V3_M2")
		)
		(pad "75" smd rect
			(at 9.249918 -5.275072)
			(size 0.3048 1.5494)
			(layers "F.Cu" "F.Mask" "F.Paste")
			(net "GND")
		)
		(pad "76" smd rect
			(at -10.349992 -4.500118)
			(size 1.1938 2.7432)
			(layers "F.Cu" "F.Mask" "F.Paste")
			(net "GND")
		)
		(pad "77" smd rect
			(at 10.349992 -4.500118)
			(size 1.1938 2.7432)
			(layers "F.Cu" "F.Mask" "F.Paste")
			(net "GND")
		)
		(zone
			(layer "F.Cu")
			(hatch none 0.5)
			(connect_pads
				(clearance 0)
			)
			(min_thickness 0.25)
			(keepout
				(tracks allowed)
				(vias not_allowed)
				(pads allowed)
				(copperpour not_allowed)
				(footprints allowed)
			)
			(placement
				(enabled no)
				(sheetname "")
			)
			(fill
				(thermal_gap 0.5)
				(thermal_bridge_width 0.5)
				(island_removal_mode 0)
			)
			(polygon
				(pts
					(xy 194.997578 -133.592316) (xy 209.30235 -133.592316) (xy 209.30235 -134.100316) (xy 194.997578 -134.100316)
				)
			)
		)
		(zone
			(layer "F.Cu")
			(hatch none 0.5)
			(connect_pads
				(clearance 0)
			)
			(min_thickness 0.25)
			(keepout
				(tracks allowed)
				(vias not_allowed)
				(pads allowed)
				(copperpour not_allowed)
				(footprints allowed)
			)
			(placement
				(enabled no)
				(sheetname "")
			)
			(fill
				(thermal_gap 0.5)
				(thermal_bridge_width 0.5)
				(island_removal_mode 0)
			)
			(polygon
				(pts
					(xy 195.247514 -128.099566) (xy 209.552286 -128.099566) (xy 209.552286 -128.607566) (xy 195.247514 -128.607566)
				)
			)
		)
		(zone
			(layer "F.Cu")
			(hatch none 0.5)
			(connect_pads
				(clearance 0)
			)
			(min_thickness 0.25)
			(keepout
				(tracks allowed)
				(vias not_allowed)
				(pads allowed)
				(copperpour not_allowed)
				(footprints allowed)
			)
			(placement
				(enabled no)
				(sheetname "")
			)
			(fill
				(thermal_gap 0.5)
				(thermal_bridge_width 0.5)
				(island_removal_mode 0)
			)
			(polygon
				(pts
					(xy 211.497418 -133.592316) (xy 213.802214 -133.592316) (xy 213.802214 -134.100316) (xy 211.497418 -134.100316)
				)
			)
		)
		(zone
			(layer "F.Cu")
			(hatch none 0.5)
			(connect_pads
				(clearance 0)
			)
			(min_thickness 0.25)
			(keepout
				(tracks allowed)
				(vias not_allowed)
				(pads allowed)
				(copperpour not_allowed)
				(footprints allowed)
			)
			(placement
				(enabled no)
				(sheetname "")
			)
			(fill
				(thermal_gap 0.5)
				(thermal_bridge_width 0.5)
				(island_removal_mode 0)
			)
			(polygon
				(pts
					(xy 211.747608 -128.099566) (xy 213.552278 -128.099566) (xy 213.552278 -128.607566) (xy 211.747608 -128.607566)
				)
			)
		)
		(zone
			(layers "F.Cu" "B.Cu" "In1.Cu" "In2.Cu" "In3.Cu" "In4.Cu" "In5.Cu" "In6.Cu")
			(hatch none 0.5)
			(connect_pads
				(clearance 0)
			)
			(min_thickness 0.25)
			(keepout
				(tracks not_allowed)
				(vias allowed)
				(pads allowed)
				(copperpour not_allowed)
				(footprints allowed)
			)
			(placement
				(enabled no)
				(sheetname "")
			)
			(fill
				(thermal_gap 0.5)
				(thermal_bridge_width 0.5)
				(island_removal_mode 0)
			)
			(polygon
				(pts
					(arc
						(start 195.263516 -129.599944)
						(mid 193.536316 -129.599944)
						(end 195.263516 -129.599944)
					)
				)
			)
		)
		(zone
			(layers "F.Cu" "B.Cu" "In1.Cu" "In2.Cu" "In3.Cu" "In4.Cu" "In5.Cu" "In6.Cu")
			(hatch none 0.5)
			(connect_pads
				(clearance 0)
			)
			(min_thickness 0.25)
			(keepout
				(tracks not_allowed)
				(vias allowed)
				(pads allowed)
				(copperpour not_allowed)
				(footprints allowed)
			)
			(placement
				(enabled no)
				(sheetname "")
			)
			(fill
				(thermal_gap 0.5)
				(thermal_bridge_width 0.5)
				(island_removal_mode 0)
			)
			(polygon
				(pts
					(arc
						(start 215.504776 -129.599944)
						(mid 213.294976 -129.599944)
						(end 215.504776 -129.599944)
					)
				)
			)
		)
	)
	(footprint ""
		(layer "F.Cu")
		(at 99.3902 -153.7716 -90)
		(property "Reference" "R19"
			(at 0 0 270)
			(layer "F.SilkS")
			(hide yes)
			(effects
				(font
					(size 1.27 1.27)
				)
			)
		)
		(property "Value" "4K7R2F-GP"
			(at 0.064008 -3.993896 270)
			(unlocked yes)
			(layer "F.Fab")
			(hide yes)
			(effects
				(font
					(size 1.016 1.016)
					(thickness 0.1524)
				)
			)
		)
		(property "Device Type" "R402H16"
			(at 0.064008 -5.517896 270)
			(unlocked yes)
			(layer "F.Fab")
			(hide yes)
			(effects
				(font
					(size 1.016 1.016)
					(thickness 0.1524)
				)
			)
		)
		(duplicate_pad_numbers_are_jumpers no)
		(fp_line
			(start -0.508 -0.9398)
			(end -0.508 0.9398)
			(stroke
				(width 0.1524)
				(type default)
			)
			(layer "F.SilkS")
		)
		(fp_line
			(start 0.508 -0.9398)
			(end -0.508 -0.9398)
			(stroke
				(width 0.1524)
				(type default)
			)
			(layer "F.SilkS")
		)
		(fp_rect
			(start -0.508 0.9398)
			(end 0.508 -0.9398)
			(stroke
				(width 0)
				(type default)
			)
			(fill no)
			(layer "F.CrtYd")
		)
		(fp_rect
			(start -0.508 0.9398)
			(end 0.508 -0.9398)
			(stroke
				(width 0)
				(type default)
			)
			(fill no)
			(layer "F.Fab")
		)
		(pad "1" smd custom
			(at 0 -0.4445 270)
			(size 0.1397 0.1397)
			(layers "F.Cu" "F.Mask" "F.Paste")
			(net "P3V3_STBY")
			(options
				(clearance outline)
				(anchor circle)
			)
			(primitives
				(gr_poly
					(pts
						(arc
							(start -0.1778 -0.2794)
							(mid -0.249642 -0.249642)
							(end -0.2794 -0.1778)
						)
						(arc
							(start -0.2794 0.1778)
							(mid -0.249642 0.249642)
							(end -0.1778 0.2794)
						)
						(arc
							(start 0.1778 0.2794)
							(mid 0.249642 0.249642)
							(end 0.2794 0.1778)
						)
						(arc
							(start 0.2794 -0.1778)
							(mid 0.249642 -0.249642)
							(end 0.1778 -0.2794)
						)
					)
					(width 0)
					(fill yes)
				)
			)
		)
		(pad "2" smd custom
			(at 0 0.4445 270)
			(size 0.1397 0.1397)
			(layers "F.Cu" "F.Mask" "F.Paste")
			(net "CFG_SEL0")
			(options
				(clearance outline)
				(anchor circle)
			)
			(primitives
				(gr_poly
					(pts
						(arc
							(start -0.1778 -0.2794)
							(mid -0.249642 -0.249642)
							(end -0.2794 -0.1778)
						)
						(arc
							(start -0.2794 0.1778)
							(mid -0.249642 0.249642)
							(end -0.1778 0.2794)
						)
						(arc
							(start 0.1778 0.2794)
							(mid 0.249642 0.249642)
							(end 0.2794 0.1778)
						)
						(arc
							(start 0.2794 -0.1778)
							(mid 0.249642 -0.249642)
							(end 0.1778 -0.2794)
						)
					)
					(width 0)
					(fill yes)
				)
			)
		)
	)
	(footprint ""
		(layer "F.Cu")
		(at 162.089338 -10.847578 90)
		(property "Reference" "L10"
			(at 0 0 90)
			(layer "F.SilkS")
			(hide yes)
			(effects
				(font
					(size 1.27 1.27)
				)
			)
		)
		(property "Value" "COIL-3D3UH-48-GP"
			(at -3.8735 -3.048 90)
			(unlocked yes)
			(layer "F.Fab")
			(hide yes)
			(effects
				(font
					(size 1.016 1.016)
					(thickness 0.1524)
				)
			)
		)
		(property "Device Type" "L4947-1215H119"
			(at -3.8735 -4.572 90)
			(unlocked yes)
			(layer "F.Fab")
			(hide yes)
			(effects
				(font
					(size 1.016 1.016)
					(thickness 0.1524)
				)
			)
		)
		(duplicate_pad_numbers_are_jumpers no)
		(fp_line
			(start 2.6035 -3.429)
			(end 2.6035 3.429)
			(stroke
				(width 0.1524)
				(type default)
			)
			(layer "F.SilkS")
		)
		(fp_line
			(start -2.6035 -3.429)
			(end 2.6035 -3.429)
			(stroke
				(width 0.1524)
				(type default)
			)
			(layer "F.SilkS")
		)
		(fp_line
			(start 2.6035 3.429)
			(end -2.6035 3.429)
			(stroke
				(width 0.1524)
				(type default)
			)
			(layer "F.SilkS")
		)
		(fp_line
			(start -2.6035 3.429)
			(end -2.6035 -3.429)
			(stroke
				(width 0.1524)
				(type default)
			)
			(layer "F.SilkS")
		)
		(fp_rect
			(start -2.3495 2.4257)
			(end 2.3495 -2.4257)
			(stroke
				(width 0)
				(type default)
			)
			(fill no)
			(layer "F.CrtYd")
		)
		(fp_poly
			(pts
				(xy -2.8575 3.5052) (xy -2.8575 2.4257) (xy 2.3495 2.4257) (xy 2.3495 -2.4257) (xy -2.3495 -2.4257)
				(xy -2.3495 2.413) (xy -2.8575 2.413) (xy -2.8575 -3.5052) (xy 2.8575 -3.5052) (xy 2.8575 3.5052)
			)
			(stroke
				(width 0)
				(type default)
			)
			(fill no)
			(layer "F.CrtYd")
		)
		(fp_rect
			(start -2.8575 3.5052)
			(end 2.8575 -3.5052)
			(stroke
				(width 0)
				(type default)
			)
			(fill no)
			(layer "F.Fab")
		)
		(pad "1" smd rect
			(at 0 -1.999996 90)
			(size 2.0066 2.3622)
			(layers "F.Cu" "F.Mask" "F.Paste")
			(net "P1V8_STBY_SW")
		)
		(pad "2" smd rect
			(at 0 1.999996 90)
			(size 2.0066 2.3622)
			(layers "F.Cu" "F.Mask" "F.Paste")
			(net "P1V8_STBY")
		)
	)
	(footprint ""
		(layer "F.Cu")
		(at 71.890128 -186.292744 180)
		(property "Reference" "C197"
			(at 0 0 180)
			(layer "F.SilkS")
			(hide yes)
			(effects
				(font
					(size 1.27 1.27)
				)
			)
		)
		(property "Value" "SC1U16V3KX-5GP"
			(at 0 -2.8194 180)
			(unlocked yes)
			(layer "F.Fab")
			(hide yes)
			(effects
				(font
					(size 1.016 1.016)
					(thickness 0.1524)
				)
			)
		)
		(property "Device Type" "C603H36"
			(at 0 -4.3434 180)
			(unlocked yes)
			(layer "F.Fab")
			(hide yes)
			(effects
				(font
					(size 1.016 1.016)
					(thickness 0.1524)
				)
			)
		)
		(duplicate_pad_numbers_are_jumpers no)
		(fp_line
			(start 0.508 0)
			(end -0.508 0)
			(stroke
				(width 0.2032)
				(type default)
			)
			(layer "F.SilkS")
		)
		(fp_rect
			(start -0.5842 1.3335)
			(end 0.5842 -1.3335)
			(stroke
				(width 0)
				(type default)
			)
			(fill no)
			(layer "F.CrtYd")
		)
		(fp_rect
			(start -0.5842 1.3335)
			(end 0.5842 -1.3335)
			(stroke
				(width 0)
				(type default)
			)
			(fill no)
			(layer "F.Fab")
		)
		(pad "1" smd custom
			(at 0 -0.762 180)
			(size 0.2159 0.2159)
			(layers "F.Cu" "F.Mask" "F.Paste")
			(net "TPS74801_P2V5_STBY_BIAS")
			(options
				(clearance outline)
				(anchor circle)
			)
			(primitives
				(gr_poly
					(pts
						(arc
							(start -0.3302 -0.4318)
							(mid -0.402042 -0.402042)
							(end -0.4318 -0.3302)
						)
						(arc
							(start -0.4318 0.3302)
							(mid -0.402042 0.402042)
							(end -0.3302 0.4318)
						)
						(arc
							(start 0.3302 0.4318)
							(mid 0.402042 0.402042)
							(end 0.4318 0.3302)
						)
						(arc
							(start 0.4318 -0.3302)
							(mid 0.402042 -0.402042)
							(end 0.3302 -0.4318)
						)
					)
					(width 0)
					(fill yes)
				)
			)
		)
		(pad "2" smd custom
			(at 0 0.762 180)
			(size 0.2159 0.2159)
			(layers "F.Cu" "F.Mask" "F.Paste")
			(net "GND")
			(options
				(clearance outline)
				(anchor circle)
			)
			(primitives
				(gr_poly
					(pts
						(arc
							(start -0.3302 -0.4318)
							(mid -0.402042 -0.402042)
							(end -0.4318 -0.3302)
						)
						(arc
							(start -0.4318 0.3302)
							(mid -0.402042 0.402042)
							(end -0.3302 0.4318)
						)
						(arc
							(start 0.3302 0.4318)
							(mid 0.402042 0.402042)
							(end 0.4318 0.3302)
						)
						(arc
							(start 0.4318 -0.3302)
							(mid 0.402042 -0.402042)
							(end 0.3302 -0.4318)
						)
					)
					(width 0)
					(fill yes)
				)
			)
		)
	)
	(footprint ""
		(layer "F.Cu")
		(at 62.769496 -158.270956 -90)
		(property "Reference" "L4"
			(at 0 0 270)
			(layer "F.SilkS")
			(hide yes)
			(effects
				(font
					(size 1.27 1.27)
				)
			)
		)
		(property "Value" "MMZ2012S601ATA1N-GP"
			(at 0 -4.2418 270)
			(unlocked yes)
			(layer "F.Fab")
			(hide yes)
			(effects
				(font
					(size 1.016 1.016)
					(thickness 0.1524)
				)
			)
		)
		(property "Device Type" "L805H42"
			(at 0 -5.7912 270)
			(unlocked yes)
			(layer "F.Fab")
			(hide yes)
			(effects
				(font
					(size 1.016 1.016)
					(thickness 0.1524)
				)
			)
		)
		(duplicate_pad_numbers_are_jumpers no)
		(fp_line
			(start -0.889 1.7018)
			(end -0.889 -1.7018)
			(stroke
				(width 0.1524)
				(type default)
			)
			(layer "F.SilkS")
		)
		(fp_line
			(start 0.889 1.7018)
			(end -0.889 1.7018)
			(stroke
				(width 0.1524)
				(type default)
			)
			(layer "F.SilkS")
		)
		(fp_line
			(start -0.889 -1.7018)
			(end 0.889 -1.7018)
			(stroke
				(width 0.1524)
				(type default)
			)
			(layer "F.SilkS")
		)
		(fp_line
			(start 0.889 -1.7018)
			(end 0.889 1.7018)
			(stroke
				(width 0.1524)
				(type default)
			)
			(layer "F.SilkS")
		)
		(fp_rect
			(start -0.9652 1.778)
			(end 0.9652 -1.778)
			(stroke
				(width 0)
				(type default)
			)
			(fill no)
			(layer "F.CrtYd")
		)
		(fp_rect
			(start -0.9652 1.778)
			(end 0.9652 -1.778)
			(stroke
				(width 0)
				(type default)
			)
			(fill no)
			(layer "F.Fab")
		)
		(pad "1" smd rect
			(at 0 -0.9652 270)
			(size 1.397 1.143)
			(layers "F.Cu" "F.Mask" "F.Paste")
			(net "P3V3_STBY")
		)
		(pad "2" smd rect
			(at 0 0.9652 270)
			(size 1.397 1.143)
			(layers "F.Cu" "F.Mask" "F.Paste")
			(net "VPLLAV33")
		)
	)
	(footprint ""
		(layer "F.Cu")
		(at 117.942868 -14.111732)
		(property "Reference" "R431"
			(at 0 0 0)
			(layer "F.SilkS")
			(hide yes)
			(effects
				(font
					(size 1.27 1.27)
				)
			)
		)
		(property "Value" "10R2F-L-GP"
			(at 0.064008 -3.993896 0)
			(unlocked yes)
			(layer "F.Fab")
			(hide yes)
			(effects
				(font
					(size 1.016 1.016)
					(thickness 0.1524)
				)
			)
		)
		(property "Device Type" "R402H14"
			(at 0.064008 -5.517896 0)
			(unlocked yes)
			(layer "F.Fab")
			(hide yes)
			(effects
				(font
					(size 1.016 1.016)
					(thickness 0.1524)
				)
			)
		)
		(duplicate_pad_numbers_are_jumpers no)
		(fp_line
			(start -0.508 -0.9398)
			(end -0.508 0.9398)
			(stroke
				(width 0.1524)
				(type default)
			)
			(layer "F.SilkS")
		)
		(fp_line
			(start 0.508 -0.9398)
			(end -0.508 -0.9398)
			(stroke
				(width 0.1524)
				(type default)
			)
			(layer "F.SilkS")
		)
		(fp_rect
			(start -0.508 0.9398)
			(end 0.508 -0.9398)
			(stroke
				(width 0)
				(type default)
			)
			(fill no)
			(layer "F.CrtYd")
		)
		(fp_rect
			(start -0.508 0.9398)
			(end 0.508 -0.9398)
			(stroke
				(width 0)
				(type default)
			)
			(fill no)
			(layer "F.Fab")
		)
		(pad "1" smd custom
			(at 0 -0.4445)
			(size 0.1397 0.1397)
			(layers "F.Cu" "F.Mask" "F.Paste")
			(net "P12V_IOM")
			(options
				(clearance outline)
				(anchor circle)
			)
			(primitives
				(gr_poly
					(pts
						(arc
							(start -0.1778 -0.2794)
							(mid -0.249642 -0.249642)
							(end -0.2794 -0.1778)
						)
						(arc
							(start -0.2794 0.1778)
							(mid -0.249642 0.249642)
							(end -0.1778 0.2794)
						)
						(arc
							(start 0.1778 0.2794)
							(mid 0.249642 0.249642)
							(end 0.2794 0.1778)
						)
						(arc
							(start 0.2794 -0.1778)
							(mid 0.249642 -0.249642)
							(end 0.1778 -0.2794)
						)
					)
					(width 0)
					(fill yes)
				)
			)
		)
		(pad "2" smd custom
			(at 0 0.4445)
			(size 0.1397 0.1397)
			(layers "F.Cu" "F.Mask" "F.Paste")
			(net "MB0_VCC")
			(options
				(clearance outline)
				(anchor circle)
			)
			(primitives
				(gr_poly
					(pts
						(arc
							(start -0.1778 -0.2794)
							(mid -0.249642 -0.249642)
							(end -0.2794 -0.1778)
						)
						(arc
							(start -0.2794 0.1778)
							(mid -0.249642 0.249642)
							(end -0.1778 0.2794)
						)
						(arc
							(start 0.1778 0.2794)
							(mid 0.249642 0.249642)
							(end 0.2794 0.1778)
						)
						(arc
							(start 0.2794 -0.1778)
							(mid 0.249642 -0.249642)
							(end 0.1778 -0.2794)
						)
					)
					(width 0)
					(fill yes)
				)
			)
		)
	)
	(footprint ""
		(layer "F.Cu")
		(at 149.29993 -78.000098)
		(property "Reference" ""
			(at 0 0 0)
			(layer "F.SilkS")
			(hide yes)
			(effects
				(font
					(size 1.27 1.27)
				)
			)
		)
		(property "Value" "*"
			(at -6.38175 0.19685 0)
			(unlocked yes)
			(layer "F.Fab")
			(hide yes)
			(effects
				(font
					(size 1.016 1.016)
					(thickness 0.1524)
				)
			)
		)
		(duplicate_pad_numbers_are_jumpers no)
		(fp_poly
			(pts
				(arc
					(start 5.0673 0)
					(mid -5.0673 0)
					(end 5.0673 0)
				)
			)
			(stroke
				(width 0)
				(type default)
			)
			(fill no)
			(layer "B.CrtYd")
		)
		(fp_poly
			(pts
				(arc
					(start 5.0673 0)
					(mid -5.0673 0)
					(end 5.0673 0)
				)
			)
			(stroke
				(width 0)
				(type default)
			)
			(fill no)
			(layer "F.CrtYd")
		)
		(fp_poly
			(pts
				(arc
					(start 5.0673 0)
					(mid -5.0673 0)
					(end 5.0673 0)
				)
			)
			(stroke
				(width 0)
				(type default)
			)
			(fill no)
			(layer "B.Fab")
		)
		(fp_poly
			(pts
				(arc
					(start 5.0673 0)
					(mid -5.0673 0)
					(end 5.0673 0)
				)
			)
			(stroke
				(width 0)
				(type default)
			)
			(fill no)
			(layer "F.Fab")
		)
		(pad "1" thru_hole circle
			(at 0 0)
			(size 9.525 9.525)
			(drill 3.5052)
			(layers "*.Cu" "*.Mask")
			(remove_unused_layers no)
			(net "Net_42")
			(clearance -2.5019)
			(thermal_gap 0.3048)
			(padstack
				(mode front_inner_back)
				(layer "Inner"
					(shape circle)
					(size 3.9116 3.9116)
					(clearance 0.3048)
				)
				(layer "B.Cu"
					(shape circle)
					(size 9.525 9.525)
					(clearance -2.5019)
				)
			)
		)
	)
	(footprint ""
		(layer "F.Cu")
		(at 204.216 -110.7694 180)
		(property "Reference" "R544"
			(at 0 0 180)
			(layer "F.SilkS")
			(hide yes)
			(effects
				(font
					(size 1.27 1.27)
				)
			)
		)
		(property "Value" "4K7R2F-GP"
			(at 0.064008 -3.993896 180)
			(unlocked yes)
			(layer "F.Fab")
			(hide yes)
			(effects
				(font
					(size 1.016 1.016)
					(thickness 0.1524)
				)
			)
		)
		(property "Device Type" "R402H16"
			(at 0.064008 -5.517896 180)
			(unlocked yes)
			(layer "F.Fab")
			(hide yes)
			(effects
				(font
					(size 1.016 1.016)
					(thickness 0.1524)
				)
			)
		)
		(duplicate_pad_numbers_are_jumpers no)
		(fp_line
			(start 0.508 -0.9398)
			(end -0.508 -0.9398)
			(stroke
				(width 0.1524)
				(type default)
			)
			(layer "F.SilkS")
		)
		(fp_line
			(start -0.508 -0.9398)
			(end -0.508 0.9398)
			(stroke
				(width 0.1524)
				(type default)
			)
			(layer "F.SilkS")
		)
		(fp_rect
			(start -0.508 0.9398)
			(end 0.508 -0.9398)
			(stroke
				(width 0)
				(type default)
			)
			(fill no)
			(layer "F.CrtYd")
		)
		(fp_rect
			(start -0.508 0.9398)
			(end 0.508 -0.9398)
			(stroke
				(width 0)
				(type default)
			)
			(fill no)
			(layer "F.Fab")
		)
		(pad "1" smd custom
			(at 0 -0.4445 180)
			(size 0.1397 0.1397)
			(layers "F.Cu" "F.Mask" "F.Paste")
			(net "TEMP_2_A1")
			(options
				(clearance outline)
				(anchor circle)
			)
			(primitives
				(gr_poly
					(pts
						(arc
							(start -0.1778 -0.2794)
							(mid -0.249642 -0.249642)
							(end -0.2794 -0.1778)
						)
						(arc
							(start -0.2794 0.1778)
							(mid -0.249642 0.249642)
							(end -0.1778 0.2794)
						)
						(arc
							(start 0.1778 0.2794)
							(mid 0.249642 0.249642)
							(end 0.2794 0.1778)
						)
						(arc
							(start 0.2794 -0.1778)
							(mid 0.249642 -0.249642)
							(end 0.1778 -0.2794)
						)
					)
					(width 0)
					(fill yes)
				)
			)
		)
		(pad "2" smd custom
			(at 0 0.4445 180)
			(size 0.1397 0.1397)
			(layers "F.Cu" "F.Mask" "F.Paste")
			(net "GND")
			(options
				(clearance outline)
				(anchor circle)
			)
			(primitives
				(gr_poly
					(pts
						(arc
							(start -0.1778 -0.2794)
							(mid -0.249642 -0.249642)
							(end -0.2794 -0.1778)
						)
						(arc
							(start -0.2794 0.1778)
							(mid -0.249642 0.249642)
							(end -0.1778 0.2794)
						)
						(arc
							(start 0.1778 0.2794)
							(mid 0.249642 0.249642)
							(end 0.2794 0.1778)
						)
						(arc
							(start 0.2794 -0.1778)
							(mid 0.249642 -0.249642)
							(end 0.1778 -0.2794)
						)
					)
					(width 0)
					(fill yes)
				)
			)
		)
	)
	(footprint ""
		(layer "F.Cu")
		(at 202.946 -110.7694 180)
		(property "Reference" "R555"
			(at 0 0 180)
			(layer "F.SilkS")
			(hide yes)
			(effects
				(font
					(size 1.27 1.27)
				)
			)
		)
		(property "Value" "4K7R2F-GP"
			(at 0.064008 -3.993896 180)
			(unlocked yes)
			(layer "F.Fab")
			(hide yes)
			(effects
				(font
					(size 1.016 1.016)
					(thickness 0.1524)
				)
			)
		)
		(property "Device Type" "R402H16"
			(at 0.064008 -5.517896 180)
			(unlocked yes)
			(layer "F.Fab")
			(hide yes)
			(effects
				(font
					(size 1.016 1.016)
					(thickness 0.1524)
				)
			)
		)
		(duplicate_pad_numbers_are_jumpers no)
		(fp_line
			(start 0.508 -0.9398)
			(end -0.508 -0.9398)
			(stroke
				(width 0.1524)
				(type default)
			)
			(layer "F.SilkS")
		)
		(fp_line
			(start -0.508 -0.9398)
			(end -0.508 0.9398)
			(stroke
				(width 0.1524)
				(type default)
			)
			(layer "F.SilkS")
		)
		(fp_rect
			(start -0.508 0.9398)
			(end 0.508 -0.9398)
			(stroke
				(width 0)
				(type default)
			)
			(fill no)
			(layer "F.CrtYd")
		)
		(fp_rect
			(start -0.508 0.9398)
			(end 0.508 -0.9398)
			(stroke
				(width 0)
				(type default)
			)
			(fill no)
			(layer "F.Fab")
		)
		(pad "1" smd custom
			(at 0 -0.4445 180)
			(size 0.1397 0.1397)
			(layers "F.Cu" "F.Mask" "F.Paste")
			(net "TEMP_2_A0")
			(options
				(clearance outline)
				(anchor circle)
			)
			(primitives
				(gr_poly
					(pts
						(arc
							(start -0.1778 -0.2794)
							(mid -0.249642 -0.249642)
							(end -0.2794 -0.1778)
						)
						(arc
							(start -0.2794 0.1778)
							(mid -0.249642 0.249642)
							(end -0.1778 0.2794)
						)
						(arc
							(start 0.1778 0.2794)
							(mid 0.249642 0.249642)
							(end 0.2794 0.1778)
						)
						(arc
							(start 0.2794 -0.1778)
							(mid 0.249642 -0.249642)
							(end 0.1778 -0.2794)
						)
					)
					(width 0)
					(fill yes)
				)
			)
		)
		(pad "2" smd custom
			(at 0 0.4445 180)
			(size 0.1397 0.1397)
			(layers "F.Cu" "F.Mask" "F.Paste")
			(net "GND")
			(options
				(clearance outline)
				(anchor circle)
			)
			(primitives
				(gr_poly
					(pts
						(arc
							(start -0.1778 -0.2794)
							(mid -0.249642 -0.249642)
							(end -0.2794 -0.1778)
						)
						(arc
							(start -0.2794 0.1778)
							(mid -0.249642 0.249642)
							(end -0.1778 0.2794)
						)
						(arc
							(start 0.1778 0.2794)
							(mid 0.249642 0.249642)
							(end 0.2794 0.1778)
						)
						(arc
							(start 0.2794 -0.1778)
							(mid 0.249642 -0.249642)
							(end 0.1778 -0.2794)
						)
					)
					(width 0)
					(fill yes)
				)
			)
		)
	)
	(footprint ""
		(layer "F.Cu")
		(at 73.05548 -185.90768)
		(property "Reference" "R508"
			(at 0 0 0)
			(layer "F.SilkS")
			(hide yes)
			(effects
				(font
					(size 1.27 1.27)
				)
			)
		)
		(property "Value" "0R2J-2-GP"
			(at 0.064008 -3.993896 0)
			(unlocked yes)
			(layer "F.Fab")
			(hide yes)
			(effects
				(font
					(size 1.016 1.016)
					(thickness 0.1524)
				)
			)
		)
		(property "Device Type" "R402H16"
			(at 0.064008 -5.517896 0)
			(unlocked yes)
			(layer "F.Fab")
			(hide yes)
			(effects
				(font
					(size 1.016 1.016)
					(thickness 0.1524)
				)
			)
		)
		(duplicate_pad_numbers_are_jumpers no)
		(fp_line
			(start -0.508 -0.9398)
			(end -0.508 0.9398)
			(stroke
				(width 0.1524)
				(type default)
			)
			(layer "F.SilkS")
		)
		(fp_line
			(start 0.508 -0.9398)
			(end -0.508 -0.9398)
			(stroke
				(width 0.1524)
				(type default)
			)
			(layer "F.SilkS")
		)
		(fp_rect
			(start -0.508 0.9398)
			(end 0.508 -0.9398)
			(stroke
				(width 0)
				(type default)
			)
			(fill no)
			(layer "F.CrtYd")
		)
		(fp_rect
			(start -0.508 0.9398)
			(end 0.508 -0.9398)
			(stroke
				(width 0)
				(type default)
			)
			(fill no)
			(layer "F.Fab")
		)
		(pad "1" smd custom
			(at 0 -0.4445)
			(size 0.1397 0.1397)
			(layers "F.Cu" "F.Mask" "F.Paste")
			(net "P5V_STBY")
			(options
				(clearance outline)
				(anchor circle)
			)
			(primitives
				(gr_poly
					(pts
						(arc
							(start -0.1778 -0.2794)
							(mid -0.249642 -0.249642)
							(end -0.2794 -0.1778)
						)
						(arc
							(start -0.2794 0.1778)
							(mid -0.249642 0.249642)
							(end -0.1778 0.2794)
						)
						(arc
							(start 0.1778 0.2794)
							(mid 0.249642 0.249642)
							(end 0.2794 0.1778)
						)
						(arc
							(start 0.2794 -0.1778)
							(mid 0.249642 -0.249642)
							(end 0.1778 -0.2794)
						)
					)
					(width 0)
					(fill yes)
				)
			)
		)
		(pad "2" smd custom
			(at 0 0.4445)
			(size 0.1397 0.1397)
			(layers "F.Cu" "F.Mask" "F.Paste")
			(net "TPS74801_P2V5_STBY_BIAS")
			(options
				(clearance outline)
				(anchor circle)
			)
			(primitives
				(gr_poly
					(pts
						(arc
							(start -0.1778 -0.2794)
							(mid -0.249642 -0.249642)
							(end -0.2794 -0.1778)
						)
						(arc
							(start -0.2794 0.1778)
							(mid -0.249642 0.249642)
							(end -0.1778 0.2794)
						)
						(arc
							(start 0.1778 0.2794)
							(mid 0.249642 0.249642)
							(end 0.2794 0.1778)
						)
						(arc
							(start 0.2794 -0.1778)
							(mid 0.249642 -0.249642)
							(end 0.1778 -0.2794)
						)
					)
					(width 0)
					(fill yes)
				)
			)
		)
	)
	(footprint ""
		(layer "F.Cu")
		(at 63.17615 -160.979104 90)
		(property "Reference" "C96"
			(at 0 0 90)
			(layer "F.SilkS")
			(hide yes)
			(effects
				(font
					(size 1.27 1.27)
				)
			)
		)
		(property "Value" "SC100P50V2JN-3GP"
			(at 1.1811 -2.7051 90)
			(unlocked yes)
			(layer "F.Fab")
			(hide yes)
			(effects
				(font
					(size 1.016 1.016)
					(thickness 0.1524)
				)
			)
		)
		(property "Device Type" "C402H22"
			(at 1.1811 -4.2291 90)
			(unlocked yes)
			(layer "F.Fab")
			(hide yes)
			(effects
				(font
					(size 1.016 1.016)
					(thickness 0.1524)
				)
			)
		)
		(duplicate_pad_numbers_are_jumpers no)
		(fp_rect
			(start -0.4318 0.9525)
			(end 0.4318 -0.9525)
			(stroke
				(width 0)
				(type default)
			)
			(fill no)
			(layer "F.CrtYd")
		)
		(fp_rect
			(start -0.4318 0.9525)
			(end 0.4318 -0.9525)
			(stroke
				(width 0)
				(type default)
			)
			(fill no)
			(layer "F.Fab")
		)
		(pad "1" smd custom
			(at 0 -0.4445 90)
			(size 0.1524 0.1524)
			(layers "F.Cu" "F.Mask" "F.Paste")
			(net "VPLLAV33")
			(options
				(clearance outline)
				(anchor circle)
			)
			(primitives
				(gr_poly
					(pts
						(arc
							(start 0.3048 -0.2032)
							(mid 0.275042 -0.275042)
							(end 0.2032 -0.3048)
						)
						(arc
							(start -0.2032 -0.3048)
							(mid -0.275042 -0.275042)
							(end -0.3048 -0.2032)
						)
						(arc
							(start -0.3048 0.2032)
							(mid -0.275042 0.275042)
							(end -0.2032 0.3048)
						)
						(arc
							(start 0.2032 0.3048)
							(mid 0.275042 0.275042)
							(end 0.3048 0.2032)
						)
					)
					(width 0)
					(fill yes)
				)
			)
		)
		(pad "2" smd custom
			(at 0 0.4445 90)
			(size 0.1524 0.1524)
			(layers "F.Cu" "F.Mask" "F.Paste")
			(net "GND")
			(options
				(clearance outline)
				(anchor circle)
			)
			(primitives
				(gr_poly
					(pts
						(arc
							(start 0.3048 -0.2032)
							(mid 0.275042 -0.275042)
							(end 0.2032 -0.3048)
						)
						(arc
							(start -0.2032 -0.3048)
							(mid -0.275042 -0.275042)
							(end -0.3048 -0.2032)
						)
						(arc
							(start -0.3048 0.2032)
							(mid -0.275042 0.275042)
							(end -0.2032 0.3048)
						)
						(arc
							(start 0.2032 0.3048)
							(mid 0.275042 0.275042)
							(end 0.3048 0.2032)
						)
					)
					(width 0)
					(fill yes)
				)
			)
		)
	)
	(footprint ""
		(layer "F.Cu")
		(at 213.647528 -139.191238 45)
		(property "Reference" "VIA66"
			(at 0 0 45)
			(layer "F.SilkS")
			(hide yes)
			(effects
				(font
					(size 1.27 1.27)
				)
			)
		)
		(property "Value" "85OHM-8L-1D6MM-L16L18-GP"
			(at 4.064105 0.609655 45)
			(unlocked yes)
			(layer "F.Fab")
			(hide yes)
			(effects
				(font
					(size 1.016 1.016)
					(thickness 0.1524)
				)
			)
		)
		(property "Device Type" "VIA-PCIE-4P-368076"
			(at 4.064105 -0.914474 45)
			(unlocked yes)
			(layer "F.Fab")
			(hide yes)
			(effects
				(font
					(size 1.016 1.016)
					(thickness 0.1524)
				)
			)
		)
		(duplicate_pad_numbers_are_jumpers no)
		(fp_poly
			(pts
				(xy -1.841491 -0.381057) (xy 1.841509 -0.381058) (xy 1.841508 0.380942) (xy -1.841491 0.380942)
			)
			(stroke
				(width 0)
				(type default)
			)
			(fill no)
			(layer "F.CrtYd")
		)
		(fp_poly
			(pts
				(xy -1.841491 -0.381057) (xy 1.841509 -0.381058) (xy 1.841508 0.380942) (xy -1.841491 0.380942)
			)
			(stroke
				(width 0)
				(type default)
			)
			(fill no)
			(layer "F.Fab")
		)
		(pad "1" thru_hole circle
			(at -1.460499 0 45)
			(size 0.508 0.508)
			(drill 0.254)
			(layers "*.Cu" "*.Mask")
			(remove_unused_layers no)
			(net "GND")
			(clearance 0.127)
			(thermal_gap 0.127)
		)
		(pad "2" thru_hole circle
			(at -0.4445 0 45)
			(size 0.508 0.508)
			(drill 0.254)
			(layers "*.Cu" "*.Mask")
			(remove_unused_layers no)
			(net "PCIE_COMP_TO_IOM_CLK_2_DP")
			(clearance 0.127)
			(thermal_gap 0.127)
		)
		(pad "3" thru_hole circle
			(at 0.4445 0 45)
			(size 0.508 0.508)
			(drill 0.254)
			(layers "*.Cu" "*.Mask")
			(remove_unused_layers no)
			(net "PCIE_COMP_TO_IOM_CLK_2_DN")
			(clearance 0.127)
			(thermal_gap 0.127)
		)
		(pad "4" thru_hole circle
			(at 1.460499 0 45)
			(size 0.508 0.508)
			(drill 0.254)
			(layers "*.Cu" "*.Mask")
			(remove_unused_layers no)
			(net "GND")
			(clearance 0.127)
			(thermal_gap 0.127)
		)
	)
	(footprint ""
		(layer "F.Cu")
		(at 20.0787 -160.971484 180)
		(property "Reference" "R529"
			(at 0 0 180)
			(layer "F.SilkS")
			(hide yes)
			(effects
				(font
					(size 1.27 1.27)
				)
			)
		)
		(property "Value" "0R5J-5-GP"
			(at 0 -8.9535 180)
			(unlocked yes)
			(layer "F.Fab")
			(hide yes)
			(effects
				(font
					(size 1.27 1.016)
					(thickness 0.1524)
				)
			)
		)
		(property "Device Type" "R805H24"
			(at 0 -10.6299 180)
			(unlocked yes)
			(layer "F.Fab")
			(hide yes)
			(effects
				(font
					(size 1.27 1.016)
					(thickness 0.1524)
				)
			)
		)
		(duplicate_pad_numbers_are_jumpers no)
		(fp_line
			(start 0.889 1.7018)
			(end 0.889 -0.508)
			(stroke
				(width 0.1524)
				(type default)
			)
			(layer "F.SilkS")
		)
		(fp_line
			(start 0.889 -1.7018)
			(end 0.889 -0.381)
			(stroke
				(width 0.1524)
				(type default)
			)
			(layer "F.SilkS")
		)
		(fp_line
			(start 0.889 -1.7018)
			(end -0.889 -1.7018)
			(stroke
				(width 0.1524)
				(type default)
			)
			(layer "F.SilkS")
		)
		(fp_line
			(start -0.889 1.7018)
			(end 0.889 1.7018)
			(stroke
				(width 0.1524)
				(type default)
			)
			(layer "F.SilkS")
		)
		(fp_line
			(start -0.889 0.0762)
			(end -0.889 1.7018)
			(stroke
				(width 0.1524)
				(type default)
			)
			(layer "F.SilkS")
		)
		(fp_line
			(start -0.889 -1.7018)
			(end -0.889 0.2794)
			(stroke
				(width 0.1524)
				(type default)
			)
			(layer "F.SilkS")
		)
		(fp_poly
			(pts
				(xy 0.9652 -1.778) (xy 0.9652 1.778) (xy -0.9652 1.778) (xy -0.9652 -1.778)
			)
			(stroke
				(width 0)
				(type default)
			)
			(fill no)
			(layer "F.CrtYd")
		)
		(fp_rect
			(start -0.9652 1.778)
			(end 0.9652 -1.778)
			(stroke
				(width 0)
				(type default)
			)
			(fill no)
			(layer "F.Fab")
		)
		(pad "1" smd rect
			(at 0 -0.9652 180)
			(size 1.397 1.143)
			(layers "F.Cu" "F.Mask" "F.Paste")
			(net "P1V2_STBY")
		)
		(pad "2" smd rect
			(at 0 0.9652 180)
			(size 1.397 1.143)
			(layers "F.Cu" "F.Mask" "F.Paste")
			(net "TPS74801_P1V2_STBY_OUT")
		)
	)
	(footprint ""
		(layer "F.Cu")
		(at 35.394646 -174.67961 -90)
		(property "Reference" "R499"
			(at 0 0 270)
			(layer "F.SilkS")
			(hide yes)
			(effects
				(font
					(size 1.27 1.27)
				)
			)
		)
		(property "Value" "10KR2F-2-GP"
			(at 0.064008 -3.993896 270)
			(unlocked yes)
			(layer "F.Fab")
			(hide yes)
			(effects
				(font
					(size 1.016 1.016)
					(thickness 0.1524)
				)
			)
		)
		(property "Device Type" "R402H16"
			(at 0.064008 -5.517896 270)
			(unlocked yes)
			(layer "F.Fab")
			(hide yes)
			(effects
				(font
					(size 1.016 1.016)
					(thickness 0.1524)
				)
			)
		)
		(duplicate_pad_numbers_are_jumpers no)
		(fp_line
			(start -0.508 -0.9398)
			(end -0.508 0.9398)
			(stroke
				(width 0.1524)
				(type default)
			)
			(layer "F.SilkS")
		)
		(fp_line
			(start 0.508 -0.9398)
			(end -0.508 -0.9398)
			(stroke
				(width 0.1524)
				(type default)
			)
			(layer "F.SilkS")
		)
		(fp_rect
			(start -0.508 0.9398)
			(end 0.508 -0.9398)
			(stroke
				(width 0)
				(type default)
			)
			(fill no)
			(layer "F.CrtYd")
		)
		(fp_rect
			(start -0.508 0.9398)
			(end 0.508 -0.9398)
			(stroke
				(width 0)
				(type default)
			)
			(fill no)
			(layer "F.Fab")
		)
		(pad "1" smd custom
			(at 0 -0.4445 270)
			(size 0.1397 0.1397)
			(layers "F.Cu" "F.Mask" "F.Paste")
			(net "P3V3_STBY_VFB")
			(options
				(clearance outline)
				(anchor circle)
			)
			(primitives
				(gr_poly
					(pts
						(arc
							(start -0.1778 -0.2794)
							(mid -0.249642 -0.249642)
							(end -0.2794 -0.1778)
						)
						(arc
							(start -0.2794 0.1778)
							(mid -0.249642 0.249642)
							(end -0.1778 0.2794)
						)
						(arc
							(start 0.1778 0.2794)
							(mid 0.249642 0.249642)
							(end 0.2794 0.1778)
						)
						(arc
							(start 0.2794 -0.1778)
							(mid 0.249642 -0.249642)
							(end 0.1778 -0.2794)
						)
					)
					(width 0)
					(fill yes)
				)
			)
		)
		(pad "2" smd custom
			(at 0 0.4445 270)
			(size 0.1397 0.1397)
			(layers "F.Cu" "F.Mask" "F.Paste")
			(net "AGND_P3V3_STBY")
			(options
				(clearance outline)
				(anchor circle)
			)
			(primitives
				(gr_poly
					(pts
						(arc
							(start -0.1778 -0.2794)
							(mid -0.249642 -0.249642)
							(end -0.2794 -0.1778)
						)
						(arc
							(start -0.2794 0.1778)
							(mid -0.249642 0.249642)
							(end -0.1778 0.2794)
						)
						(arc
							(start 0.1778 0.2794)
							(mid 0.249642 0.249642)
							(end 0.2794 0.1778)
						)
						(arc
							(start 0.2794 -0.1778)
							(mid 0.249642 -0.249642)
							(end 0.1778 -0.2794)
						)
					)
					(width 0)
					(fill yes)
				)
			)
		)
	)
	(footprint ""
		(layer "F.Cu")
		(at 44.9072 -158.5976)
		(property "Reference" "R173"
			(at 0 0 0)
			(layer "F.SilkS")
			(hide yes)
			(effects
				(font
					(size 1.27 1.27)
				)
			)
		)
		(property "Value" "0R2J-2-GP"
			(at 0.064008 -3.993896 0)
			(unlocked yes)
			(layer "F.Fab")
			(hide yes)
			(effects
				(font
					(size 1.016 1.016)
					(thickness 0.1524)
				)
			)
		)
		(property "Device Type" "R402H16"
			(at 0.064008 -5.517896 0)
			(unlocked yes)
			(layer "F.Fab")
			(hide yes)
			(effects
				(font
					(size 1.016 1.016)
					(thickness 0.1524)
				)
			)
		)
		(duplicate_pad_numbers_are_jumpers no)
		(fp_line
			(start -0.508 -0.9398)
			(end -0.508 0.9398)
			(stroke
				(width 0.1524)
				(type default)
			)
			(layer "F.SilkS")
		)
		(fp_line
			(start 0.508 -0.9398)
			(end -0.508 -0.9398)
			(stroke
				(width 0.1524)
				(type default)
			)
			(layer "F.SilkS")
		)
		(fp_rect
			(start -0.508 0.9398)
			(end 0.508 -0.9398)
			(stroke
				(width 0)
				(type default)
			)
			(fill no)
			(layer "F.CrtYd")
		)
		(fp_rect
			(start -0.508 0.9398)
			(end 0.508 -0.9398)
			(stroke
				(width 0)
				(type default)
			)
			(fill no)
			(layer "F.Fab")
		)
		(pad "1" smd custom
			(at 0 -0.4445)
			(size 0.1397 0.1397)
			(layers "F.Cu" "F.Mask" "F.Paste")
			(net "I2C_M2_1_SCL")
			(options
				(clearance outline)
				(anchor circle)
			)
			(primitives
				(gr_poly
					(pts
						(arc
							(start -0.1778 -0.2794)
							(mid -0.249642 -0.249642)
							(end -0.2794 -0.1778)
						)
						(arc
							(start -0.2794 0.1778)
							(mid -0.249642 0.249642)
							(end -0.1778 0.2794)
						)
						(arc
							(start 0.1778 0.2794)
							(mid 0.249642 0.249642)
							(end 0.2794 0.1778)
						)
						(arc
							(start 0.2794 -0.1778)
							(mid 0.249642 -0.249642)
							(end 0.1778 -0.2794)
						)
					)
					(width 0)
					(fill yes)
				)
			)
		)
		(pad "2" smd custom
			(at 0 0.4445)
			(size 0.1397 0.1397)
			(layers "F.Cu" "F.Mask" "F.Paste")
			(net "BMC_SMB8_CLK")
			(options
				(clearance outline)
				(anchor circle)
			)
			(primitives
				(gr_poly
					(pts
						(arc
							(start -0.1778 -0.2794)
							(mid -0.249642 -0.249642)
							(end -0.2794 -0.1778)
						)
						(arc
							(start -0.2794 0.1778)
							(mid -0.249642 0.249642)
							(end -0.1778 0.2794)
						)
						(arc
							(start 0.1778 0.2794)
							(mid 0.249642 0.249642)
							(end 0.2794 0.1778)
						)
						(arc
							(start 0.2794 -0.1778)
							(mid 0.249642 -0.249642)
							(end 0.1778 -0.2794)
						)
					)
					(width 0)
					(fill yes)
				)
			)
		)
	)
	(footprint ""
		(layer "F.Cu")
		(at 28.2448 -180.7464)
		(property "Reference" "R495"
			(at 0 0 0)
			(layer "F.SilkS")
			(hide yes)
			(effects
				(font
					(size 1.27 1.27)
				)
			)
		)
		(property "Value" "866KR2F-GP"
			(at 0.064008 -3.993896 0)
			(unlocked yes)
			(layer "F.Fab")
			(hide yes)
			(effects
				(font
					(size 1.016 1.016)
					(thickness 0.1524)
				)
			)
		)
		(property "Device Type" "R402H16"
			(at 0.064008 -5.517896 0)
			(unlocked yes)
			(layer "F.Fab")
			(hide yes)
			(effects
				(font
					(size 1.016 1.016)
					(thickness 0.1524)
				)
			)
		)
		(duplicate_pad_numbers_are_jumpers no)
		(fp_line
			(start -0.508 -0.9398)
			(end -0.508 0.9398)
			(stroke
				(width 0.1524)
				(type default)
			)
			(layer "F.SilkS")
		)
		(fp_line
			(start 0.508 -0.9398)
			(end -0.508 -0.9398)
			(stroke
				(width 0.1524)
				(type default)
			)
			(layer "F.SilkS")
		)
		(fp_rect
			(start -0.508 0.9398)
			(end 0.508 -0.9398)
			(stroke
				(width 0)
				(type default)
			)
			(fill no)
			(layer "F.CrtYd")
		)
		(fp_rect
			(start -0.508 0.9398)
			(end 0.508 -0.9398)
			(stroke
				(width 0)
				(type default)
			)
			(fill no)
			(layer "F.Fab")
		)
		(pad "1" smd custom
			(at 0 -0.4445)
			(size 0.1397 0.1397)
			(layers "F.Cu" "F.Mask" "F.Paste")
			(net "P3V3_STBY_VREG")
			(options
				(clearance outline)
				(anchor circle)
			)
			(primitives
				(gr_poly
					(pts
						(arc
							(start -0.1778 -0.2794)
							(mid -0.249642 -0.249642)
							(end -0.2794 -0.1778)
						)
						(arc
							(start -0.2794 0.1778)
							(mid -0.249642 0.249642)
							(end -0.1778 0.2794)
						)
						(arc
							(start 0.1778 0.2794)
							(mid 0.249642 0.249642)
							(end 0.2794 0.1778)
						)
						(arc
							(start 0.2794 -0.1778)
							(mid 0.249642 -0.249642)
							(end 0.1778 -0.2794)
						)
					)
					(width 0)
					(fill yes)
				)
			)
		)
		(pad "2" smd custom
			(at 0 0.4445)
			(size 0.1397 0.1397)
			(layers "F.Cu" "F.Mask" "F.Paste")
			(net "P3V3_STBY_RF")
			(options
				(clearance outline)
				(anchor circle)
			)
			(primitives
				(gr_poly
					(pts
						(arc
							(start -0.1778 -0.2794)
							(mid -0.249642 -0.249642)
							(end -0.2794 -0.1778)
						)
						(arc
							(start -0.2794 0.1778)
							(mid -0.249642 0.249642)
							(end -0.1778 0.2794)
						)
						(arc
							(start 0.1778 0.2794)
							(mid 0.249642 0.249642)
							(end 0.2794 0.1778)
						)
						(arc
							(start 0.2794 -0.1778)
							(mid 0.249642 -0.249642)
							(end 0.1778 -0.2794)
						)
					)
					(width 0)
					(fill yes)
				)
			)
		)
	)
	(footprint ""
		(layer "F.Cu")
		(at 87.976964 -151.068786 90)
		(property "Reference" "R92"
			(at 0 0 90)
			(layer "F.SilkS")
			(hide yes)
			(effects
				(font
					(size 1.27 1.27)
				)
			)
		)
		(property "Value" "0R2J-2-GP"
			(at 0.064008 -3.993896 90)
			(unlocked yes)
			(layer "F.Fab")
			(hide yes)
			(effects
				(font
					(size 1.016 1.016)
					(thickness 0.1524)
				)
			)
		)
		(property "Device Type" "R402H16"
			(at 0.064008 -5.517896 90)
			(unlocked yes)
			(layer "F.Fab")
			(hide yes)
			(effects
				(font
					(size 1.016 1.016)
					(thickness 0.1524)
				)
			)
		)
		(duplicate_pad_numbers_are_jumpers no)
		(fp_line
			(start 0.508 -0.9398)
			(end -0.508 -0.9398)
			(stroke
				(width 0.1524)
				(type default)
			)
			(layer "F.SilkS")
		)
		(fp_line
			(start -0.508 -0.9398)
			(end -0.508 0.9398)
			(stroke
				(width 0.1524)
				(type default)
			)
			(layer "F.SilkS")
		)
		(fp_rect
			(start -0.508 0.9398)
			(end 0.508 -0.9398)
			(stroke
				(width 0)
				(type default)
			)
			(fill no)
			(layer "F.CrtYd")
		)
		(fp_rect
			(start -0.508 0.9398)
			(end 0.508 -0.9398)
			(stroke
				(width 0)
				(type default)
			)
			(fill no)
			(layer "F.Fab")
		)
		(pad "1" smd custom
			(at 0 -0.4445 90)
			(size 0.1397 0.1397)
			(layers "F.Cu" "F.Mask" "F.Paste")
			(net "I2C_BMC_COMP_SCL_R")
			(options
				(clearance outline)
				(anchor circle)
			)
			(primitives
				(gr_poly
					(pts
						(arc
							(start -0.1778 -0.2794)
							(mid -0.249642 -0.249642)
							(end -0.2794 -0.1778)
						)
						(arc
							(start -0.2794 0.1778)
							(mid -0.249642 0.249642)
							(end -0.1778 0.2794)
						)
						(arc
							(start 0.1778 0.2794)
							(mid 0.249642 0.249642)
							(end 0.2794 0.1778)
						)
						(arc
							(start 0.2794 -0.1778)
							(mid 0.249642 -0.249642)
							(end 0.1778 -0.2794)
						)
					)
					(width 0)
					(fill yes)
				)
			)
		)
		(pad "2" smd custom
			(at 0 0.4445 90)
			(size 0.1397 0.1397)
			(layers "F.Cu" "F.Mask" "F.Paste")
			(net "I2C_BMC_COMP_SCL")
			(options
				(clearance outline)
				(anchor circle)
			)
			(primitives
				(gr_poly
					(pts
						(arc
							(start -0.1778 -0.2794)
							(mid -0.249642 -0.249642)
							(end -0.2794 -0.1778)
						)
						(arc
							(start -0.2794 0.1778)
							(mid -0.249642 0.249642)
							(end -0.1778 0.2794)
						)
						(arc
							(start 0.1778 0.2794)
							(mid 0.249642 0.249642)
							(end 0.2794 0.1778)
						)
						(arc
							(start 0.2794 -0.1778)
							(mid 0.249642 -0.249642)
							(end 0.1778 -0.2794)
						)
					)
					(width 0)
					(fill yes)
				)
			)
		)
	)
	(footprint ""
		(layer "F.Cu")
		(at 78.122018 -70.952868 90)
		(property "Reference" "VIA1"
			(at 0 0 90)
			(layer "F.SilkS")
			(hide yes)
			(effects
				(font
					(size 1.27 1.27)
				)
			)
		)
		(property "Value" "85OHM-8L-1D6MM-L16L18-GP"
			(at 4.064 0.6096 90)
			(unlocked yes)
			(layer "F.Fab")
			(hide yes)
			(effects
				(font
					(size 1.016 1.016)
					(thickness 0.1524)
				)
			)
		)
		(property "Device Type" "VIA-PCIE-4P-368076"
			(at 4.064 -0.9144 90)
			(unlocked yes)
			(layer "F.Fab")
			(hide yes)
			(effects
				(font
					(size 1.016 1.016)
					(thickness 0.1524)
				)
			)
		)
		(duplicate_pad_numbers_are_jumpers no)
		(fp_rect
			(start -1.8415 0.381)
			(end 1.8415 -0.381)
			(stroke
				(width 0)
				(type default)
			)
			(fill no)
			(layer "F.CrtYd")
		)
		(fp_rect
			(start -1.8415 0.381)
			(end 1.8415 -0.381)
			(stroke
				(width 0)
				(type default)
			)
			(fill no)
			(layer "F.Fab")
		)
		(pad "1" thru_hole circle
			(at -1.4605 0 90)
			(size 0.508 0.508)
			(drill 0.254)
			(layers "*.Cu" "*.Mask")
			(remove_unused_layers no)
			(net "GND")
			(clearance 0.127)
			(thermal_gap 0.127)
		)
		(pad "2" thru_hole circle
			(at -0.4445 0 90)
			(size 0.508 0.508)
			(drill 0.254)
			(layers "*.Cu" "*.Mask")
			(remove_unused_layers no)
			(net "PCIE_COMP_TO_IOM_16_DP")
			(clearance 0.127)
			(thermal_gap 0.127)
		)
		(pad "3" thru_hole circle
			(at 0.4445 0 90)
			(size 0.508 0.508)
			(drill 0.254)
			(layers "*.Cu" "*.Mask")
			(remove_unused_layers no)
			(net "PCIE_COMP_TO_IOM_16_DN")
			(clearance 0.127)
			(thermal_gap 0.127)
		)
		(pad "4" thru_hole circle
			(at 1.4605 0 90)
			(size 0.508 0.508)
			(drill 0.254)
			(layers "*.Cu" "*.Mask")
			(remove_unused_layers no)
			(net "GND")
			(clearance 0.127)
			(thermal_gap 0.127)
		)
	)
	(footprint ""
		(layer "F.Cu")
		(at 76.916026 -134.669276 90)
		(property "Reference" "U19"
			(at 0 0 90)
			(layer "F.SilkS")
			(hide yes)
			(effects
				(font
					(size 1.27 1.27)
				)
			)
		)
		(property "Value" "SN74LVC1G74DCUT-GP"
			(at 0 -11.1252 90)
			(unlocked yes)
			(layer "F.Fab")
			(hide yes)
			(effects
				(font
					(size 1.016 1.016)
					(thickness 0.1524)
				)
			)
		)
		(property "Device Type" "SSOIC8-4H36"
			(at 0 -12.6492 90)
			(unlocked yes)
			(layer "F.Fab")
			(hide yes)
			(effects
				(font
					(size 1.016 1.016)
					(thickness 0.1524)
				)
			)
		)
		(duplicate_pad_numbers_are_jumpers no)
		(fp_line
			(start 1.2573 -2.1844)
			(end 1.2573 2.1844)
			(stroke
				(width 0.1524)
				(type default)
			)
			(layer "F.SilkS")
		)
		(fp_line
			(start -1.2573 -2.1844)
			(end 1.2573 -2.1844)
			(stroke
				(width 0.1524)
				(type default)
			)
			(layer "F.SilkS")
		)
		(fp_line
			(start -1.2192 -0.3556)
			(end -0.9017 -0.0381)
			(stroke
				(width 0.1524)
				(type default)
			)
			(layer "F.SilkS")
		)
		(fp_line
			(start -1.2573 -0.3556)
			(end -1.2192 -0.3556)
			(stroke
				(width 0.1524)
				(type default)
			)
			(layer "F.SilkS")
		)
		(fp_line
			(start -0.9017 -0.0381)
			(end -1.2065 0.2667)
			(stroke
				(width 0.1524)
				(type default)
			)
			(layer "F.SilkS")
		)
		(fp_line
			(start -1.2065 0.2667)
			(end -1.27 0.2667)
			(stroke
				(width 0.1524)
				(type default)
			)
			(layer "F.SilkS")
		)
		(fp_line
			(start -1.2954 0.4572)
			(end -1.2954 2.159)
			(stroke
				(width 0.4064)
				(type default)
			)
			(layer "F.SilkS")
		)
		(fp_line
			(start 1.2573 2.1844)
			(end -1.2573 2.1844)
			(stroke
				(width 0.1524)
				(type default)
			)
			(layer "F.SilkS")
		)
		(fp_line
			(start -1.2573 2.1844)
			(end -1.2573 -2.1844)
			(stroke
				(width 0.1524)
				(type default)
			)
			(layer "F.SilkS")
		)
		(fp_poly
			(pts
				(xy -1.5113 2.4384) (xy 1.5113 2.4384) (xy 1.5113 -2.4384) (xy -1.5113 -2.4384)
			)
			(stroke
				(width 0)
				(type default)
			)
			(fill no)
			(layer "F.CrtYd")
		)
		(fp_poly
			(pts
				(xy -1.5113 -2.4384) (xy 1.5113 -2.4384) (xy 1.5113 2.4384) (xy -1.5113 2.4384)
			)
			(stroke
				(width 0)
				(type default)
			)
			(fill no)
			(layer "F.Fab")
		)
		(pad "1" smd rect
			(at -0.75057 1.1684 90)
			(size 0.3048 1.524)
			(layers "F.Cu" "F.Mask" "F.Paste")
			(net "DEBUG_HDR_UART_SEL")
		)
		(pad "2" smd rect
			(at -0.25019 1.1684 90)
			(size 0.3048 1.524)
			(layers "F.Cu" "F.Mask" "F.Paste")
			(net "D_FLIP_D")
		)
		(pad "3" smd rect
			(at 0.25019 1.1684 90)
			(size 0.3048 1.524)
			(layers "F.Cu" "F.Mask" "F.Paste")
			(net "D_FLIP_Q#")
		)
		(pad "4" smd rect
			(at 0.75057 1.1684 90)
			(size 0.3048 1.524)
			(layers "F.Cu" "F.Mask" "F.Paste")
			(net "GND")
		)
		(pad "5" smd rect
			(at 0.75057 -1.1684 90)
			(size 0.3048 1.524)
			(layers "F.Cu" "F.Mask" "F.Paste")
			(net "D_FLIP_Q")
		)
		(pad "6" smd rect
			(at 0.25019 -1.1684 90)
			(size 0.3048 1.524)
			(layers "F.Cu" "F.Mask" "F.Paste")
			(net "D_FLIP_CLR#")
		)
		(pad "7" smd rect
			(at -0.25019 -1.1684 90)
			(size 0.3048 1.524)
			(layers "F.Cu" "F.Mask" "F.Paste")
			(net "D_FLIP_PRE#")
		)
		(pad "8" smd rect
			(at -0.75057 -1.1684 90)
			(size 0.3048 1.524)
			(layers "F.Cu" "F.Mask" "F.Paste")
			(net "P3V3_STBY")
		)
	)
	(footprint ""
		(layer "B.Cu")
		(at 14.4272 -146.2659 90)
		(property "Reference" "R210"
			(at 0 0 90)
			(layer "B.SilkS")
			(hide yes)
			(effects
				(font
					(size 1.27 1.27)
				)
				(justify mirror)
			)
		)
		(property "Value" "120R2F-GP"
			(at -0.064008 -3.993896 90)
			(unlocked yes)
			(layer "B.Fab")
			(hide yes)
			(effects
				(font
					(size 1.016 1.016)
					(thickness 0.1524)
				)
				(justify mirror)
			)
		)
		(property "Device Type" "R402H16"
			(at -0.064008 -5.517896 90)
			(unlocked yes)
			(layer "B.Fab")
			(hide yes)
			(effects
				(font
					(size 1.016 1.016)
					(thickness 0.1524)
				)
				(justify mirror)
			)
		)
		(duplicate_pad_numbers_are_jumpers no)
		(fp_line
			(start 0.508 -0.9398)
			(end 0.508 0.9398)
			(stroke
				(width 0.1524)
				(type default)
			)
			(layer "B.SilkS")
		)
		(fp_line
			(start -0.508 -0.9398)
			(end 0.508 -0.9398)
			(stroke
				(width 0.1524)
				(type default)
			)
			(layer "B.SilkS")
		)
		(fp_rect
			(start 0.508 0.9398)
			(end -0.508 -0.9398)
			(stroke
				(width 0)
				(type default)
			)
			(fill no)
			(layer "B.CrtYd")
		)
		(fp_rect
			(start 0.508 0.9398)
			(end -0.508 -0.9398)
			(stroke
				(width 0)
				(type default)
			)
			(fill no)
			(layer "B.Fab")
		)
		(pad "1" smd custom
			(at 0 -0.4445 270)
			(size 0.1397 0.1397)
			(layers "B.Cu" "B.Mask" "B.Paste")
			(net "MEMCKE")
			(options
				(clearance outline)
				(anchor circle)
			)
			(primitives
				(gr_poly
					(pts
						(arc
							(start -0.1778 0.2794)
							(mid -0.249642 0.249642)
							(end -0.2794 0.1778)
						)
						(arc
							(start -0.2794 -0.1778)
							(mid -0.249642 -0.249642)
							(end -0.1778 -0.2794)
						)
						(arc
							(start 0.1778 -0.2794)
							(mid 0.249642 -0.249642)
							(end 0.2794 -0.1778)
						)
						(arc
							(start 0.2794 0.1778)
							(mid 0.249642 0.249642)
							(end 0.1778 0.2794)
						)
					)
					(width 0)
					(fill yes)
				)
			)
		)
		(pad "2" smd custom
			(at 0 0.4445 270)
			(size 0.1397 0.1397)
			(layers "B.Cu" "B.Mask" "B.Paste")
			(net "P1V2_STBY")
			(options
				(clearance outline)
				(anchor circle)
			)
			(primitives
				(gr_poly
					(pts
						(arc
							(start -0.1778 0.2794)
							(mid -0.249642 0.249642)
							(end -0.2794 0.1778)
						)
						(arc
							(start -0.2794 -0.1778)
							(mid -0.249642 -0.249642)
							(end -0.1778 -0.2794)
						)
						(arc
							(start 0.1778 -0.2794)
							(mid 0.249642 -0.249642)
							(end 0.2794 -0.1778)
						)
						(arc
							(start 0.2794 0.1778)
							(mid 0.249642 0.249642)
							(end 0.1778 0.2794)
						)
					)
					(width 0)
					(fill yes)
				)
			)
		)
	)
	(footprint ""
		(layer "B.Cu")
		(at 176.197768 -130.724148 180)
		(property "Reference" "C630"
			(at 0 0 0)
			(layer "B.SilkS")
			(hide yes)
			(effects
				(font
					(size 1.27 1.27)
				)
				(justify mirror)
			)
		)
		(property "Value" "SCD1U16V2KX-3GP"
			(at -1.1811 -2.7051 180)
			(unlocked yes)
			(layer "B.Fab")
			(hide yes)
			(effects
				(font
					(size 1.016 1.016)
					(thickness 0.1524)
				)
				(justify mirror)
			)
		)
		(property "Device Type" "C402H22"
			(at -1.1811 -4.2291 180)
			(unlocked yes)
			(layer "B.Fab")
			(hide yes)
			(effects
				(font
					(size 1.016 1.016)
					(thickness 0.1524)
				)
				(justify mirror)
			)
		)
		(duplicate_pad_numbers_are_jumpers no)
		(fp_rect
			(start 0.4318 0.9525)
			(end -0.4318 -0.9525)
			(stroke
				(width 0)
				(type default)
			)
			(fill no)
			(layer "B.CrtYd")
		)
		(fp_rect
			(start 0.4318 0.9525)
			(end -0.4318 -0.9525)
			(stroke
				(width 0)
				(type default)
			)
			(fill no)
			(layer "B.Fab")
		)
		(pad "1" smd custom
			(at 0 -0.4445)
			(size 0.1524 0.1524)
			(layers "B.Cu" "B.Mask" "B.Paste")
			(net "P3V3_M2")
			(options
				(clearance outline)
				(anchor circle)
			)
			(primitives
				(gr_poly
					(pts
						(arc
							(start 0.3048 0.2032)
							(mid 0.275042 0.275042)
							(end 0.2032 0.3048)
						)
						(arc
							(start -0.2032 0.3048)
							(mid -0.275042 0.275042)
							(end -0.3048 0.2032)
						)
						(arc
							(start -0.3048 -0.2032)
							(mid -0.275042 -0.275042)
							(end -0.2032 -0.3048)
						)
						(arc
							(start 0.2032 -0.3048)
							(mid 0.275042 -0.275042)
							(end 0.3048 -0.2032)
						)
					)
					(width 0)
					(fill yes)
				)
			)
		)
		(pad "2" smd custom
			(at 0 0.4445)
			(size 0.1524 0.1524)
			(layers "B.Cu" "B.Mask" "B.Paste")
			(net "GND")
			(options
				(clearance outline)
				(anchor circle)
			)
			(primitives
				(gr_poly
					(pts
						(arc
							(start 0.3048 0.2032)
							(mid 0.275042 0.275042)
							(end 0.2032 0.3048)
						)
						(arc
							(start -0.2032 0.3048)
							(mid -0.275042 0.275042)
							(end -0.3048 0.2032)
						)
						(arc
							(start -0.3048 -0.2032)
							(mid -0.275042 -0.275042)
							(end -0.2032 -0.3048)
						)
						(arc
							(start 0.2032 -0.3048)
							(mid 0.275042 -0.275042)
							(end 0.3048 -0.2032)
						)
					)
					(width 0)
					(fill yes)
				)
			)
		)
	)
	(footprint ""
		(layer "B.Cu")
		(at 95.377 -7.874 90)
		(property "Reference" "R37"
			(at 0 0 90)
			(layer "B.SilkS")
			(hide yes)
			(effects
				(font
					(size 1.27 1.27)
				)
				(justify mirror)
			)
		)
		(property "Value" "1MR2F-GP"
			(at -0.064008 -3.993896 90)
			(unlocked yes)
			(layer "B.Fab")
			(hide yes)
			(effects
				(font
					(size 1.016 1.016)
					(thickness 0.1524)
				)
				(justify mirror)
			)
		)
		(property "Device Type" "R402H16"
			(at -0.064008 -5.517896 90)
			(unlocked yes)
			(layer "B.Fab")
			(hide yes)
			(effects
				(font
					(size 1.016 1.016)
					(thickness 0.1524)
				)
				(justify mirror)
			)
		)
		(duplicate_pad_numbers_are_jumpers no)
		(fp_line
			(start 0.508 -0.9398)
			(end 0.508 0.9398)
			(stroke
				(width 0.1524)
				(type default)
			)
			(layer "B.SilkS")
		)
		(fp_line
			(start -0.508 -0.9398)
			(end 0.508 -0.9398)
			(stroke
				(width 0.1524)
				(type default)
			)
			(layer "B.SilkS")
		)
		(fp_rect
			(start 0.508 0.9398)
			(end -0.508 -0.9398)
			(stroke
				(width 0)
				(type default)
			)
			(fill no)
			(layer "B.CrtYd")
		)
		(fp_rect
			(start 0.508 0.9398)
			(end -0.508 -0.9398)
			(stroke
				(width 0)
				(type default)
			)
			(fill no)
			(layer "B.Fab")
		)
		(pad "1" smd custom
			(at 0 -0.4445 270)
			(size 0.1397 0.1397)
			(layers "B.Cu" "B.Mask" "B.Paste")
			(net "USB_CONN_GND")
			(options
				(clearance outline)
				(anchor circle)
			)
			(primitives
				(gr_poly
					(pts
						(arc
							(start -0.1778 0.2794)
							(mid -0.249642 0.249642)
							(end -0.2794 0.1778)
						)
						(arc
							(start -0.2794 -0.1778)
							(mid -0.249642 -0.249642)
							(end -0.1778 -0.2794)
						)
						(arc
							(start 0.1778 -0.2794)
							(mid 0.249642 -0.249642)
							(end 0.2794 -0.1778)
						)
						(arc
							(start 0.2794 0.1778)
							(mid 0.249642 0.249642)
							(end 0.1778 0.2794)
						)
					)
					(width 0)
					(fill yes)
				)
			)
		)
		(pad "2" smd custom
			(at 0 0.4445 270)
			(size 0.1397 0.1397)
			(layers "B.Cu" "B.Mask" "B.Paste")
			(net "GND")
			(options
				(clearance outline)
				(anchor circle)
			)
			(primitives
				(gr_poly
					(pts
						(arc
							(start -0.1778 0.2794)
							(mid -0.249642 0.249642)
							(end -0.2794 0.1778)
						)
						(arc
							(start -0.2794 -0.1778)
							(mid -0.249642 -0.249642)
							(end -0.1778 -0.2794)
						)
						(arc
							(start 0.1778 -0.2794)
							(mid 0.249642 -0.249642)
							(end 0.2794 -0.1778)
						)
						(arc
							(start 0.2794 0.1778)
							(mid 0.249642 0.249642)
							(end 0.1778 0.2794)
						)
					)
					(width 0)
					(fill yes)
				)
			)
		)
	)
	(footprint ""
		(layer "B.Cu")
		(at 41.4782 -134.3406 180)
		(property "Reference" "R373"
			(at 0 0 0)
			(layer "B.SilkS")
			(hide yes)
			(effects
				(font
					(size 1.27 1.27)
				)
				(justify mirror)
			)
		)
		(property "Value" "4K7R2F-GP"
			(at -0.064008 -3.993896 180)
			(unlocked yes)
			(layer "B.Fab")
			(hide yes)
			(effects
				(font
					(size 1.016 1.016)
					(thickness 0.1524)
				)
				(justify mirror)
			)
		)
		(property "Device Type" "R402H16"
			(at -0.064008 -5.517896 180)
			(unlocked yes)
			(layer "B.Fab")
			(hide yes)
			(effects
				(font
					(size 1.016 1.016)
					(thickness 0.1524)
				)
				(justify mirror)
			)
		)
		(duplicate_pad_numbers_are_jumpers no)
		(fp_line
			(start 0.508 -0.9398)
			(end 0.508 0.9398)
			(stroke
				(width 0.1524)
				(type default)
			)
			(layer "B.SilkS")
		)
		(fp_line
			(start -0.508 -0.9398)
			(end 0.508 -0.9398)
			(stroke
				(width 0.1524)
				(type default)
			)
			(layer "B.SilkS")
		)
		(fp_rect
			(start 0.508 0.9398)
			(end -0.508 -0.9398)
			(stroke
				(width 0)
				(type default)
			)
			(fill no)
			(layer "B.CrtYd")
		)
		(fp_rect
			(start 0.508 0.9398)
			(end -0.508 -0.9398)
			(stroke
				(width 0)
				(type default)
			)
			(fill no)
			(layer "B.Fab")
		)
		(pad "1" smd custom
			(at 0 -0.4445)
			(size 0.1397 0.1397)
			(layers "B.Cu" "B.Mask" "B.Paste")
			(net "P3V3_STBY")
			(options
				(clearance outline)
				(anchor circle)
			)
			(primitives
				(gr_poly
					(pts
						(arc
							(start -0.1778 0.2794)
							(mid -0.249642 0.249642)
							(end -0.2794 0.1778)
						)
						(arc
							(start -0.2794 -0.1778)
							(mid -0.249642 -0.249642)
							(end -0.1778 -0.2794)
						)
						(arc
							(start 0.1778 -0.2794)
							(mid 0.249642 -0.249642)
							(end 0.2794 -0.1778)
						)
						(arc
							(start 0.2794 0.1778)
							(mid 0.249642 0.249642)
							(end 0.1778 0.2794)
						)
					)
					(width 0)
					(fill yes)
				)
			)
		)
		(pad "2" smd custom
			(at 0 0.4445)
			(size 0.1397 0.1397)
			(layers "B.Cu" "B.Mask" "B.Paste")
			(net "BMC_GPIOS5")
			(options
				(clearance outline)
				(anchor circle)
			)
			(primitives
				(gr_poly
					(pts
						(arc
							(start -0.1778 0.2794)
							(mid -0.249642 0.249642)
							(end -0.2794 0.1778)
						)
						(arc
							(start -0.2794 -0.1778)
							(mid -0.249642 -0.249642)
							(end -0.1778 -0.2794)
						)
						(arc
							(start 0.1778 -0.2794)
							(mid 0.249642 -0.249642)
							(end 0.2794 -0.1778)
						)
						(arc
							(start 0.2794 0.1778)
							(mid 0.249642 0.249642)
							(end 0.1778 0.2794)
						)
					)
					(width 0)
					(fill yes)
				)
			)
		)
	)
	(footprint ""
		(layer "B.Cu")
		(at 12.091924 -136.715246 90)
		(property "Reference" "R251"
			(at 0 0 90)
			(layer "B.SilkS")
			(hide yes)
			(effects
				(font
					(size 1.27 1.27)
				)
				(justify mirror)
			)
		)
		(property "Value" "120R2F-GP"
			(at -0.064008 -3.993896 90)
			(unlocked yes)
			(layer "B.Fab")
			(hide yes)
			(effects
				(font
					(size 1.016 1.016)
					(thickness 0.1524)
				)
				(justify mirror)
			)
		)
		(property "Device Type" "R402H16"
			(at -0.064008 -5.517896 90)
			(unlocked yes)
			(layer "B.Fab")
			(hide yes)
			(effects
				(font
					(size 1.016 1.016)
					(thickness 0.1524)
				)
				(justify mirror)
			)
		)
		(duplicate_pad_numbers_are_jumpers no)
		(fp_line
			(start 0.508 -0.9398)
			(end 0.508 0.9398)
			(stroke
				(width 0.1524)
				(type default)
			)
			(layer "B.SilkS")
		)
		(fp_line
			(start -0.508 -0.9398)
			(end 0.508 -0.9398)
			(stroke
				(width 0.1524)
				(type default)
			)
			(layer "B.SilkS")
		)
		(fp_rect
			(start 0.508 0.9398)
			(end -0.508 -0.9398)
			(stroke
				(width 0)
				(type default)
			)
			(fill no)
			(layer "B.CrtYd")
		)
		(fp_rect
			(start 0.508 0.9398)
			(end -0.508 -0.9398)
			(stroke
				(width 0)
				(type default)
			)
			(fill no)
			(layer "B.Fab")
		)
		(pad "1" smd custom
			(at 0 -0.4445 270)
			(size 0.1397 0.1397)
			(layers "B.Cu" "B.Mask" "B.Paste")
			(net "MEMA_8")
			(options
				(clearance outline)
				(anchor circle)
			)
			(primitives
				(gr_poly
					(pts
						(arc
							(start -0.1778 0.2794)
							(mid -0.249642 0.249642)
							(end -0.2794 0.1778)
						)
						(arc
							(start -0.2794 -0.1778)
							(mid -0.249642 -0.249642)
							(end -0.1778 -0.2794)
						)
						(arc
							(start 0.1778 -0.2794)
							(mid 0.249642 -0.249642)
							(end 0.2794 -0.1778)
						)
						(arc
							(start 0.2794 0.1778)
							(mid 0.249642 0.249642)
							(end 0.1778 0.2794)
						)
					)
					(width 0)
					(fill yes)
				)
			)
		)
		(pad "2" smd custom
			(at 0 0.4445 270)
			(size 0.1397 0.1397)
			(layers "B.Cu" "B.Mask" "B.Paste")
			(net "P1V2_STBY")
			(options
				(clearance outline)
				(anchor circle)
			)
			(primitives
				(gr_poly
					(pts
						(arc
							(start -0.1778 0.2794)
							(mid -0.249642 0.249642)
							(end -0.2794 0.1778)
						)
						(arc
							(start -0.2794 -0.1778)
							(mid -0.249642 -0.249642)
							(end -0.1778 -0.2794)
						)
						(arc
							(start 0.1778 -0.2794)
							(mid 0.249642 -0.249642)
							(end 0.2794 -0.1778)
						)
						(arc
							(start 0.2794 0.1778)
							(mid 0.249642 0.249642)
							(end 0.1778 0.2794)
						)
					)
					(width 0)
					(fill yes)
				)
			)
		)
	)
	(footprint ""
		(layer "B.Cu")
		(at 35.2298 -122.9106 90)
		(property "Reference" "R767"
			(at 0 0 90)
			(layer "B.SilkS")
			(hide yes)
			(effects
				(font
					(size 1.27 1.27)
				)
				(justify mirror)
			)
		)
		(property "Value" "0R2J-2-GP"
			(at -0.064008 -3.993896 90)
			(unlocked yes)
			(layer "B.Fab")
			(hide yes)
			(effects
				(font
					(size 1.016 1.016)
					(thickness 0.1524)
				)
				(justify mirror)
			)
		)
		(property "Device Type" "R402H16"
			(at -0.064008 -5.517896 90)
			(unlocked yes)
			(layer "B.Fab")
			(hide yes)
			(effects
				(font
					(size 1.016 1.016)
					(thickness 0.1524)
				)
				(justify mirror)
			)
		)
		(duplicate_pad_numbers_are_jumpers no)
		(fp_line
			(start 0.508 -0.9398)
			(end 0.508 0.9398)
			(stroke
				(width 0.1524)
				(type default)
			)
			(layer "B.SilkS")
		)
		(fp_line
			(start -0.508 -0.9398)
			(end 0.508 -0.9398)
			(stroke
				(width 0.1524)
				(type default)
			)
			(layer "B.SilkS")
		)
		(fp_rect
			(start 0.508 0.9398)
			(end -0.508 -0.9398)
			(stroke
				(width 0)
				(type default)
			)
			(fill no)
			(layer "B.CrtYd")
		)
		(fp_rect
			(start 0.508 0.9398)
			(end -0.508 -0.9398)
			(stroke
				(width 0)
				(type default)
			)
			(fill no)
			(layer "B.Fab")
		)
		(pad "1" smd custom
			(at 0 -0.4445 270)
			(size 0.1397 0.1397)
			(layers "B.Cu" "B.Mask" "B.Paste")
			(net "FLA_CS_0_R")
			(options
				(clearance outline)
				(anchor circle)
			)
			(primitives
				(gr_poly
					(pts
						(arc
							(start -0.1778 0.2794)
							(mid -0.249642 0.249642)
							(end -0.2794 0.1778)
						)
						(arc
							(start -0.2794 -0.1778)
							(mid -0.249642 -0.249642)
							(end -0.1778 -0.2794)
						)
						(arc
							(start 0.1778 -0.2794)
							(mid 0.249642 -0.249642)
							(end 0.2794 -0.1778)
						)
						(arc
							(start 0.2794 0.1778)
							(mid 0.249642 0.249642)
							(end 0.1778 0.2794)
						)
					)
					(width 0)
					(fill yes)
				)
			)
		)
		(pad "2" smd custom
			(at 0 0.4445 270)
			(size 0.1397 0.1397)
			(layers "B.Cu" "B.Mask" "B.Paste")
			(net "BMC_CPU_DIS")
			(options
				(clearance outline)
				(anchor circle)
			)
			(primitives
				(gr_poly
					(pts
						(arc
							(start -0.1778 0.2794)
							(mid -0.249642 0.249642)
							(end -0.2794 0.1778)
						)
						(arc
							(start -0.2794 -0.1778)
							(mid -0.249642 -0.249642)
							(end -0.1778 -0.2794)
						)
						(arc
							(start 0.1778 -0.2794)
							(mid 0.249642 -0.249642)
							(end 0.2794 -0.1778)
						)
						(arc
							(start 0.2794 0.1778)
							(mid 0.249642 0.249642)
							(end 0.1778 0.2794)
						)
					)
					(width 0)
					(fill yes)
				)
			)
		)
	)
	(footprint ""
		(layer "B.Cu")
		(at 52.2478 -162.1028 -90)
		(property "Reference" "R821"
			(at 0 0 90)
			(layer "B.SilkS")
			(hide yes)
			(effects
				(font
					(size 1.27 1.27)
				)
				(justify mirror)
			)
		)
		(property "Value" "1KR2F-3-GP"
			(at -0.064008 -3.993896 270)
			(unlocked yes)
			(layer "B.Fab")
			(hide yes)
			(effects
				(font
					(size 1.016 1.016)
					(thickness 0.1524)
				)
				(justify mirror)
			)
		)
		(property "Device Type" "R402H16"
			(at -0.064008 -5.517896 270)
			(unlocked yes)
			(layer "B.Fab")
			(hide yes)
			(effects
				(font
					(size 1.016 1.016)
					(thickness 0.1524)
				)
				(justify mirror)
			)
		)
		(duplicate_pad_numbers_are_jumpers no)
		(fp_line
			(start -0.508 -0.9398)
			(end 0.508 -0.9398)
			(stroke
				(width 0.1524)
				(type default)
			)
			(layer "B.SilkS")
		)
		(fp_line
			(start 0.508 -0.9398)
			(end 0.508 0.9398)
			(stroke
				(width 0.1524)
				(type default)
			)
			(layer "B.SilkS")
		)
		(fp_rect
			(start 0.508 0.9398)
			(end -0.508 -0.9398)
			(stroke
				(width 0)
				(type default)
			)
			(fill no)
			(layer "B.CrtYd")
		)
		(fp_rect
			(start 0.508 0.9398)
			(end -0.508 -0.9398)
			(stroke
				(width 0)
				(type default)
			)
			(fill no)
			(layer "B.Fab")
		)
		(pad "1" smd custom
			(at 0 -0.4445 90)
			(size 0.1397 0.1397)
			(layers "B.Cu" "B.Mask" "B.Paste")
			(net "ADC_P3V3_M2")
			(options
				(clearance outline)
				(anchor circle)
			)
			(primitives
				(gr_poly
					(pts
						(arc
							(start -0.1778 0.2794)
							(mid -0.249642 0.249642)
							(end -0.2794 0.1778)
						)
						(arc
							(start -0.2794 -0.1778)
							(mid -0.249642 -0.249642)
							(end -0.1778 -0.2794)
						)
						(arc
							(start 0.1778 -0.2794)
							(mid 0.249642 -0.249642)
							(end 0.2794 -0.1778)
						)
						(arc
							(start 0.2794 0.1778)
							(mid 0.249642 0.249642)
							(end 0.1778 0.2794)
						)
					)
					(width 0)
					(fill yes)
				)
			)
		)
		(pad "2" smd custom
			(at 0 0.4445 90)
			(size 0.1397 0.1397)
			(layers "B.Cu" "B.Mask" "B.Paste")
			(net "GND")
			(options
				(clearance outline)
				(anchor circle)
			)
			(primitives
				(gr_poly
					(pts
						(arc
							(start -0.1778 0.2794)
							(mid -0.249642 0.249642)
							(end -0.2794 0.1778)
						)
						(arc
							(start -0.2794 -0.1778)
							(mid -0.249642 -0.249642)
							(end -0.1778 -0.2794)
						)
						(arc
							(start 0.1778 -0.2794)
							(mid 0.249642 -0.249642)
							(end 0.2794 -0.1778)
						)
						(arc
							(start 0.2794 0.1778)
							(mid 0.249642 0.249642)
							(end 0.1778 0.2794)
						)
					)
					(width 0)
					(fill yes)
				)
			)
		)
	)
	(footprint ""
		(layer "B.Cu")
		(at 136.323324 -17.460468 -90)
		(property "Reference" "R742"
			(at 0 0 90)
			(layer "B.SilkS")
			(hide yes)
			(effects
				(font
					(size 1.27 1.27)
				)
				(justify mirror)
			)
		)
		(property "Value" "10KR2F-2-GP"
			(at -0.064008 -3.993896 270)
			(unlocked yes)
			(layer "B.Fab")
			(hide yes)
			(effects
				(font
					(size 1.016 1.016)
					(thickness 0.1524)
				)
				(justify mirror)
			)
		)
		(property "Device Type" "R402H16"
			(at -0.064008 -5.517896 270)
			(unlocked yes)
			(layer "B.Fab")
			(hide yes)
			(effects
				(font
					(size 1.016 1.016)
					(thickness 0.1524)
				)
				(justify mirror)
			)
		)
		(duplicate_pad_numbers_are_jumpers no)
		(fp_line
			(start -0.508 -0.9398)
			(end 0.508 -0.9398)
			(stroke
				(width 0.1524)
				(type default)
			)
			(layer "B.SilkS")
		)
		(fp_line
			(start 0.508 -0.9398)
			(end 0.508 0.9398)
			(stroke
				(width 0.1524)
				(type default)
			)
			(layer "B.SilkS")
		)
		(fp_rect
			(start 0.508 0.9398)
			(end -0.508 -0.9398)
			(stroke
				(width 0)
				(type default)
			)
			(fill no)
			(layer "B.CrtYd")
		)
		(fp_rect
			(start 0.508 0.9398)
			(end -0.508 -0.9398)
			(stroke
				(width 0)
				(type default)
			)
			(fill no)
			(layer "B.Fab")
		)
		(pad "1" smd custom
			(at 0 -0.4445 90)
			(size 0.1397 0.1397)
			(layers "B.Cu" "B.Mask" "B.Paste")
			(net "P12V_IOM")
			(options
				(clearance outline)
				(anchor circle)
			)
			(primitives
				(gr_poly
					(pts
						(arc
							(start -0.1778 0.2794)
							(mid -0.249642 0.249642)
							(end -0.2794 0.1778)
						)
						(arc
							(start -0.2794 -0.1778)
							(mid -0.249642 -0.249642)
							(end -0.1778 -0.2794)
						)
						(arc
							(start 0.1778 -0.2794)
							(mid 0.249642 -0.249642)
							(end 0.2794 -0.1778)
						)
						(arc
							(start 0.2794 0.1778)
							(mid 0.249642 0.249642)
							(end 0.1778 0.2794)
						)
					)
					(width 0)
					(fill yes)
				)
			)
		)
		(pad "2" smd custom
			(at 0 0.4445 90)
			(size 0.1397 0.1397)
			(layers "B.Cu" "B.Mask" "B.Paste")
			(net "IOM_MATED_N")
			(options
				(clearance outline)
				(anchor circle)
			)
			(primitives
				(gr_poly
					(pts
						(arc
							(start -0.1778 0.2794)
							(mid -0.249642 0.249642)
							(end -0.2794 0.1778)
						)
						(arc
							(start -0.2794 -0.1778)
							(mid -0.249642 -0.249642)
							(end -0.1778 -0.2794)
						)
						(arc
							(start 0.1778 -0.2794)
							(mid 0.249642 -0.249642)
							(end 0.2794 -0.1778)
						)
						(arc
							(start 0.2794 0.1778)
							(mid 0.249642 0.249642)
							(end 0.1778 0.2794)
						)
					)
					(width 0)
					(fill yes)
				)
			)
		)
	)
	(footprint ""
		(layer "B.Cu")
		(at 224.881186 -55.88381)
		(property "Reference" "L6"
			(at 0 0 0)
			(layer "B.SilkS")
			(hide yes)
			(effects
				(font
					(size 1.27 1.27)
				)
				(justify mirror)
			)
		)
		(property "Value" "BLM21PG220SN1DGP"
			(at -0.0254 -5.6896 0)
			(unlocked yes)
			(layer "B.Fab")
			(hide yes)
			(effects
				(font
					(size 1.016 1.016)
					(thickness 0.1524)
				)
				(justify mirror)
			)
		)
		(property "Device Type" "L20125H42"
			(at -0.0254 -7.5946 0)
			(unlocked yes)
			(layer "B.Fab")
			(hide yes)
			(effects
				(font
					(size 1.016 1.016)
					(thickness 0.1524)
				)
				(justify mirror)
			)
		)
		(duplicate_pad_numbers_are_jumpers no)
		(fp_line
			(start -0.9144 -1.7018)
			(end 0.9144 -1.7018)
			(stroke
				(width 0.1524)
				(type default)
			)
			(layer "B.SilkS")
		)
		(fp_line
			(start -0.9144 1.7018)
			(end -0.9144 -1.7018)
			(stroke
				(width 0.1524)
				(type default)
			)
			(layer "B.SilkS")
		)
		(fp_line
			(start 0.9144 -1.7018)
			(end 0.9144 1.7018)
			(stroke
				(width 0.1524)
				(type default)
			)
			(layer "B.SilkS")
		)
		(fp_line
			(start 0.9144 1.7018)
			(end -0.9144 1.7018)
			(stroke
				(width 0.1524)
				(type default)
			)
			(layer "B.SilkS")
		)
		(fp_rect
			(start 1.0033 1.778)
			(end -1.0033 -1.778)
			(stroke
				(width 0)
				(type default)
			)
			(fill no)
			(layer "B.CrtYd")
		)
		(fp_poly
			(pts
				(xy 1.0033 -1.778) (xy -1.0033 -1.778) (xy -1.0033 1.778) (xy 1.0033 1.778)
			)
			(stroke
				(width 0)
				(type default)
			)
			(fill no)
			(layer "B.Fab")
		)
		(pad "1" smd rect
			(at 0 -0.9652 180)
			(size 1.397 1.143)
			(layers "B.Cu" "B.Mask" "B.Paste")
			(net "P12V_STBY")
		)
		(pad "2" smd rect
			(at 0 0.9652 180)
			(size 1.397 1.143)
			(layers "B.Cu" "B.Mask" "B.Paste")
			(net "P12V_STBY_VIN_PU1")
		)
	)
	(footprint ""
		(layer "B.Cu")
		(at 35.007296 -139.330684 180)
		(property "Reference" "C106"
			(at 0 0 0)
			(layer "B.SilkS")
			(hide yes)
			(effects
				(font
					(size 1.27 1.27)
				)
				(justify mirror)
			)
		)
		(property "Value" "SC4D7U25V5KX-1-GP"
			(at 0.0762 -6.1214 180)
			(unlocked yes)
			(layer "B.Fab")
			(hide yes)
			(effects
				(font
					(size 1.016 1.016)
					(thickness 0.1524)
				)
				(justify mirror)
			)
		)
		(property "Device Type" "C805H58"
			(at 0.0762 -8.1534 180)
			(unlocked yes)
			(layer "B.Fab")
			(hide yes)
			(effects
				(font
					(size 1.016 1.016)
					(thickness 0.1524)
				)
				(justify mirror)
			)
		)
		(duplicate_pad_numbers_are_jumpers no)
		(fp_line
			(start -0.635 0)
			(end 0.635 0)
			(stroke
				(width 0.508)
				(type default)
			)
			(layer "B.SilkS")
		)
		(fp_rect
			(start 0.9652 1.778)
			(end -0.9652 -1.778)
			(stroke
				(width 0)
				(type default)
			)
			(fill no)
			(layer "B.CrtYd")
		)
		(fp_poly
			(pts
				(xy 0.9652 -1.778) (xy -0.9652 -1.778) (xy -0.9652 1.778) (xy 0.9652 1.778)
			)
			(stroke
				(width 0)
				(type default)
			)
			(fill no)
			(layer "B.Fab")
		)
		(pad "1" smd rect
			(at 0 -0.9652)
			(size 1.397 1.143)
			(layers "B.Cu" "B.Mask" "B.Paste")
			(net "P3V3_STBY")
		)
		(pad "2" smd rect
			(at 0 0.9652)
			(size 1.397 1.143)
			(layers "B.Cu" "B.Mask" "B.Paste")
			(net "GND")
		)
	)
	(footprint ""
		(layer "B.Cu")
		(at 178.458114 -122.988832 -90)
		(property "Reference" "R816"
			(at 0 0 90)
			(layer "B.SilkS")
			(hide yes)
			(effects
				(font
					(size 1.27 1.27)
				)
				(justify mirror)
			)
		)
		(property "Value" "1KR2F-3-GP"
			(at -0.064008 -3.993896 270)
			(unlocked yes)
			(layer "B.Fab")
			(hide yes)
			(effects
				(font
					(size 1.016 1.016)
					(thickness 0.1524)
				)
				(justify mirror)
			)
		)
		(property "Device Type" "R402H16"
			(at -0.064008 -5.517896 270)
			(unlocked yes)
			(layer "B.Fab")
			(hide yes)
			(effects
				(font
					(size 1.016 1.016)
					(thickness 0.1524)
				)
				(justify mirror)
			)
		)
		(duplicate_pad_numbers_are_jumpers no)
		(fp_line
			(start -0.508 -0.9398)
			(end 0.508 -0.9398)
			(stroke
				(width 0.1524)
				(type default)
			)
			(layer "B.SilkS")
		)
		(fp_line
			(start 0.508 -0.9398)
			(end 0.508 0.9398)
			(stroke
				(width 0.1524)
				(type default)
			)
			(layer "B.SilkS")
		)
		(fp_rect
			(start 0.508 0.9398)
			(end -0.508 -0.9398)
			(stroke
				(width 0)
				(type default)
			)
			(fill no)
			(layer "B.CrtYd")
		)
		(fp_rect
			(start 0.508 0.9398)
			(end -0.508 -0.9398)
			(stroke
				(width 0)
				(type default)
			)
			(fill no)
			(layer "B.Fab")
		)
		(pad "1" smd custom
			(at 0 -0.4445 90)
			(size 0.1397 0.1397)
			(layers "B.Cu" "B.Mask" "B.Paste")
			(net "P1V8_STBY")
			(options
				(clearance outline)
				(anchor circle)
			)
			(primitives
				(gr_poly
					(pts
						(arc
							(start -0.1778 0.2794)
							(mid -0.249642 0.249642)
							(end -0.2794 0.1778)
						)
						(arc
							(start -0.2794 -0.1778)
							(mid -0.249642 -0.249642)
							(end -0.1778 -0.2794)
						)
						(arc
							(start 0.1778 -0.2794)
							(mid 0.249642 -0.249642)
							(end 0.2794 -0.1778)
						)
						(arc
							(start 0.2794 0.1778)
							(mid 0.249642 0.249642)
							(end 0.1778 0.2794)
						)
					)
					(width 0)
					(fill yes)
				)
			)
		)
		(pad "2" smd custom
			(at 0 0.4445 90)
			(size 0.1397 0.1397)
			(layers "B.Cu" "B.Mask" "B.Paste")
			(net "I2C_M2_2_1V8_SDA")
			(options
				(clearance outline)
				(anchor circle)
			)
			(primitives
				(gr_poly
					(pts
						(arc
							(start -0.1778 0.2794)
							(mid -0.249642 0.249642)
							(end -0.2794 0.1778)
						)
						(arc
							(start -0.2794 -0.1778)
							(mid -0.249642 -0.249642)
							(end -0.1778 -0.2794)
						)
						(arc
							(start 0.1778 -0.2794)
							(mid 0.249642 -0.249642)
							(end 0.2794 -0.1778)
						)
						(arc
							(start 0.2794 0.1778)
							(mid 0.249642 0.249642)
							(end 0.1778 0.2794)
						)
					)
					(width 0)
					(fill yes)
				)
			)
		)
	)
	(footprint ""
		(layer "B.Cu")
		(at 79.008478 -50.209196 180)
		(property "Reference" "C28"
			(at 0 0 0)
			(layer "B.SilkS")
			(hide yes)
			(effects
				(font
					(size 1.27 1.27)
				)
				(justify mirror)
			)
		)
		(property "Value" "SC2D2U25V5KX-2-GP"
			(at 0.0762 -6.1214 180)
			(unlocked yes)
			(layer "B.Fab")
			(hide yes)
			(effects
				(font
					(size 1.016 1.016)
					(thickness 0.1524)
				)
				(justify mirror)
			)
		)
		(property "Device Type" "C805H54"
			(at 0.0762 -8.1534 180)
			(unlocked yes)
			(layer "B.Fab")
			(hide yes)
			(effects
				(font
					(size 1.016 1.016)
					(thickness 0.1524)
				)
				(justify mirror)
			)
		)
		(duplicate_pad_numbers_are_jumpers no)
		(fp_line
			(start -0.635 0)
			(end 0.635 0)
			(stroke
				(width 0.508)
				(type default)
			)
			(layer "B.SilkS")
		)
		(fp_rect
			(start 0.9652 1.778)
			(end -0.9652 -1.778)
			(stroke
				(width 0)
				(type default)
			)
			(fill no)
			(layer "B.CrtYd")
		)
		(fp_poly
			(pts
				(xy 0.9652 -1.778) (xy -0.9652 -1.778) (xy -0.9652 1.778) (xy 0.9652 1.778)
			)
			(stroke
				(width 0)
				(type default)
			)
			(fill no)
			(layer "B.Fab")
		)
		(pad "1" smd rect
			(at 0 -0.9652)
			(size 1.397 1.143)
			(layers "B.Cu" "B.Mask" "B.Paste")
			(net "P12V_STBY")
		)
		(pad "2" smd rect
			(at 0 0.9652)
			(size 1.397 1.143)
			(layers "B.Cu" "B.Mask" "B.Paste")
			(net "GND")
		)
	)
	(footprint ""
		(layer "B.Cu")
		(at 166.585138 -9.171178)
		(property "Reference" "C218"
			(at 0 0 0)
			(layer "B.SilkS")
			(hide yes)
			(effects
				(font
					(size 1.27 1.27)
				)
				(justify mirror)
			)
		)
		(property "Value" "SC10U6D3V5KX-4GP"
			(at 0.0762 -6.1214 0)
			(unlocked yes)
			(layer "B.Fab")
			(hide yes)
			(effects
				(font
					(size 1.016 1.016)
					(thickness 0.1524)
				)
				(justify mirror)
			)
		)
		(property "Device Type" "C805H58"
			(at 0.0762 -8.1534 0)
			(unlocked yes)
			(layer "B.Fab")
			(hide yes)
			(effects
				(font
					(size 1.016 1.016)
					(thickness 0.1524)
				)
				(justify mirror)
			)
		)
		(duplicate_pad_numbers_are_jumpers no)
		(fp_line
			(start -0.635 0)
			(end 0.635 0)
			(stroke
				(width 0.508)
				(type default)
			)
			(layer "B.SilkS")
		)
		(fp_rect
			(start 0.9652 1.778)
			(end -0.9652 -1.778)
			(stroke
				(width 0)
				(type default)
			)
			(fill no)
			(layer "B.CrtYd")
		)
		(fp_poly
			(pts
				(xy 0.9652 -1.778) (xy -0.9652 -1.778) (xy -0.9652 1.778) (xy 0.9652 1.778)
			)
			(stroke
				(width 0)
				(type default)
			)
			(fill no)
			(layer "B.Fab")
		)
		(pad "1" smd rect
			(at 0 -0.9652 180)
			(size 1.397 1.143)
			(layers "B.Cu" "B.Mask" "B.Paste")
			(net "P1V8_STBY")
		)
		(pad "2" smd rect
			(at 0 0.9652 180)
			(size 1.397 1.143)
			(layers "B.Cu" "B.Mask" "B.Paste")
			(net "GND")
		)
	)
	(footprint ""
		(layer "B.Cu")
		(at 22.014942 -129.1082 180)
		(property "Reference" "R260"
			(at 0 0 0)
			(layer "B.SilkS")
			(hide yes)
			(effects
				(font
					(size 1.27 1.27)
				)
				(justify mirror)
			)
		)
		(property "Value" "120R2F-GP"
			(at -0.064008 -3.993896 180)
			(unlocked yes)
			(layer "B.Fab")
			(hide yes)
			(effects
				(font
					(size 1.016 1.016)
					(thickness 0.1524)
				)
				(justify mirror)
			)
		)
		(property "Device Type" "R402H16"
			(at -0.064008 -5.517896 180)
			(unlocked yes)
			(layer "B.Fab")
			(hide yes)
			(effects
				(font
					(size 1.016 1.016)
					(thickness 0.1524)
				)
				(justify mirror)
			)
		)
		(duplicate_pad_numbers_are_jumpers no)
		(fp_line
			(start 0.508 -0.9398)
			(end 0.508 0.9398)
			(stroke
				(width 0.1524)
				(type default)
			)
			(layer "B.SilkS")
		)
		(fp_line
			(start -0.508 -0.9398)
			(end 0.508 -0.9398)
			(stroke
				(width 0.1524)
				(type default)
			)
			(layer "B.SilkS")
		)
		(fp_rect
			(start 0.508 0.9398)
			(end -0.508 -0.9398)
			(stroke
				(width 0)
				(type default)
			)
			(fill no)
			(layer "B.CrtYd")
		)
		(fp_rect
			(start 0.508 0.9398)
			(end -0.508 -0.9398)
			(stroke
				(width 0)
				(type default)
			)
			(fill no)
			(layer "B.Fab")
		)
		(pad "1" smd custom
			(at 0 -0.4445)
			(size 0.1397 0.1397)
			(layers "B.Cu" "B.Mask" "B.Paste")
			(net "GND")
			(options
				(clearance outline)
				(anchor circle)
			)
			(primitives
				(gr_poly
					(pts
						(arc
							(start -0.1778 0.2794)
							(mid -0.249642 0.249642)
							(end -0.2794 0.1778)
						)
						(arc
							(start -0.2794 -0.1778)
							(mid -0.249642 -0.249642)
							(end -0.1778 -0.2794)
						)
						(arc
							(start 0.1778 -0.2794)
							(mid 0.249642 -0.249642)
							(end 0.2794 -0.1778)
						)
						(arc
							(start 0.2794 0.1778)
							(mid 0.249642 0.249642)
							(end 0.1778 0.2794)
						)
					)
					(width 0)
					(fill yes)
				)
			)
		)
		(pad "2" smd custom
			(at 0 0.4445)
			(size 0.1397 0.1397)
			(layers "B.Cu" "B.Mask" "B.Paste")
			(net "MEMA_13")
			(options
				(clearance outline)
				(anchor circle)
			)
			(primitives
				(gr_poly
					(pts
						(arc
							(start -0.1778 0.2794)
							(mid -0.249642 0.249642)
							(end -0.2794 0.1778)
						)
						(arc
							(start -0.2794 -0.1778)
							(mid -0.249642 -0.249642)
							(end -0.1778 -0.2794)
						)
						(arc
							(start 0.1778 -0.2794)
							(mid 0.249642 -0.249642)
							(end 0.2794 -0.1778)
						)
						(arc
							(start 0.2794 0.1778)
							(mid 0.249642 0.249642)
							(end 0.1778 0.2794)
						)
					)
					(width 0)
					(fill yes)
				)
			)
		)
	)
	(footprint ""
		(layer "B.Cu")
		(at 10.20191 -135.290052 90)
		(property "Reference" "R256"
			(at 0 0 90)
			(layer "B.SilkS")
			(hide yes)
			(effects
				(font
					(size 1.27 1.27)
				)
				(justify mirror)
			)
		)
		(property "Value" "120R2F-GP"
			(at -0.064008 -3.993896 90)
			(unlocked yes)
			(layer "B.Fab")
			(hide yes)
			(effects
				(font
					(size 1.016 1.016)
					(thickness 0.1524)
				)
				(justify mirror)
			)
		)
		(property "Device Type" "R402H16"
			(at -0.064008 -5.517896 90)
			(unlocked yes)
			(layer "B.Fab")
			(hide yes)
			(effects
				(font
					(size 1.016 1.016)
					(thickness 0.1524)
				)
				(justify mirror)
			)
		)
		(duplicate_pad_numbers_are_jumpers no)
		(fp_line
			(start 0.508 -0.9398)
			(end 0.508 0.9398)
			(stroke
				(width 0.1524)
				(type default)
			)
			(layer "B.SilkS")
		)
		(fp_line
			(start -0.508 -0.9398)
			(end 0.508 -0.9398)
			(stroke
				(width 0.1524)
				(type default)
			)
			(layer "B.SilkS")
		)
		(fp_rect
			(start 0.508 0.9398)
			(end -0.508 -0.9398)
			(stroke
				(width 0)
				(type default)
			)
			(fill no)
			(layer "B.CrtYd")
		)
		(fp_rect
			(start 0.508 0.9398)
			(end -0.508 -0.9398)
			(stroke
				(width 0)
				(type default)
			)
			(fill no)
			(layer "B.Fab")
		)
		(pad "1" smd custom
			(at 0 -0.4445 270)
			(size 0.1397 0.1397)
			(layers "B.Cu" "B.Mask" "B.Paste")
			(net "GND")
			(options
				(clearance outline)
				(anchor circle)
			)
			(primitives
				(gr_poly
					(pts
						(arc
							(start -0.1778 0.2794)
							(mid -0.249642 0.249642)
							(end -0.2794 0.1778)
						)
						(arc
							(start -0.2794 -0.1778)
							(mid -0.249642 -0.249642)
							(end -0.1778 -0.2794)
						)
						(arc
							(start 0.1778 -0.2794)
							(mid 0.249642 -0.249642)
							(end 0.2794 -0.1778)
						)
						(arc
							(start 0.2794 0.1778)
							(mid 0.249642 0.249642)
							(end 0.1778 0.2794)
						)
					)
					(width 0)
					(fill yes)
				)
			)
		)
		(pad "2" smd custom
			(at 0 0.4445 270)
			(size 0.1397 0.1397)
			(layers "B.Cu" "B.Mask" "B.Paste")
			(net "MEMA_11")
			(options
				(clearance outline)
				(anchor circle)
			)
			(primitives
				(gr_poly
					(pts
						(arc
							(start -0.1778 0.2794)
							(mid -0.249642 0.249642)
							(end -0.2794 0.1778)
						)
						(arc
							(start -0.2794 -0.1778)
							(mid -0.249642 -0.249642)
							(end -0.1778 -0.2794)
						)
						(arc
							(start 0.1778 -0.2794)
							(mid 0.249642 -0.249642)
							(end 0.2794 -0.1778)
						)
						(arc
							(start 0.2794 0.1778)
							(mid 0.249642 0.249642)
							(end 0.1778 0.2794)
						)
					)
					(width 0)
					(fill yes)
				)
			)
		)
	)
	(footprint ""
		(layer "B.Cu")
		(at 55.0164 -127.24892)
		(property "Reference" "U37"
			(at 0 0 0)
			(layer "B.SilkS")
			(hide yes)
			(effects
				(font
					(size 1.27 1.27)
				)
				(justify mirror)
			)
		)
		(property "Value" "SN74LVC1G08DCKR-GP"
			(at 2.3368 -8.6868 0)
			(unlocked yes)
			(layer "B.Fab")
			(hide yes)
			(effects
				(font
					(size 1.016 1.016)
					(thickness 0.1524)
				)
				(justify mirror)
			)
		)
		(property "Device Type" "SC70-5H44"
			(at 2.3114 -10.414 0)
			(unlocked yes)
			(layer "B.Fab")
			(hide yes)
			(effects
				(font
					(size 1.016 1.016)
					(thickness 0.1524)
				)
				(justify mirror)
			)
		)
		(duplicate_pad_numbers_are_jumpers no)
		(fp_line
			(start -1.3843 -1.8034)
			(end -1.3843 -1.1176)
			(stroke
				(width 0.3302)
				(type default)
			)
			(layer "B.SilkS")
		)
		(fp_line
			(start -1.27 -1.7018)
			(end -1.27 1.7018)
			(stroke
				(width 0.1524)
				(type default)
			)
			(layer "B.SilkS")
		)
		(fp_line
			(start -1.27 1.7018)
			(end 1.27 1.7018)
			(stroke
				(width 0.1524)
				(type default)
			)
			(layer "B.SilkS")
		)
		(fp_line
			(start -0.6604 -1.8034)
			(end -1.3843 -1.8034)
			(stroke
				(width 0.3302)
				(type default)
			)
			(layer "B.SilkS")
		)
		(fp_line
			(start 1.27 -1.7018)
			(end -1.27 -1.7018)
			(stroke
				(width 0.1524)
				(type default)
			)
			(layer "B.SilkS")
		)
		(fp_line
			(start 1.27 1.7018)
			(end 1.27 -1.7018)
			(stroke
				(width 0.1524)
				(type default)
			)
			(layer "B.SilkS")
		)
		(fp_rect
			(start 1.524 1.9558)
			(end -1.524 -1.9558)
			(stroke
				(width 0)
				(type default)
			)
			(fill no)
			(layer "B.CrtYd")
		)
		(fp_poly
			(pts
				(xy 1.524 -1.9558) (xy -1.524 -1.9558) (xy -1.524 1.9558) (xy 1.524 1.9558)
			)
			(stroke
				(width 0)
				(type default)
			)
			(fill no)
			(layer "B.Fab")
		)
		(pad "1" smd rect
			(at -0.65024 -0.8255 180)
			(size 0.4064 1.2192)
			(layers "B.Cu" "B.Mask" "B.Paste")
			(net "RST_BMC_EXTRST_N_1")
		)
		(pad "2" smd rect
			(at 0 -0.8255 180)
			(size 0.4064 1.2192)
			(layers "B.Cu" "B.Mask" "B.Paste")
			(net "DEBUG_RST_BTN_N_R")
		)
		(pad "3" smd rect
			(at 0.65024 -0.8255 180)
			(size 0.4064 1.2192)
			(layers "B.Cu" "B.Mask" "B.Paste")
			(net "GND")
		)
		(pad "4" smd rect
			(at 0.65024 0.8255 180)
			(size 0.4064 1.2192)
			(layers "B.Cu" "B.Mask" "B.Paste")
			(net "RST_BMC_EXTRST_N")
		)
		(pad "5" smd rect
			(at -0.65024 0.8255 180)
			(size 0.4064 1.2192)
			(layers "B.Cu" "B.Mask" "B.Paste")
			(net "P3V3_STBY")
		)
	)
	(footprint ""
		(layer "B.Cu")
		(at 78.109318 -173.471586 -90)
		(property "Reference" "R301"
			(at 0 0 90)
			(layer "B.SilkS")
			(hide yes)
			(effects
				(font
					(size 1.27 1.27)
				)
				(justify mirror)
			)
		)
		(property "Value" "0R2J-2-GP"
			(at -0.064008 -3.993896 270)
			(unlocked yes)
			(layer "B.Fab")
			(hide yes)
			(effects
				(font
					(size 1.016 1.016)
					(thickness 0.1524)
				)
				(justify mirror)
			)
		)
		(property "Device Type" "R402H16"
			(at -0.064008 -5.517896 270)
			(unlocked yes)
			(layer "B.Fab")
			(hide yes)
			(effects
				(font
					(size 1.016 1.016)
					(thickness 0.1524)
				)
				(justify mirror)
			)
		)
		(duplicate_pad_numbers_are_jumpers no)
		(fp_line
			(start -0.508 -0.9398)
			(end 0.508 -0.9398)
			(stroke
				(width 0.1524)
				(type default)
			)
			(layer "B.SilkS")
		)
		(fp_line
			(start 0.508 -0.9398)
			(end 0.508 0.9398)
			(stroke
				(width 0.1524)
				(type default)
			)
			(layer "B.SilkS")
		)
		(fp_rect
			(start 0.508 0.9398)
			(end -0.508 -0.9398)
			(stroke
				(width 0)
				(type default)
			)
			(fill no)
			(layer "B.CrtYd")
		)
		(fp_rect
			(start 0.508 0.9398)
			(end -0.508 -0.9398)
			(stroke
				(width 0)
				(type default)
			)
			(fill no)
			(layer "B.Fab")
		)
		(pad "1" smd custom
			(at 0 -0.4445 90)
			(size 0.1397 0.1397)
			(layers "B.Cu" "B.Mask" "B.Paste")
			(net "UART_EXP_BMC_RX")
			(options
				(clearance outline)
				(anchor circle)
			)
			(primitives
				(gr_poly
					(pts
						(arc
							(start -0.1778 0.2794)
							(mid -0.249642 0.249642)
							(end -0.2794 0.1778)
						)
						(arc
							(start -0.2794 -0.1778)
							(mid -0.249642 -0.249642)
							(end -0.1778 -0.2794)
						)
						(arc
							(start 0.1778 -0.2794)
							(mid 0.249642 -0.249642)
							(end 0.2794 -0.1778)
						)
						(arc
							(start 0.2794 0.1778)
							(mid 0.249642 0.249642)
							(end 0.1778 0.2794)
						)
					)
					(width 0)
					(fill yes)
				)
			)
		)
		(pad "2" smd custom
			(at 0 0.4445 90)
			(size 0.1397 0.1397)
			(layers "B.Cu" "B.Mask" "B.Paste")
			(net "UART_EXP_BMC_RX_R")
			(options
				(clearance outline)
				(anchor circle)
			)
			(primitives
				(gr_poly
					(pts
						(arc
							(start -0.1778 0.2794)
							(mid -0.249642 0.249642)
							(end -0.2794 0.1778)
						)
						(arc
							(start -0.2794 -0.1778)
							(mid -0.249642 -0.249642)
							(end -0.1778 -0.2794)
						)
						(arc
							(start 0.1778 -0.2794)
							(mid 0.249642 -0.249642)
							(end 0.2794 -0.1778)
						)
						(arc
							(start 0.2794 0.1778)
							(mid 0.249642 0.249642)
							(end 0.1778 0.2794)
						)
					)
					(width 0)
					(fill yes)
				)
			)
		)
	)
	(footprint ""
		(layer "B.Cu")
		(at 93.37548 -152.746456 180)
		(property "Reference" "C9"
			(at 0 0 0)
			(layer "B.SilkS")
			(hide yes)
			(effects
				(font
					(size 1.27 1.27)
				)
				(justify mirror)
			)
		)
		(property "Value" "SC1U16V2KX-7-GP"
			(at -1.7526 -1.6002 180)
			(unlocked yes)
			(layer "B.Fab")
			(hide yes)
			(effects
				(font
					(size 1.016 1.016)
					(thickness 0.1524)
				)
				(justify mirror)
			)
		)
		(property "Device Type" "C402-TO0D2H24"
			(at -1.7526 -3.1242 180)
			(unlocked yes)
			(layer "B.Fab")
			(hide yes)
			(effects
				(font
					(size 1.016 1.016)
					(thickness 0.1524)
				)
				(justify mirror)
			)
		)
		(duplicate_pad_numbers_are_jumpers no)
		(fp_rect
			(start 0.4826 0.889)
			(end -0.4826 -0.889)
			(stroke
				(width 0)
				(type default)
			)
			(fill no)
			(layer "B.CrtYd")
		)
		(fp_rect
			(start 0.4826 0.889)
			(end -0.4826 -0.889)
			(stroke
				(width 0)
				(type default)
			)
			(fill no)
			(layer "B.Fab")
		)
		(pad "1" smd custom
			(at 0 -0.4572)
			(size 0.1524 0.1524)
			(layers "B.Cu" "B.Mask" "B.Paste")
			(net "P3V3_STBY")
			(options
				(clearance outline)
				(anchor circle)
			)
			(primitives
				(gr_poly
					(pts
						(arc
							(start -0.254 -0.3048)
							(mid -0.325842 -0.275042)
							(end -0.3556 -0.2032)
						)
						(arc
							(start -0.3556 0.2032)
							(mid -0.325842 0.275042)
							(end -0.254 0.3048)
						)
						(arc
							(start 0.254 0.3048)
							(mid 0.325842 0.275042)
							(end 0.3556 0.2032)
						)
						(arc
							(start 0.3556 -0.2032)
							(mid 0.325842 -0.275042)
							(end 0.254 -0.3048)
						)
					)
					(width 0)
					(fill yes)
				)
			)
		)
		(pad "2" smd custom
			(at 0 0.4572)
			(size 0.1524 0.1524)
			(layers "B.Cu" "B.Mask" "B.Paste")
			(net "GND")
			(options
				(clearance outline)
				(anchor circle)
			)
			(primitives
				(gr_poly
					(pts
						(arc
							(start -0.254 -0.3048)
							(mid -0.325842 -0.275042)
							(end -0.3556 -0.2032)
						)
						(arc
							(start -0.3556 0.2032)
							(mid -0.325842 0.275042)
							(end -0.254 0.3048)
						)
						(arc
							(start 0.254 0.3048)
							(mid 0.325842 0.275042)
							(end 0.3556 0.2032)
						)
						(arc
							(start 0.3556 -0.2032)
							(mid 0.325842 -0.275042)
							(end 0.254 -0.3048)
						)
					)
					(width 0)
					(fill yes)
				)
			)
		)
	)
	(footprint ""
		(layer "B.Cu")
		(at 65.2526 -136.0932 -90)
		(property "Reference" "R785"
			(at 0 0 90)
			(layer "B.SilkS")
			(hide yes)
			(effects
				(font
					(size 1.27 1.27)
				)
				(justify mirror)
			)
		)
		(property "Value" "10KR2F-2-GP"
			(at -0.064008 -3.993896 270)
			(unlocked yes)
			(layer "B.Fab")
			(hide yes)
			(effects
				(font
					(size 1.016 1.016)
					(thickness 0.1524)
				)
				(justify mirror)
			)
		)
		(property "Device Type" "R402H16"
			(at -0.064008 -5.517896 270)
			(unlocked yes)
			(layer "B.Fab")
			(hide yes)
			(effects
				(font
					(size 1.016 1.016)
					(thickness 0.1524)
				)
				(justify mirror)
			)
		)
		(duplicate_pad_numbers_are_jumpers no)
		(fp_line
			(start -0.508 -0.9398)
			(end 0.508 -0.9398)
			(stroke
				(width 0.1524)
				(type default)
			)
			(layer "B.SilkS")
		)
		(fp_line
			(start 0.508 -0.9398)
			(end 0.508 0.9398)
			(stroke
				(width 0.1524)
				(type default)
			)
			(layer "B.SilkS")
		)
		(fp_rect
			(start 0.508 0.9398)
			(end -0.508 -0.9398)
			(stroke
				(width 0)
				(type default)
			)
			(fill no)
			(layer "B.CrtYd")
		)
		(fp_rect
			(start 0.508 0.9398)
			(end -0.508 -0.9398)
			(stroke
				(width 0)
				(type default)
			)
			(fill no)
			(layer "B.Fab")
		)
		(pad "1" smd custom
			(at 0 -0.4445 90)
			(size 0.1397 0.1397)
			(layers "B.Cu" "B.Mask" "B.Paste")
			(net "P3V3_STBY")
			(options
				(clearance outline)
				(anchor circle)
			)
			(primitives
				(gr_poly
					(pts
						(arc
							(start -0.1778 0.2794)
							(mid -0.249642 0.249642)
							(end -0.2794 0.1778)
						)
						(arc
							(start -0.2794 -0.1778)
							(mid -0.249642 -0.249642)
							(end -0.1778 -0.2794)
						)
						(arc
							(start 0.1778 -0.2794)
							(mid 0.249642 -0.249642)
							(end 0.2794 -0.1778)
						)
						(arc
							(start 0.2794 0.1778)
							(mid 0.249642 0.249642)
							(end 0.1778 0.2794)
						)
					)
					(width 0)
					(fill yes)
				)
			)
		)
		(pad "2" smd custom
			(at 0 0.4445 90)
			(size 0.1397 0.1397)
			(layers "B.Cu" "B.Mask" "B.Paste")
			(net "TP_BMC_GPIOA0")
			(options
				(clearance outline)
				(anchor circle)
			)
			(primitives
				(gr_poly
					(pts
						(arc
							(start -0.1778 0.2794)
							(mid -0.249642 0.249642)
							(end -0.2794 0.1778)
						)
						(arc
							(start -0.2794 -0.1778)
							(mid -0.249642 -0.249642)
							(end -0.1778 -0.2794)
						)
						(arc
							(start 0.1778 -0.2794)
							(mid 0.249642 -0.249642)
							(end 0.2794 -0.1778)
						)
						(arc
							(start 0.2794 0.1778)
							(mid 0.249642 0.249642)
							(end 0.1778 0.2794)
						)
					)
					(width 0)
					(fill yes)
				)
			)
		)
	)
	(footprint ""
		(layer "B.Cu")
		(at 43.3832 -128.2192)
		(property "Reference" "R270"
			(at 0 0 0)
			(layer "B.SilkS")
			(hide yes)
			(effects
				(font
					(size 1.27 1.27)
				)
				(justify mirror)
			)
		)
		(property "Value" "33R2F-3-GP"
			(at -0.064008 -3.993896 0)
			(unlocked yes)
			(layer "B.Fab")
			(hide yes)
			(effects
				(font
					(size 1.016 1.016)
					(thickness 0.1524)
				)
				(justify mirror)
			)
		)
		(property "Device Type" "R402H16"
			(at -0.064008 -5.517896 0)
			(unlocked yes)
			(layer "B.Fab")
			(hide yes)
			(effects
				(font
					(size 1.016 1.016)
					(thickness 0.1524)
				)
				(justify mirror)
			)
		)
		(duplicate_pad_numbers_are_jumpers no)
		(fp_line
			(start -0.508 -0.9398)
			(end 0.508 -0.9398)
			(stroke
				(width 0.1524)
				(type default)
			)
			(layer "B.SilkS")
		)
		(fp_line
			(start 0.508 -0.9398)
			(end 0.508 0.9398)
			(stroke
				(width 0.1524)
				(type default)
			)
			(layer "B.SilkS")
		)
		(fp_rect
			(start 0.508 0.9398)
			(end -0.508 -0.9398)
			(stroke
				(width 0)
				(type default)
			)
			(fill no)
			(layer "B.CrtYd")
		)
		(fp_rect
			(start 0.508 0.9398)
			(end -0.508 -0.9398)
			(stroke
				(width 0)
				(type default)
			)
			(fill no)
			(layer "B.Fab")
		)
		(pad "1" smd custom
			(at 0 -0.4445 180)
			(size 0.1397 0.1397)
			(layers "B.Cu" "B.Mask" "B.Paste")
			(net "BMC_SPI_MISO")
			(options
				(clearance outline)
				(anchor circle)
			)
			(primitives
				(gr_poly
					(pts
						(arc
							(start -0.1778 0.2794)
							(mid -0.249642 0.249642)
							(end -0.2794 0.1778)
						)
						(arc
							(start -0.2794 -0.1778)
							(mid -0.249642 -0.249642)
							(end -0.1778 -0.2794)
						)
						(arc
							(start 0.1778 -0.2794)
							(mid 0.249642 -0.249642)
							(end 0.2794 -0.1778)
						)
						(arc
							(start 0.2794 0.1778)
							(mid 0.249642 0.249642)
							(end 0.1778 0.2794)
						)
					)
					(width 0)
					(fill yes)
				)
			)
		)
		(pad "2" smd custom
			(at 0 0.4445 180)
			(size 0.1397 0.1397)
			(layers "B.Cu" "B.Mask" "B.Paste")
			(net "BMC_SPI_MISO_R")
			(options
				(clearance outline)
				(anchor circle)
			)
			(primitives
				(gr_poly
					(pts
						(arc
							(start -0.1778 0.2794)
							(mid -0.249642 0.249642)
							(end -0.2794 0.1778)
						)
						(arc
							(start -0.2794 -0.1778)
							(mid -0.249642 -0.249642)
							(end -0.1778 -0.2794)
						)
						(arc
							(start 0.1778 -0.2794)
							(mid 0.249642 -0.249642)
							(end 0.2794 -0.1778)
						)
						(arc
							(start 0.2794 0.1778)
							(mid 0.249642 0.249642)
							(end 0.1778 0.2794)
						)
					)
					(width 0)
					(fill yes)
				)
			)
		)
	)
	(footprint ""
		(layer "B.Cu")
		(at 73.224644 -148.73097)
		(property "Reference" "R50"
			(at 0 0 0)
			(layer "B.SilkS")
			(hide yes)
			(effects
				(font
					(size 1.27 1.27)
				)
				(justify mirror)
			)
		)
		(property "Value" "4K7R2F-GP"
			(at -0.064008 -3.993896 0)
			(unlocked yes)
			(layer "B.Fab")
			(hide yes)
			(effects
				(font
					(size 1.016 1.016)
					(thickness 0.1524)
				)
				(justify mirror)
			)
		)
		(property "Device Type" "R402H16"
			(at -0.064008 -5.517896 0)
			(unlocked yes)
			(layer "B.Fab")
			(hide yes)
			(effects
				(font
					(size 1.016 1.016)
					(thickness 0.1524)
				)
				(justify mirror)
			)
		)
		(duplicate_pad_numbers_are_jumpers no)
		(fp_line
			(start -0.508 -0.9398)
			(end 0.508 -0.9398)
			(stroke
				(width 0.1524)
				(type default)
			)
			(layer "B.SilkS")
		)
		(fp_line
			(start 0.508 -0.9398)
			(end 0.508 0.9398)
			(stroke
				(width 0.1524)
				(type default)
			)
			(layer "B.SilkS")
		)
		(fp_rect
			(start 0.508 0.9398)
			(end -0.508 -0.9398)
			(stroke
				(width 0)
				(type default)
			)
			(fill no)
			(layer "B.CrtYd")
		)
		(fp_rect
			(start 0.508 0.9398)
			(end -0.508 -0.9398)
			(stroke
				(width 0)
				(type default)
			)
			(fill no)
			(layer "B.Fab")
		)
		(pad "1" smd custom
			(at 0 -0.4445 180)
			(size 0.1397 0.1397)
			(layers "B.Cu" "B.Mask" "B.Paste")
			(net "P3V3_STBY")
			(options
				(clearance outline)
				(anchor circle)
			)
			(primitives
				(gr_poly
					(pts
						(arc
							(start -0.1778 0.2794)
							(mid -0.249642 0.249642)
							(end -0.2794 0.1778)
						)
						(arc
							(start -0.2794 -0.1778)
							(mid -0.249642 -0.249642)
							(end -0.1778 -0.2794)
						)
						(arc
							(start 0.1778 -0.2794)
							(mid 0.249642 -0.249642)
							(end 0.2794 -0.1778)
						)
						(arc
							(start 0.2794 0.1778)
							(mid 0.249642 0.249642)
							(end 0.1778 0.2794)
						)
					)
					(width 0)
					(fill yes)
				)
			)
		)
		(pad "2" smd custom
			(at 0 0.4445 180)
			(size 0.1397 0.1397)
			(layers "B.Cu" "B.Mask" "B.Paste")
			(net "I2C_DEBUG_SDA")
			(options
				(clearance outline)
				(anchor circle)
			)
			(primitives
				(gr_poly
					(pts
						(arc
							(start -0.1778 0.2794)
							(mid -0.249642 0.249642)
							(end -0.2794 0.1778)
						)
						(arc
							(start -0.2794 -0.1778)
							(mid -0.249642 -0.249642)
							(end -0.1778 -0.2794)
						)
						(arc
							(start 0.1778 -0.2794)
							(mid 0.249642 -0.249642)
							(end 0.2794 -0.1778)
						)
						(arc
							(start 0.2794 0.1778)
							(mid 0.249642 0.249642)
							(end 0.1778 0.2794)
						)
					)
					(width 0)
					(fill yes)
				)
			)
		)
	)
	(footprint ""
		(layer "B.Cu")
		(at 91.94292 -135.2296 -90)
		(property "Reference" "U101"
			(at 0 0 90)
			(layer "B.SilkS")
			(hide yes)
			(effects
				(font
					(size 1.27 1.27)
				)
				(justify mirror)
			)
		)
		(property "Value" "SNLVC1G126DCKR-GP"
			(at 2.3368 -8.6868 270)
			(unlocked yes)
			(layer "B.Fab")
			(hide yes)
			(effects
				(font
					(size 1.016 1.016)
					(thickness 0.1524)
				)
				(justify mirror)
			)
		)
		(property "Device Type" "SC70-5H44"
			(at 2.3114 -10.414 270)
			(unlocked yes)
			(layer "B.Fab")
			(hide yes)
			(effects
				(font
					(size 1.016 1.016)
					(thickness 0.1524)
				)
				(justify mirror)
			)
		)
		(duplicate_pad_numbers_are_jumpers no)
		(fp_line
			(start -1.27 1.7018)
			(end 1.27 1.7018)
			(stroke
				(width 0.1524)
				(type default)
			)
			(layer "B.SilkS")
		)
		(fp_line
			(start 1.27 1.7018)
			(end 1.27 -1.7018)
			(stroke
				(width 0.1524)
				(type default)
			)
			(layer "B.SilkS")
		)
		(fp_line
			(start -1.27 -1.7018)
			(end -1.27 1.7018)
			(stroke
				(width 0.1524)
				(type default)
			)
			(layer "B.SilkS")
		)
		(fp_line
			(start 1.27 -1.7018)
			(end -1.27 -1.7018)
			(stroke
				(width 0.1524)
				(type default)
			)
			(layer "B.SilkS")
		)
		(fp_line
			(start -1.3843 -1.8034)
			(end -1.3843 -1.1176)
			(stroke
				(width 0.3302)
				(type default)
			)
			(layer "B.SilkS")
		)
		(fp_line
			(start -0.6604 -1.8034)
			(end -1.3843 -1.8034)
			(stroke
				(width 0.3302)
				(type default)
			)
			(layer "B.SilkS")
		)
		(fp_rect
			(start 1.524 1.9558)
			(end -1.524 -1.9558)
			(stroke
				(width 0)
				(type default)
			)
			(fill no)
			(layer "B.CrtYd")
		)
		(fp_poly
			(pts
				(xy 1.524 -1.9558) (xy -1.524 -1.9558) (xy -1.524 1.9558) (xy 1.524 1.9558)
			)
			(stroke
				(width 0)
				(type default)
			)
			(fill no)
			(layer "B.Fab")
		)
		(pad "1" smd rect
			(at -0.65024 -0.8255 90)
			(size 0.4064 1.2192)
			(layers "B.Cu" "B.Mask" "B.Paste")
			(net "DEBUG_CARD_PRSNT")
		)
		(pad "2" smd rect
			(at 0 -0.8255 90)
			(size 0.4064 1.2192)
			(layers "B.Cu" "B.Mask" "B.Paste")
			(net "UART_IOM_RX")
		)
		(pad "3" smd rect
			(at 0.65024 -0.8255 90)
			(size 0.4064 1.2192)
			(layers "B.Cu" "B.Mask" "B.Paste")
			(net "GND")
		)
		(pad "4" smd rect
			(at 0.65024 0.8255 90)
			(size 0.4064 1.2192)
			(layers "B.Cu" "B.Mask" "B.Paste")
			(net "DEBUG_UART_IOM_RX")
		)
		(pad "5" smd rect
			(at -0.65024 0.8255 90)
			(size 0.4064 1.2192)
			(layers "B.Cu" "B.Mask" "B.Paste")
			(net "P3V3_STBY")
		)
	)
	(footprint ""
		(layer "B.Cu")
		(at 50.105056 -151.599646)
		(property "Reference" "TP209"
			(at 0 0 0)
			(layer "B.SilkS")
			(hide yes)
			(effects
				(font
					(size 1.27 1.27)
				)
				(justify mirror)
			)
		)
		(property "Value" "TPAD28-2-GP"
			(at 0.0127 -1.6637 0)
			(unlocked yes)
			(layer "B.Fab")
			(hide yes)
			(effects
				(font
					(size 1.016 1.016)
					(thickness 0.1524)
				)
				(justify mirror)
			)
		)
		(property "Device Type" "TPAD28"
			(at 0.0127 -3.1877 0)
			(unlocked yes)
			(layer "B.Fab")
			(hide yes)
			(effects
				(font
					(size 1.016 1.016)
					(thickness 0.1524)
				)
				(justify mirror)
			)
		)
		(duplicate_pad_numbers_are_jumpers no)
		(fp_poly
			(pts
				(arc
					(start 0.3556 0)
					(mid -0.3556 0)
					(end 0.3556 0)
				)
			)
			(stroke
				(width 0)
				(type default)
			)
			(fill no)
			(layer "B.CrtYd")
		)
		(fp_poly
			(pts
				(arc
					(start 0.6096 0)
					(mid -0.6096 0)
					(end 0.6096 0)
				)
			)
			(stroke
				(width 0)
				(type default)
			)
			(fill no)
			(layer "B.Fab")
		)
		(pad "1" smd circle
			(at 0 0 180)
			(size 0.7112 0.7112)
			(layers "B.Cu" "B.Mask" "B.Paste")
			(net "ADC_P1V5")
		)
	)
	(footprint ""
		(layer "B.Cu")
		(at 44.802044 -130.345434 90)
		(property "Reference" "R293"
			(at 0 0 90)
			(layer "B.SilkS")
			(hide yes)
			(effects
				(font
					(size 1.27 1.27)
				)
				(justify mirror)
			)
		)
		(property "Value" "0R2J-2-GP"
			(at -0.064008 -3.993896 90)
			(unlocked yes)
			(layer "B.Fab")
			(hide yes)
			(effects
				(font
					(size 1.016 1.016)
					(thickness 0.1524)
				)
				(justify mirror)
			)
		)
		(property "Device Type" "R402H16"
			(at -0.064008 -5.517896 90)
			(unlocked yes)
			(layer "B.Fab")
			(hide yes)
			(effects
				(font
					(size 1.016 1.016)
					(thickness 0.1524)
				)
				(justify mirror)
			)
		)
		(duplicate_pad_numbers_are_jumpers no)
		(fp_line
			(start 0.508 -0.9398)
			(end 0.508 0.9398)
			(stroke
				(width 0.1524)
				(type default)
			)
			(layer "B.SilkS")
		)
		(fp_line
			(start -0.508 -0.9398)
			(end 0.508 -0.9398)
			(stroke
				(width 0.1524)
				(type default)
			)
			(layer "B.SilkS")
		)
		(fp_rect
			(start 0.508 0.9398)
			(end -0.508 -0.9398)
			(stroke
				(width 0)
				(type default)
			)
			(fill no)
			(layer "B.CrtYd")
		)
		(fp_rect
			(start 0.508 0.9398)
			(end -0.508 -0.9398)
			(stroke
				(width 0)
				(type default)
			)
			(fill no)
			(layer "B.Fab")
		)
		(pad "1" smd custom
			(at 0 -0.4445 270)
			(size 0.1397 0.1397)
			(layers "B.Cu" "B.Mask" "B.Paste")
			(net "IOM_FULL_PWR_EN")
			(options
				(clearance outline)
				(anchor circle)
			)
			(primitives
				(gr_poly
					(pts
						(arc
							(start -0.1778 0.2794)
							(mid -0.249642 0.249642)
							(end -0.2794 0.1778)
						)
						(arc
							(start -0.2794 -0.1778)
							(mid -0.249642 -0.249642)
							(end -0.1778 -0.2794)
						)
						(arc
							(start 0.1778 -0.2794)
							(mid 0.249642 -0.249642)
							(end 0.2794 -0.1778)
						)
						(arc
							(start 0.2794 0.1778)
							(mid 0.249642 0.249642)
							(end 0.1778 0.2794)
						)
					)
					(width 0)
					(fill yes)
				)
			)
		)
		(pad "2" smd custom
			(at 0 0.4445 270)
			(size 0.1397 0.1397)
			(layers "B.Cu" "B.Mask" "B.Paste")
			(net "IOM_FULL_PWR_EN_R")
			(options
				(clearance outline)
				(anchor circle)
			)
			(primitives
				(gr_poly
					(pts
						(arc
							(start -0.1778 0.2794)
							(mid -0.249642 0.249642)
							(end -0.2794 0.1778)
						)
						(arc
							(start -0.2794 -0.1778)
							(mid -0.249642 -0.249642)
							(end -0.1778 -0.2794)
						)
						(arc
							(start 0.1778 -0.2794)
							(mid 0.249642 -0.249642)
							(end 0.2794 -0.1778)
						)
						(arc
							(start 0.2794 0.1778)
							(mid 0.249642 0.249642)
							(end 0.1778 0.2794)
						)
					)
					(width 0)
					(fill yes)
				)
			)
		)
	)
	(footprint ""
		(layer "B.Cu")
		(at 212.805264 -87.912956)
		(property "Reference" "R807"
			(at 0 0 0)
			(layer "B.SilkS")
			(hide yes)
			(effects
				(font
					(size 1.27 1.27)
				)
				(justify mirror)
			)
		)
		(property "Value" "4K7R2F-GP"
			(at -0.064008 -3.993896 0)
			(unlocked yes)
			(layer "B.Fab")
			(hide yes)
			(effects
				(font
					(size 1.016 1.016)
					(thickness 0.1524)
				)
				(justify mirror)
			)
		)
		(property "Device Type" "R402H16"
			(at -0.064008 -5.517896 0)
			(unlocked yes)
			(layer "B.Fab")
			(hide yes)
			(effects
				(font
					(size 1.016 1.016)
					(thickness 0.1524)
				)
				(justify mirror)
			)
		)
		(duplicate_pad_numbers_are_jumpers no)
		(fp_line
			(start -0.508 -0.9398)
			(end 0.508 -0.9398)
			(stroke
				(width 0.1524)
				(type default)
			)
			(layer "B.SilkS")
		)
		(fp_line
			(start 0.508 -0.9398)
			(end 0.508 0.9398)
			(stroke
				(width 0.1524)
				(type default)
			)
			(layer "B.SilkS")
		)
		(fp_rect
			(start 0.508 0.9398)
			(end -0.508 -0.9398)
			(stroke
				(width 0)
				(type default)
			)
			(fill no)
			(layer "B.CrtYd")
		)
		(fp_rect
			(start 0.508 0.9398)
			(end -0.508 -0.9398)
			(stroke
				(width 0)
				(type default)
			)
			(fill no)
			(layer "B.Fab")
		)
		(pad "1" smd custom
			(at 0 -0.4445 180)
			(size 0.1397 0.1397)
			(layers "B.Cu" "B.Mask" "B.Paste")
			(net "P3V3_PG")
			(options
				(clearance outline)
				(anchor circle)
			)
			(primitives
				(gr_poly
					(pts
						(arc
							(start -0.1778 0.2794)
							(mid -0.249642 0.249642)
							(end -0.2794 0.1778)
						)
						(arc
							(start -0.2794 -0.1778)
							(mid -0.249642 -0.249642)
							(end -0.1778 -0.2794)
						)
						(arc
							(start 0.1778 -0.2794)
							(mid 0.249642 -0.249642)
							(end 0.2794 -0.1778)
						)
						(arc
							(start 0.2794 0.1778)
							(mid 0.249642 0.249642)
							(end 0.1778 0.2794)
						)
					)
					(width 0)
					(fill yes)
				)
			)
		)
		(pad "2" smd custom
			(at 0 0.4445 180)
			(size 0.1397 0.1397)
			(layers "B.Cu" "B.Mask" "B.Paste")
			(net "P3V3")
			(options
				(clearance outline)
				(anchor circle)
			)
			(primitives
				(gr_poly
					(pts
						(arc
							(start -0.1778 0.2794)
							(mid -0.249642 0.249642)
							(end -0.2794 0.1778)
						)
						(arc
							(start -0.2794 -0.1778)
							(mid -0.249642 -0.249642)
							(end -0.1778 -0.2794)
						)
						(arc
							(start 0.1778 -0.2794)
							(mid 0.249642 -0.249642)
							(end 0.2794 -0.1778)
						)
						(arc
							(start 0.2794 0.1778)
							(mid 0.249642 0.249642)
							(end 0.1778 0.2794)
						)
					)
					(width 0)
					(fill yes)
				)
			)
		)
	)
	(footprint ""
		(layer "B.Cu")
		(at 44.139866 -148.180298 -90)
		(property "Reference" "C55"
			(at 0 0 90)
			(layer "B.SilkS")
			(hide yes)
			(effects
				(font
					(size 1.27 1.27)
				)
				(justify mirror)
			)
		)
		(property "Value" "SCD1U16V2KX-3GP"
			(at -1.1811 -2.7051 270)
			(unlocked yes)
			(layer "B.Fab")
			(hide yes)
			(effects
				(font
					(size 1.016 1.016)
					(thickness 0.1524)
				)
				(justify mirror)
			)
		)
		(property "Device Type" "C402H22"
			(at -1.1811 -4.2291 270)
			(unlocked yes)
			(layer "B.Fab")
			(hide yes)
			(effects
				(font
					(size 1.016 1.016)
					(thickness 0.1524)
				)
				(justify mirror)
			)
		)
		(duplicate_pad_numbers_are_jumpers no)
		(fp_rect
			(start 0.4318 0.9525)
			(end -0.4318 -0.9525)
			(stroke
				(width 0)
				(type default)
			)
			(fill no)
			(layer "B.CrtYd")
		)
		(fp_rect
			(start 0.4318 0.9525)
			(end -0.4318 -0.9525)
			(stroke
				(width 0)
				(type default)
			)
			(fill no)
			(layer "B.Fab")
		)
		(pad "1" smd custom
			(at 0 -0.4445 90)
			(size 0.1524 0.1524)
			(layers "B.Cu" "B.Mask" "B.Paste")
			(net "GND")
			(options
				(clearance outline)
				(anchor circle)
			)
			(primitives
				(gr_poly
					(pts
						(arc
							(start 0.3048 0.2032)
							(mid 0.275042 0.275042)
							(end 0.2032 0.3048)
						)
						(arc
							(start -0.2032 0.3048)
							(mid -0.275042 0.275042)
							(end -0.3048 0.2032)
						)
						(arc
							(start -0.3048 -0.2032)
							(mid -0.275042 -0.275042)
							(end -0.2032 -0.3048)
						)
						(arc
							(start 0.2032 -0.3048)
							(mid 0.275042 -0.275042)
							(end 0.3048 -0.2032)
						)
					)
					(width 0)
					(fill yes)
				)
			)
		)
		(pad "2" smd custom
			(at 0 0.4445 90)
			(size 0.1524 0.1524)
			(layers "B.Cu" "B.Mask" "B.Paste")
			(net "DDR_VREF")
			(options
				(clearance outline)
				(anchor circle)
			)
			(primitives
				(gr_poly
					(pts
						(arc
							(start 0.3048 0.2032)
							(mid 0.275042 0.275042)
							(end 0.2032 0.3048)
						)
						(arc
							(start -0.2032 0.3048)
							(mid -0.275042 0.275042)
							(end -0.3048 0.2032)
						)
						(arc
							(start -0.3048 -0.2032)
							(mid -0.275042 -0.275042)
							(end -0.2032 -0.3048)
						)
						(arc
							(start 0.2032 -0.3048)
							(mid 0.275042 -0.275042)
							(end 0.3048 -0.2032)
						)
					)
					(width 0)
					(fill yes)
				)
			)
		)
	)
	(footprint ""
		(layer "B.Cu")
		(at 77.7494 -167.9702 90)
		(property "Reference" "R330"
			(at 0 0 90)
			(layer "B.SilkS")
			(hide yes)
			(effects
				(font
					(size 1.27 1.27)
				)
				(justify mirror)
			)
		)
		(property "Value" "4K7R2F-GP"
			(at -0.064008 -3.993896 90)
			(unlocked yes)
			(layer "B.Fab")
			(hide yes)
			(effects
				(font
					(size 1.016 1.016)
					(thickness 0.1524)
				)
				(justify mirror)
			)
		)
		(property "Device Type" "R402H16"
			(at -0.064008 -5.517896 90)
			(unlocked yes)
			(layer "B.Fab")
			(hide yes)
			(effects
				(font
					(size 1.016 1.016)
					(thickness 0.1524)
				)
				(justify mirror)
			)
		)
		(duplicate_pad_numbers_are_jumpers no)
		(fp_line
			(start 0.508 -0.9398)
			(end 0.508 0.9398)
			(stroke
				(width 0.1524)
				(type default)
			)
			(layer "B.SilkS")
		)
		(fp_line
			(start -0.508 -0.9398)
			(end 0.508 -0.9398)
			(stroke
				(width 0.1524)
				(type default)
			)
			(layer "B.SilkS")
		)
		(fp_rect
			(start 0.508 0.9398)
			(end -0.508 -0.9398)
			(stroke
				(width 0)
				(type default)
			)
			(fill no)
			(layer "B.CrtYd")
		)
		(fp_rect
			(start 0.508 0.9398)
			(end -0.508 -0.9398)
			(stroke
				(width 0)
				(type default)
			)
			(fill no)
			(layer "B.Fab")
		)
		(pad "1" smd custom
			(at 0 -0.4445 270)
			(size 0.1397 0.1397)
			(layers "B.Cu" "B.Mask" "B.Paste")
			(net "P3V3_STBY")
			(options
				(clearance outline)
				(anchor circle)
			)
			(primitives
				(gr_poly
					(pts
						(arc
							(start -0.1778 0.2794)
							(mid -0.249642 0.249642)
							(end -0.2794 0.1778)
						)
						(arc
							(start -0.2794 -0.1778)
							(mid -0.249642 -0.249642)
							(end -0.1778 -0.2794)
						)
						(arc
							(start 0.1778 -0.2794)
							(mid 0.249642 -0.249642)
							(end 0.2794 -0.1778)
						)
						(arc
							(start 0.2794 0.1778)
							(mid 0.249642 0.249642)
							(end 0.1778 0.2794)
						)
					)
					(width 0)
					(fill yes)
				)
			)
		)
		(pad "2" smd custom
			(at 0 0.4445 270)
			(size 0.1397 0.1397)
			(layers "B.Cu" "B.Mask" "B.Paste")
			(net "UART_EXP_BMC_TX")
			(options
				(clearance outline)
				(anchor circle)
			)
			(primitives
				(gr_poly
					(pts
						(arc
							(start -0.1778 0.2794)
							(mid -0.249642 0.249642)
							(end -0.2794 0.1778)
						)
						(arc
							(start -0.2794 -0.1778)
							(mid -0.249642 -0.249642)
							(end -0.1778 -0.2794)
						)
						(arc
							(start 0.1778 -0.2794)
							(mid 0.249642 -0.249642)
							(end 0.2794 -0.1778)
						)
						(arc
							(start 0.2794 0.1778)
							(mid 0.249642 0.249642)
							(end 0.1778 0.2794)
						)
					)
					(width 0)
					(fill yes)
				)
			)
		)
	)
	(footprint ""
		(layer "B.Cu")
		(at 59.2582 -138.5316)
		(property "Reference" "R273"
			(at 0 0 0)
			(layer "B.SilkS")
			(hide yes)
			(effects
				(font
					(size 1.27 1.27)
				)
				(justify mirror)
			)
		)
		(property "Value" "4K7R2F-GP"
			(at -0.064008 -3.993896 0)
			(unlocked yes)
			(layer "B.Fab")
			(hide yes)
			(effects
				(font
					(size 1.016 1.016)
					(thickness 0.1524)
				)
				(justify mirror)
			)
		)
		(property "Device Type" "R402H16"
			(at -0.064008 -5.517896 0)
			(unlocked yes)
			(layer "B.Fab")
			(hide yes)
			(effects
				(font
					(size 1.016 1.016)
					(thickness 0.1524)
				)
				(justify mirror)
			)
		)
		(duplicate_pad_numbers_are_jumpers no)
		(fp_line
			(start -0.508 -0.9398)
			(end 0.508 -0.9398)
			(stroke
				(width 0.1524)
				(type default)
			)
			(layer "B.SilkS")
		)
		(fp_line
			(start 0.508 -0.9398)
			(end 0.508 0.9398)
			(stroke
				(width 0.1524)
				(type default)
			)
			(layer "B.SilkS")
		)
		(fp_rect
			(start 0.508 0.9398)
			(end -0.508 -0.9398)
			(stroke
				(width 0)
				(type default)
			)
			(fill no)
			(layer "B.CrtYd")
		)
		(fp_rect
			(start 0.508 0.9398)
			(end -0.508 -0.9398)
			(stroke
				(width 0)
				(type default)
			)
			(fill no)
			(layer "B.Fab")
		)
		(pad "1" smd custom
			(at 0 -0.4445 180)
			(size 0.1397 0.1397)
			(layers "B.Cu" "B.Mask" "B.Paste")
			(net "SYS_PWR_LED")
			(options
				(clearance outline)
				(anchor circle)
			)
			(primitives
				(gr_poly
					(pts
						(arc
							(start -0.1778 0.2794)
							(mid -0.249642 0.249642)
							(end -0.2794 0.1778)
						)
						(arc
							(start -0.2794 -0.1778)
							(mid -0.249642 -0.249642)
							(end -0.1778 -0.2794)
						)
						(arc
							(start 0.1778 -0.2794)
							(mid 0.249642 -0.249642)
							(end 0.2794 -0.1778)
						)
						(arc
							(start 0.2794 0.1778)
							(mid 0.249642 0.249642)
							(end 0.1778 0.2794)
						)
					)
					(width 0)
					(fill yes)
				)
			)
		)
		(pad "2" smd custom
			(at 0 0.4445 180)
			(size 0.1397 0.1397)
			(layers "B.Cu" "B.Mask" "B.Paste")
			(net "GND")
			(options
				(clearance outline)
				(anchor circle)
			)
			(primitives
				(gr_poly
					(pts
						(arc
							(start -0.1778 0.2794)
							(mid -0.249642 0.249642)
							(end -0.2794 0.1778)
						)
						(arc
							(start -0.2794 -0.1778)
							(mid -0.249642 -0.249642)
							(end -0.1778 -0.2794)
						)
						(arc
							(start 0.1778 -0.2794)
							(mid 0.249642 -0.249642)
							(end 0.2794 -0.1778)
						)
						(arc
							(start 0.2794 0.1778)
							(mid 0.249642 0.249642)
							(end 0.1778 0.2794)
						)
					)
					(width 0)
					(fill yes)
				)
			)
		)
	)
	(footprint ""
		(layer "B.Cu")
		(at 57.58815 -122.974354 90)
		(property "Reference" "R345"
			(at 0 0 90)
			(layer "B.SilkS")
			(hide yes)
			(effects
				(font
					(size 1.27 1.27)
				)
				(justify mirror)
			)
		)
		(property "Value" "0R2J-2-GP"
			(at -0.064008 -3.993896 90)
			(unlocked yes)
			(layer "B.Fab")
			(hide yes)
			(effects
				(font
					(size 1.016 1.016)
					(thickness 0.1524)
				)
				(justify mirror)
			)
		)
		(property "Device Type" "R402H16"
			(at -0.064008 -5.517896 90)
			(unlocked yes)
			(layer "B.Fab")
			(hide yes)
			(effects
				(font
					(size 1.016 1.016)
					(thickness 0.1524)
				)
				(justify mirror)
			)
		)
		(duplicate_pad_numbers_are_jumpers no)
		(fp_line
			(start 0.508 -0.9398)
			(end 0.508 0.9398)
			(stroke
				(width 0.1524)
				(type default)
			)
			(layer "B.SilkS")
		)
		(fp_line
			(start -0.508 -0.9398)
			(end 0.508 -0.9398)
			(stroke
				(width 0.1524)
				(type default)
			)
			(layer "B.SilkS")
		)
		(fp_rect
			(start 0.508 0.9398)
			(end -0.508 -0.9398)
			(stroke
				(width 0)
				(type default)
			)
			(fill no)
			(layer "B.CrtYd")
		)
		(fp_rect
			(start 0.508 0.9398)
			(end -0.508 -0.9398)
			(stroke
				(width 0)
				(type default)
			)
			(fill no)
			(layer "B.Fab")
		)
		(pad "1" smd custom
			(at 0 -0.4445 270)
			(size 0.1397 0.1397)
			(layers "B.Cu" "B.Mask" "B.Paste")
			(net "DEBUG_RST_BTN_N_R")
			(options
				(clearance outline)
				(anchor circle)
			)
			(primitives
				(gr_poly
					(pts
						(arc
							(start -0.1778 0.2794)
							(mid -0.249642 0.249642)
							(end -0.2794 0.1778)
						)
						(arc
							(start -0.2794 -0.1778)
							(mid -0.249642 -0.249642)
							(end -0.1778 -0.2794)
						)
						(arc
							(start 0.1778 -0.2794)
							(mid 0.249642 -0.249642)
							(end 0.2794 -0.1778)
						)
						(arc
							(start 0.2794 0.1778)
							(mid 0.249642 0.249642)
							(end 0.1778 0.2794)
						)
					)
					(width 0)
					(fill yes)
				)
			)
		)
		(pad "2" smd custom
			(at 0 0.4445 270)
			(size 0.1397 0.1397)
			(layers "B.Cu" "B.Mask" "B.Paste")
			(net "DEBUG_RST_BTN_N")
			(options
				(clearance outline)
				(anchor circle)
			)
			(primitives
				(gr_poly
					(pts
						(arc
							(start -0.1778 0.2794)
							(mid -0.249642 0.249642)
							(end -0.2794 0.1778)
						)
						(arc
							(start -0.2794 -0.1778)
							(mid -0.249642 -0.249642)
							(end -0.1778 -0.2794)
						)
						(arc
							(start 0.1778 -0.2794)
							(mid 0.249642 -0.249642)
							(end 0.2794 -0.1778)
						)
						(arc
							(start 0.2794 0.1778)
							(mid 0.249642 0.249642)
							(end 0.1778 0.2794)
						)
					)
					(width 0)
					(fill yes)
				)
			)
		)
	)
	(footprint ""
		(layer "B.Cu")
		(at 47.371 -124.206 -90)
		(property "Reference" "R156"
			(at 0 0 90)
			(layer "B.SilkS")
			(hide yes)
			(effects
				(font
					(size 1.27 1.27)
				)
				(justify mirror)
			)
		)
		(property "Value" "0R2J-2-GP"
			(at -0.064008 -3.993896 270)
			(unlocked yes)
			(layer "B.Fab")
			(hide yes)
			(effects
				(font
					(size 1.016 1.016)
					(thickness 0.1524)
				)
				(justify mirror)
			)
		)
		(property "Device Type" "R402H16"
			(at -0.064008 -5.517896 270)
			(unlocked yes)
			(layer "B.Fab")
			(hide yes)
			(effects
				(font
					(size 1.016 1.016)
					(thickness 0.1524)
				)
				(justify mirror)
			)
		)
		(duplicate_pad_numbers_are_jumpers no)
		(fp_line
			(start -0.508 -0.9398)
			(end 0.508 -0.9398)
			(stroke
				(width 0.1524)
				(type default)
			)
			(layer "B.SilkS")
		)
		(fp_line
			(start 0.508 -0.9398)
			(end 0.508 0.9398)
			(stroke
				(width 0.1524)
				(type default)
			)
			(layer "B.SilkS")
		)
		(fp_rect
			(start 0.508 0.9398)
			(end -0.508 -0.9398)
			(stroke
				(width 0)
				(type default)
			)
			(fill no)
			(layer "B.CrtYd")
		)
		(fp_rect
			(start 0.508 0.9398)
			(end -0.508 -0.9398)
			(stroke
				(width 0)
				(type default)
			)
			(fill no)
			(layer "B.Fab")
		)
		(pad "1" smd custom
			(at 0 -0.4445 90)
			(size 0.1397 0.1397)
			(layers "B.Cu" "B.Mask" "B.Paste")
			(net "BMC_SMB2_CLK_TP")
			(options
				(clearance outline)
				(anchor circle)
			)
			(primitives
				(gr_poly
					(pts
						(arc
							(start -0.1778 0.2794)
							(mid -0.249642 0.249642)
							(end -0.2794 0.1778)
						)
						(arc
							(start -0.2794 -0.1778)
							(mid -0.249642 -0.249642)
							(end -0.1778 -0.2794)
						)
						(arc
							(start 0.1778 -0.2794)
							(mid 0.249642 -0.249642)
							(end 0.2794 -0.1778)
						)
						(arc
							(start 0.2794 0.1778)
							(mid 0.249642 0.249642)
							(end 0.1778 0.2794)
						)
					)
					(width 0)
					(fill yes)
				)
			)
		)
		(pad "2" smd custom
			(at 0 0.4445 90)
			(size 0.1397 0.1397)
			(layers "B.Cu" "B.Mask" "B.Paste")
			(net "BMC_SMB2_CLK")
			(options
				(clearance outline)
				(anchor circle)
			)
			(primitives
				(gr_poly
					(pts
						(arc
							(start -0.1778 0.2794)
							(mid -0.249642 0.249642)
							(end -0.2794 0.1778)
						)
						(arc
							(start -0.2794 -0.1778)
							(mid -0.249642 -0.249642)
							(end -0.1778 -0.2794)
						)
						(arc
							(start 0.1778 -0.2794)
							(mid 0.249642 -0.249642)
							(end 0.2794 -0.1778)
						)
						(arc
							(start 0.2794 0.1778)
							(mid 0.249642 0.249642)
							(end 0.1778 0.2794)
						)
					)
					(width 0)
					(fill yes)
				)
			)
		)
	)
	(footprint ""
		(layer "B.Cu")
		(at 65.4304 -138.0236)
		(property "Reference" "TP13"
			(at 0 0 0)
			(layer "B.SilkS")
			(hide yes)
			(effects
				(font
					(size 1.27 1.27)
				)
				(justify mirror)
			)
		)
		(property "Value" "TPAD28-2-GP"
			(at 0.0127 -1.6637 0)
			(unlocked yes)
			(layer "B.Fab")
			(hide yes)
			(effects
				(font
					(size 1.016 1.016)
					(thickness 0.1524)
				)
				(justify mirror)
			)
		)
		(property "Device Type" "TPAD28"
			(at 0.0127 -3.1877 0)
			(unlocked yes)
			(layer "B.Fab")
			(hide yes)
			(effects
				(font
					(size 1.016 1.016)
					(thickness 0.1524)
				)
				(justify mirror)
			)
		)
		(duplicate_pad_numbers_are_jumpers no)
		(fp_poly
			(pts
				(arc
					(start 0.3556 0)
					(mid -0.3556 0)
					(end 0.3556 0)
				)
			)
			(stroke
				(width 0)
				(type default)
			)
			(fill no)
			(layer "B.CrtYd")
		)
		(fp_poly
			(pts
				(arc
					(start 0.6096 0)
					(mid -0.6096 0)
					(end 0.6096 0)
				)
			)
			(stroke
				(width 0)
				(type default)
			)
			(fill no)
			(layer "B.Fab")
		)
		(pad "1" smd circle
			(at 0 0 180)
			(size 0.7112 0.7112)
			(layers "B.Cu" "B.Mask" "B.Paste")
			(net "TP_BMC_GPIOA0")
		)
	)
	(footprint ""
		(layer "B.Cu")
		(at 32.7914 -152.2222 180)
		(property "Reference" "C92"
			(at 0 0 0)
			(layer "B.SilkS")
			(hide yes)
			(effects
				(font
					(size 1.27 1.27)
				)
				(justify mirror)
			)
		)
		(property "Value" "SC1U16V3KX-5GP"
			(at 0 -2.8194 180)
			(unlocked yes)
			(layer "B.Fab")
			(hide yes)
			(effects
				(font
					(size 1.016 1.016)
					(thickness 0.1524)
				)
				(justify mirror)
			)
		)
		(property "Device Type" "C603H36"
			(at 0 -4.3434 180)
			(unlocked yes)
			(layer "B.Fab")
			(hide yes)
			(effects
				(font
					(size 1.016 1.016)
					(thickness 0.1524)
				)
				(justify mirror)
			)
		)
		(duplicate_pad_numbers_are_jumpers no)
		(fp_line
			(start -0.508 0)
			(end 0.508 0)
			(stroke
				(width 0.2032)
				(type default)
			)
			(layer "B.SilkS")
		)
		(fp_rect
			(start 0.5842 1.3335)
			(end -0.5842 -1.3335)
			(stroke
				(width 0)
				(type default)
			)
			(fill no)
			(layer "B.CrtYd")
		)
		(fp_rect
			(start 0.5842 1.3335)
			(end -0.5842 -1.3335)
			(stroke
				(width 0)
				(type default)
			)
			(fill no)
			(layer "B.Fab")
		)
		(pad "1" smd custom
			(at 0 -0.762)
			(size 0.2159 0.2159)
			(layers "B.Cu" "B.Mask" "B.Paste")
			(net "MPLLAV33")
			(options
				(clearance outline)
				(anchor circle)
			)
			(primitives
				(gr_poly
					(pts
						(arc
							(start -0.3302 0.4318)
							(mid -0.402042 0.402042)
							(end -0.4318 0.3302)
						)
						(arc
							(start -0.4318 -0.3302)
							(mid -0.402042 -0.402042)
							(end -0.3302 -0.4318)
						)
						(arc
							(start 0.3302 -0.4318)
							(mid 0.402042 -0.402042)
							(end 0.4318 -0.3302)
						)
						(arc
							(start 0.4318 0.3302)
							(mid 0.402042 0.402042)
							(end 0.3302 0.4318)
						)
					)
					(width 0)
					(fill yes)
				)
			)
		)
		(pad "2" smd custom
			(at 0 0.762)
			(size 0.2159 0.2159)
			(layers "B.Cu" "B.Mask" "B.Paste")
			(net "GND")
			(options
				(clearance outline)
				(anchor circle)
			)
			(primitives
				(gr_poly
					(pts
						(arc
							(start -0.3302 0.4318)
							(mid -0.402042 0.402042)
							(end -0.4318 0.3302)
						)
						(arc
							(start -0.4318 -0.3302)
							(mid -0.402042 -0.402042)
							(end -0.3302 -0.4318)
						)
						(arc
							(start 0.3302 -0.4318)
							(mid 0.402042 -0.402042)
							(end 0.4318 -0.3302)
						)
						(arc
							(start 0.4318 0.3302)
							(mid 0.402042 0.402042)
							(end 0.3302 0.4318)
						)
					)
					(width 0)
					(fill yes)
				)
			)
		)
	)
	(footprint ""
		(layer "B.Cu")
		(at 48.7172 -120.0912 -90)
		(property "Reference" "U27"
			(at 0 0 90)
			(layer "B.SilkS")
			(hide yes)
			(effects
				(font
					(size 1.27 1.27)
				)
				(justify mirror)
			)
		)
		(property "Value" "TMP75AIDGKR-GP"
			(at 0.1143 -9.1948 270)
			(unlocked yes)
			(layer "B.Fab")
			(hide yes)
			(effects
				(font
					(size 1.016 1.016)
					(thickness 0.1524)
				)
				(justify mirror)
			)
		)
		(property "Device Type" "MSOP8-1H44"
			(at 0.1143 -10.795 270)
			(unlocked yes)
			(layer "B.Fab")
			(hide yes)
			(effects
				(font
					(size 1.016 1.016)
					(thickness 0.1524)
				)
				(justify mirror)
			)
		)
		(duplicate_pad_numbers_are_jumpers no)
		(fp_line
			(start 1.778 1.0922)
			(end 1.778 3.048)
			(stroke
				(width 0.508)
				(type default)
			)
			(layer "B.SilkS")
		)
		(fp_line
			(start -1.0795 1.016)
			(end -1.0795 -1.016)
			(stroke
				(width 0.1524)
				(type default)
			)
			(layer "B.SilkS")
		)
		(fp_line
			(start 1.9558 1.016)
			(end -1.0795 1.016)
			(stroke
				(width 0.1524)
				(type default)
			)
			(layer "B.SilkS")
		)
		(fp_line
			(start 1.4478 -0.0381)
			(end 1.9558 0.4699)
			(stroke
				(width 0.1524)
				(type default)
			)
			(layer "B.SilkS")
		)
		(fp_line
			(start 1.9558 -0.5461)
			(end 1.4478 -0.0381)
			(stroke
				(width 0.1524)
				(type default)
			)
			(layer "B.SilkS")
		)
		(fp_line
			(start -1.0795 -1.016)
			(end 1.9558 -1.016)
			(stroke
				(width 0.1524)
				(type default)
			)
			(layer "B.SilkS")
		)
		(fp_line
			(start 1.9558 -1.016)
			(end 1.9558 1.016)
			(stroke
				(width 0.1524)
				(type default)
			)
			(layer "B.SilkS")
		)
		(fp_poly
			(pts
				(xy 1.1557 -1.016) (xy 1.1557 1.016) (xy -1.1557 1.016) (xy -1.1557 -1.016)
			)
			(stroke
				(width 0)
				(type default)
			)
			(fill yes)
			(layer "B.SilkS")
		)
		(fp_rect
			(start 1.4986 2.4511)
			(end -1.4986 -2.4511)
			(stroke
				(width 0)
				(type default)
			)
			(fill no)
			(layer "B.CrtYd")
		)
		(fp_poly
			(pts
				(xy 2.032 3.302) (xy 2.032 -3.302) (xy -2.032 -3.302) (xy -2.032 -2.1209) (xy -1.4986 -2.1209) (xy -1.4986 -2.4511)
				(xy 1.4986 -2.4511) (xy 1.4986 2.4511) (xy -1.4986 2.4511) (xy -1.4986 -2.1082) (xy -2.032 -2.1082)
				(xy -2.032 3.302)
			)
			(stroke
				(width 0)
				(type default)
			)
			(fill no)
			(layer "B.CrtYd")
		)
		(fp_rect
			(start 2.032 3.302)
			(end -2.032 -3.302)
			(stroke
				(width 0)
				(type default)
			)
			(fill no)
			(layer "B.Fab")
		)
		(pad "1" smd rect
			(at 0.97536 2.05486 90)
			(size 0.3556 1.524)
			(layers "B.Cu" "B.Mask" "B.Paste")
			(net "TEMP_3_SDA")
		)
		(pad "2" smd rect
			(at 0.32512 2.05486 90)
			(size 0.3556 1.524)
			(layers "B.Cu" "B.Mask" "B.Paste")
			(net "TEMP_3_SCL")
		)
		(pad "3" smd rect
			(at -0.32512 2.05486 90)
			(size 0.3556 1.524)
			(layers "B.Cu" "B.Mask" "B.Paste")
			(net "TEMP_3_ALERT")
		)
		(pad "4" smd rect
			(at -0.97536 2.05486 90)
			(size 0.3556 1.524)
			(layers "B.Cu" "B.Mask" "B.Paste")
			(net "GND")
		)
		(pad "5" smd rect
			(at -0.97536 -2.05486 90)
			(size 0.3556 1.524)
			(layers "B.Cu" "B.Mask" "B.Paste")
			(net "TEMP_3_A2")
		)
		(pad "6" smd rect
			(at -0.32512 -2.05486 90)
			(size 0.3556 1.524)
			(layers "B.Cu" "B.Mask" "B.Paste")
			(net "TEMP_3_A1")
		)
		(pad "7" smd rect
			(at 0.32512 -2.05486 90)
			(size 0.3556 1.524)
			(layers "B.Cu" "B.Mask" "B.Paste")
			(net "TEMP_3_A0")
		)
		(pad "8" smd rect
			(at 0.97536 -2.05486 90)
			(size 0.3556 1.524)
			(layers "B.Cu" "B.Mask" "B.Paste")
			(net "P3V3_STBY")
		)
	)
	(footprint ""
		(layer "B.Cu")
		(at 57.42305 -146.511264 -90)
		(property "Reference" "R360"
			(at 0 0 90)
			(layer "B.SilkS")
			(hide yes)
			(effects
				(font
					(size 1.27 1.27)
				)
				(justify mirror)
			)
		)
		(property "Value" "10KR2F-2-GP"
			(at -0.064008 -3.993896 270)
			(unlocked yes)
			(layer "B.Fab")
			(hide yes)
			(effects
				(font
					(size 1.016 1.016)
					(thickness 0.1524)
				)
				(justify mirror)
			)
		)
		(property "Device Type" "R402H16"
			(at -0.064008 -5.517896 270)
			(unlocked yes)
			(layer "B.Fab")
			(hide yes)
			(effects
				(font
					(size 1.016 1.016)
					(thickness 0.1524)
				)
				(justify mirror)
			)
		)
		(duplicate_pad_numbers_are_jumpers no)
		(fp_line
			(start -0.508 -0.9398)
			(end 0.508 -0.9398)
			(stroke
				(width 0.1524)
				(type default)
			)
			(layer "B.SilkS")
		)
		(fp_line
			(start 0.508 -0.9398)
			(end 0.508 0.9398)
			(stroke
				(width 0.1524)
				(type default)
			)
			(layer "B.SilkS")
		)
		(fp_rect
			(start 0.508 0.9398)
			(end -0.508 -0.9398)
			(stroke
				(width 0)
				(type default)
			)
			(fill no)
			(layer "B.CrtYd")
		)
		(fp_rect
			(start 0.508 0.9398)
			(end -0.508 -0.9398)
			(stroke
				(width 0)
				(type default)
			)
			(fill no)
			(layer "B.Fab")
		)
		(pad "1" smd custom
			(at 0 -0.4445 90)
			(size 0.1397 0.1397)
			(layers "B.Cu" "B.Mask" "B.Paste")
			(net "P3V3_STBY")
			(options
				(clearance outline)
				(anchor circle)
			)
			(primitives
				(gr_poly
					(pts
						(arc
							(start -0.1778 0.2794)
							(mid -0.249642 0.249642)
							(end -0.2794 0.1778)
						)
						(arc
							(start -0.2794 -0.1778)
							(mid -0.249642 -0.249642)
							(end -0.1778 -0.2794)
						)
						(arc
							(start 0.1778 -0.2794)
							(mid 0.249642 -0.249642)
							(end 0.2794 -0.1778)
						)
						(arc
							(start 0.2794 0.1778)
							(mid 0.249642 0.249642)
							(end 0.1778 0.2794)
						)
					)
					(width 0)
					(fill yes)
				)
			)
		)
		(pad "2" smd custom
			(at 0 0.4445 90)
			(size 0.1397 0.1397)
			(layers "B.Cu" "B.Mask" "B.Paste")
			(net "JTAG_BMC_TCK")
			(options
				(clearance outline)
				(anchor circle)
			)
			(primitives
				(gr_poly
					(pts
						(arc
							(start -0.1778 0.2794)
							(mid -0.249642 0.249642)
							(end -0.2794 0.1778)
						)
						(arc
							(start -0.2794 -0.1778)
							(mid -0.249642 -0.249642)
							(end -0.1778 -0.2794)
						)
						(arc
							(start 0.1778 -0.2794)
							(mid 0.249642 -0.249642)
							(end 0.2794 -0.1778)
						)
						(arc
							(start 0.2794 0.1778)
							(mid 0.249642 0.249642)
							(end 0.1778 0.2794)
						)
					)
					(width 0)
					(fill yes)
				)
			)
		)
	)
	(footprint ""
		(layer "B.Cu")
		(at 215.60028 -102.050088)
		(property "Reference" "R844"
			(at 0 0 0)
			(layer "B.SilkS")
			(hide yes)
			(effects
				(font
					(size 1.27 1.27)
				)
				(justify mirror)
			)
		)
		(property "Value" "309KR2F-GP"
			(at -0.064008 -3.993896 0)
			(unlocked yes)
			(layer "B.Fab")
			(hide yes)
			(effects
				(font
					(size 1.016 1.016)
					(thickness 0.1524)
				)
				(justify mirror)
			)
		)
		(property "Device Type" "R402H16"
			(at -0.064008 -5.517896 0)
			(unlocked yes)
			(layer "B.Fab")
			(hide yes)
			(effects
				(font
					(size 1.016 1.016)
					(thickness 0.1524)
				)
				(justify mirror)
			)
		)
		(duplicate_pad_numbers_are_jumpers no)
		(fp_line
			(start -0.508 -0.9398)
			(end 0.508 -0.9398)
			(stroke
				(width 0.1524)
				(type default)
			)
			(layer "B.SilkS")
		)
		(fp_line
			(start 0.508 -0.9398)
			(end 0.508 0.9398)
			(stroke
				(width 0.1524)
				(type default)
			)
			(layer "B.SilkS")
		)
		(fp_rect
			(start 0.508 0.9398)
			(end -0.508 -0.9398)
			(stroke
				(width 0)
				(type default)
			)
			(fill no)
			(layer "B.CrtYd")
		)
		(fp_rect
			(start 0.508 0.9398)
			(end -0.508 -0.9398)
			(stroke
				(width 0)
				(type default)
			)
			(fill no)
			(layer "B.Fab")
		)
		(pad "1" smd custom
			(at 0 -0.4445 180)
			(size 0.1397 0.1397)
			(layers "B.Cu" "B.Mask" "B.Paste")
			(net "P3V3_M2_VREG")
			(options
				(clearance outline)
				(anchor circle)
			)
			(primitives
				(gr_poly
					(pts
						(arc
							(start -0.1778 0.2794)
							(mid -0.249642 0.249642)
							(end -0.2794 0.1778)
						)
						(arc
							(start -0.2794 -0.1778)
							(mid -0.249642 -0.249642)
							(end -0.1778 -0.2794)
						)
						(arc
							(start 0.1778 -0.2794)
							(mid 0.249642 -0.249642)
							(end 0.2794 -0.1778)
						)
						(arc
							(start 0.2794 0.1778)
							(mid 0.249642 0.249642)
							(end 0.1778 0.2794)
						)
					)
					(width 0)
					(fill yes)
				)
			)
		)
		(pad "2" smd custom
			(at 0 0.4445 180)
			(size 0.1397 0.1397)
			(layers "B.Cu" "B.Mask" "B.Paste")
			(net "P3V3_M2_RF")
			(options
				(clearance outline)
				(anchor circle)
			)
			(primitives
				(gr_poly
					(pts
						(arc
							(start -0.1778 0.2794)
							(mid -0.249642 0.249642)
							(end -0.2794 0.1778)
						)
						(arc
							(start -0.2794 -0.1778)
							(mid -0.249642 -0.249642)
							(end -0.1778 -0.2794)
						)
						(arc
							(start 0.1778 -0.2794)
							(mid 0.249642 -0.249642)
							(end 0.2794 -0.1778)
						)
						(arc
							(start 0.2794 0.1778)
							(mid 0.249642 0.249642)
							(end 0.1778 0.2794)
						)
					)
					(width 0)
					(fill yes)
				)
			)
		)
	)
	(footprint ""
		(layer "B.Cu")
		(at 87.3506 -95.9612 -90)
		(property "Reference" "R728"
			(at 0 0 90)
			(layer "B.SilkS")
			(hide yes)
			(effects
				(font
					(size 1.27 1.27)
				)
				(justify mirror)
			)
		)
		(property "Value" "4K7R2F-GP"
			(at -0.064008 -3.993896 270)
			(unlocked yes)
			(layer "B.Fab")
			(hide yes)
			(effects
				(font
					(size 1.016 1.016)
					(thickness 0.1524)
				)
				(justify mirror)
			)
		)
		(property "Device Type" "R402H16"
			(at -0.064008 -5.517896 270)
			(unlocked yes)
			(layer "B.Fab")
			(hide yes)
			(effects
				(font
					(size 1.016 1.016)
					(thickness 0.1524)
				)
				(justify mirror)
			)
		)
		(duplicate_pad_numbers_are_jumpers no)
		(fp_line
			(start -0.508 -0.9398)
			(end 0.508 -0.9398)
			(stroke
				(width 0.1524)
				(type default)
			)
			(layer "B.SilkS")
		)
		(fp_line
			(start 0.508 -0.9398)
			(end 0.508 0.9398)
			(stroke
				(width 0.1524)
				(type default)
			)
			(layer "B.SilkS")
		)
		(fp_rect
			(start 0.508 0.9398)
			(end -0.508 -0.9398)
			(stroke
				(width 0)
				(type default)
			)
			(fill no)
			(layer "B.CrtYd")
		)
		(fp_rect
			(start 0.508 0.9398)
			(end -0.508 -0.9398)
			(stroke
				(width 0)
				(type default)
			)
			(fill no)
			(layer "B.Fab")
		)
		(pad "1" smd custom
			(at 0 -0.4445 90)
			(size 0.1397 0.1397)
			(layers "B.Cu" "B.Mask" "B.Paste")
			(net "CONN_A_PRSNTA")
			(options
				(clearance outline)
				(anchor circle)
			)
			(primitives
				(gr_poly
					(pts
						(arc
							(start -0.1778 0.2794)
							(mid -0.249642 0.249642)
							(end -0.2794 0.1778)
						)
						(arc
							(start -0.2794 -0.1778)
							(mid -0.249642 -0.249642)
							(end -0.1778 -0.2794)
						)
						(arc
							(start 0.1778 -0.2794)
							(mid 0.249642 -0.249642)
							(end 0.2794 -0.1778)
						)
						(arc
							(start 0.2794 0.1778)
							(mid 0.249642 0.249642)
							(end 0.1778 0.2794)
						)
					)
					(width 0)
					(fill yes)
				)
			)
		)
		(pad "2" smd custom
			(at 0 0.4445 90)
			(size 0.1397 0.1397)
			(layers "B.Cu" "B.Mask" "B.Paste")
			(net "P3V3_STBY")
			(options
				(clearance outline)
				(anchor circle)
			)
			(primitives
				(gr_poly
					(pts
						(arc
							(start -0.1778 0.2794)
							(mid -0.249642 0.249642)
							(end -0.2794 0.1778)
						)
						(arc
							(start -0.2794 -0.1778)
							(mid -0.249642 -0.249642)
							(end -0.1778 -0.2794)
						)
						(arc
							(start 0.1778 -0.2794)
							(mid 0.249642 -0.249642)
							(end 0.2794 -0.1778)
						)
						(arc
							(start 0.2794 0.1778)
							(mid 0.249642 0.249642)
							(end 0.1778 0.2794)
						)
					)
					(width 0)
					(fill yes)
				)
			)
		)
	)
	(footprint ""
		(layer "B.Cu")
		(at 40.2844 -133.7818 180)
		(property "Reference" "R375"
			(at 0 0 0)
			(layer "B.SilkS")
			(hide yes)
			(effects
				(font
					(size 1.27 1.27)
				)
				(justify mirror)
			)
		)
		(property "Value" "4K7R2F-GP"
			(at -0.064008 -3.993896 180)
			(unlocked yes)
			(layer "B.Fab")
			(hide yes)
			(effects
				(font
					(size 1.016 1.016)
					(thickness 0.1524)
				)
				(justify mirror)
			)
		)
		(property "Device Type" "R402H16"
			(at -0.064008 -5.517896 180)
			(unlocked yes)
			(layer "B.Fab")
			(hide yes)
			(effects
				(font
					(size 1.016 1.016)
					(thickness 0.1524)
				)
				(justify mirror)
			)
		)
		(duplicate_pad_numbers_are_jumpers no)
		(fp_line
			(start 0.508 -0.9398)
			(end 0.508 0.9398)
			(stroke
				(width 0.1524)
				(type default)
			)
			(layer "B.SilkS")
		)
		(fp_line
			(start -0.508 -0.9398)
			(end 0.508 -0.9398)
			(stroke
				(width 0.1524)
				(type default)
			)
			(layer "B.SilkS")
		)
		(fp_rect
			(start 0.508 0.9398)
			(end -0.508 -0.9398)
			(stroke
				(width 0)
				(type default)
			)
			(fill no)
			(layer "B.CrtYd")
		)
		(fp_rect
			(start 0.508 0.9398)
			(end -0.508 -0.9398)
			(stroke
				(width 0)
				(type default)
			)
			(fill no)
			(layer "B.Fab")
		)
		(pad "1" smd custom
			(at 0 -0.4445)
			(size 0.1397 0.1397)
			(layers "B.Cu" "B.Mask" "B.Paste")
			(net "P3V3_STBY")
			(options
				(clearance outline)
				(anchor circle)
			)
			(primitives
				(gr_poly
					(pts
						(arc
							(start -0.1778 0.2794)
							(mid -0.249642 0.249642)
							(end -0.2794 0.1778)
						)
						(arc
							(start -0.2794 -0.1778)
							(mid -0.249642 -0.249642)
							(end -0.1778 -0.2794)
						)
						(arc
							(start 0.1778 -0.2794)
							(mid 0.249642 -0.249642)
							(end 0.2794 -0.1778)
						)
						(arc
							(start 0.2794 0.1778)
							(mid 0.249642 0.249642)
							(end 0.1778 0.2794)
						)
					)
					(width 0)
					(fill yes)
				)
			)
		)
		(pad "2" smd custom
			(at 0 0.4445)
			(size 0.1397 0.1397)
			(layers "B.Cu" "B.Mask" "B.Paste")
			(net "BMC_GPIOS7")
			(options
				(clearance outline)
				(anchor circle)
			)
			(primitives
				(gr_poly
					(pts
						(arc
							(start -0.1778 0.2794)
							(mid -0.249642 0.249642)
							(end -0.2794 0.1778)
						)
						(arc
							(start -0.2794 -0.1778)
							(mid -0.249642 -0.249642)
							(end -0.1778 -0.2794)
						)
						(arc
							(start 0.1778 -0.2794)
							(mid 0.249642 -0.249642)
							(end 0.2794 -0.1778)
						)
						(arc
							(start 0.2794 0.1778)
							(mid 0.249642 0.249642)
							(end 0.1778 0.2794)
						)
					)
					(width 0)
					(fill yes)
				)
			)
		)
	)
	(footprint ""
		(layer "B.Cu")
		(at 84.871306 -170.019726 90)
		(property "Reference" "U32"
			(at 0 0 90)
			(layer "B.SilkS")
			(hide yes)
			(effects
				(font
					(size 1.27 1.27)
				)
				(justify mirror)
			)
		)
		(property "Value" "SN74LVC126APWR-1-GP"
			(at 0 -10.6172 90)
			(unlocked yes)
			(layer "B.Fab")
			(hide yes)
			(effects
				(font
					(size 1.016 1.016)
					(thickness 0.1524)
				)
				(justify mirror)
			)
		)
		(property "Device Type" "SSOIC14-1H48"
			(at 0 -12.1412 90)
			(unlocked yes)
			(layer "B.Fab")
			(hide yes)
			(effects
				(font
					(size 1.016 1.016)
					(thickness 0.1524)
				)
				(justify mirror)
			)
		)
		(duplicate_pad_numbers_are_jumpers no)
		(fp_line
			(start 2.2352 -1.8415)
			(end -2.2352 -1.8415)
			(stroke
				(width 0.0254)
				(type default)
			)
			(layer "B.SilkS")
		)
		(fp_line
			(start -2.2352 -1.8415)
			(end -2.2352 1.8415)
			(stroke
				(width 0.0254)
				(type default)
			)
			(layer "B.SilkS")
		)
		(fp_line
			(start 2.2352 -1.8288)
			(end -2.2225 -1.8288)
			(stroke
				(width 0.0254)
				(type default)
			)
			(layer "B.SilkS")
		)
		(fp_line
			(start -2.23266 -1.8161)
			(end 2.2352 -1.8161)
			(stroke
				(width 0.0254)
				(type default)
			)
			(layer "B.SilkS")
		)
		(fp_line
			(start 2.2352 -1.8034)
			(end -2.2225 -1.8034)
			(stroke
				(width 0.0254)
				(type default)
			)
			(layer "B.SilkS")
		)
		(fp_line
			(start -2.23266 -1.7907)
			(end 2.2352 -1.7907)
			(stroke
				(width 0.0254)
				(type default)
			)
			(layer "B.SilkS")
		)
		(fp_line
			(start 2.2352 -1.778)
			(end -2.2225 -1.778)
			(stroke
				(width 0.0254)
				(type default)
			)
			(layer "B.SilkS")
		)
		(fp_line
			(start -2.23266 -1.7653)
			(end 2.2352 -1.7653)
			(stroke
				(width 0.0254)
				(type default)
			)
			(layer "B.SilkS")
		)
		(fp_line
			(start 2.2352 -1.7526)
			(end -2.2225 -1.7526)
			(stroke
				(width 0.0254)
				(type default)
			)
			(layer "B.SilkS")
		)
		(fp_line
			(start -2.23266 -1.7399)
			(end 2.2352 -1.7399)
			(stroke
				(width 0.0254)
				(type default)
			)
			(layer "B.SilkS")
		)
		(fp_line
			(start 2.2352 -1.7272)
			(end -2.2225 -1.7272)
			(stroke
				(width 0.0254)
				(type default)
			)
			(layer "B.SilkS")
		)
		(fp_line
			(start -2.23266 -1.7145)
			(end 2.2352 -1.7145)
			(stroke
				(width 0.0254)
				(type default)
			)
			(layer "B.SilkS")
		)
		(fp_line
			(start 2.2352 -1.7018)
			(end -2.2225 -1.7018)
			(stroke
				(width 0.0254)
				(type default)
			)
			(layer "B.SilkS")
		)
		(fp_line
			(start -2.23266 -1.6891)
			(end 2.2352 -1.6891)
			(stroke
				(width 0.0254)
				(type default)
			)
			(layer "B.SilkS")
		)
		(fp_line
			(start 2.2352 -1.6764)
			(end -2.2225 -1.6764)
			(stroke
				(width 0.0254)
				(type default)
			)
			(layer "B.SilkS")
		)
		(fp_line
			(start -2.23266 -1.6637)
			(end 2.2352 -1.6637)
			(stroke
				(width 0.0254)
				(type default)
			)
			(layer "B.SilkS")
		)
		(fp_line
			(start 2.794 -1.651)
			(end -2.159 -1.651)
			(stroke
				(width 0.2032)
				(type default)
			)
			(layer "B.SilkS")
		)
		(fp_line
			(start 2.794 -1.651)
			(end 2.794 4.064)
			(stroke
				(width 0.2032)
				(type default)
			)
			(layer "B.SilkS")
		)
		(fp_line
			(start 2.2352 -1.651)
			(end -2.2225 -1.651)
			(stroke
				(width 0.0254)
				(type default)
			)
			(layer "B.SilkS")
		)
		(fp_line
			(start -2.159 -1.651)
			(end -2.159 1.651)
			(stroke
				(width 0.2032)
				(type default)
			)
			(layer "B.SilkS")
		)
		(fp_line
			(start -2.23266 -1.6383)
			(end 2.2352 -1.6383)
			(stroke
				(width 0.0254)
				(type default)
			)
			(layer "B.SilkS")
		)
		(fp_line
			(start 2.2352 -1.6256)
			(end -2.2225 -1.6256)
			(stroke
				(width 0.0254)
				(type default)
			)
			(layer "B.SilkS")
		)
		(fp_line
			(start -2.23266 -1.6129)
			(end 2.2352 -1.6129)
			(stroke
				(width 0.0254)
				(type default)
			)
			(layer "B.SilkS")
		)
		(fp_line
			(start 2.2352 -1.6002)
			(end -2.2225 -1.6002)
			(stroke
				(width 0.0254)
				(type default)
			)
			(layer "B.SilkS")
		)
		(fp_line
			(start -2.23266 -1.5875)
			(end 2.2352 -1.5875)
			(stroke
				(width 0.0254)
				(type default)
			)
			(layer "B.SilkS")
		)
		(fp_line
			(start 2.2352 -1.5748)
			(end -2.2225 -1.5748)
			(stroke
				(width 0.0254)
				(type default)
			)
			(layer "B.SilkS")
		)
		(fp_line
			(start -2.23266 -1.5621)
			(end 2.2352 -1.5621)
			(stroke
				(width 0.0254)
				(type default)
			)
			(layer "B.SilkS")
		)
		(fp_line
			(start 2.2352 -1.5494)
			(end -2.2225 -1.5494)
			(stroke
				(width 0.0254)
				(type default)
			)
			(layer "B.SilkS")
		)
		(fp_line
			(start -2.23266 -1.5367)
			(end 2.2352 -1.5367)
			(stroke
				(width 0.0254)
				(type default)
			)
			(layer "B.SilkS")
		)
		(fp_line
			(start 2.2352 -1.524)
			(end -2.2225 -1.524)
			(stroke
				(width 0.0254)
				(type default)
			)
			(layer "B.SilkS")
		)
		(fp_line
			(start -2.23266 -1.5113)
			(end 2.2352 -1.5113)
			(stroke
				(width 0.0254)
				(type default)
			)
			(layer "B.SilkS")
		)
		(fp_line
			(start 2.2352 -1.4986)
			(end -2.2225 -1.4986)
			(stroke
				(width 0.0254)
				(type default)
			)
			(layer "B.SilkS")
		)
		(fp_line
			(start -2.23266 -1.4859)
			(end 2.2352 -1.4859)
			(stroke
				(width 0.0254)
				(type default)
			)
			(layer "B.SilkS")
		)
		(fp_line
			(start 2.2352 -1.4732)
			(end -2.2225 -1.4732)
			(stroke
				(width 0.0254)
				(type default)
			)
			(layer "B.SilkS")
		)
		(fp_line
			(start -2.23266 -1.4605)
			(end 2.2352 -1.4605)
			(stroke
				(width 0.0254)
				(type default)
			)
			(layer "B.SilkS")
		)
		(fp_line
			(start 2.2352 -1.4478)
			(end -2.2225 -1.4478)
			(stroke
				(width 0.0254)
				(type default)
			)
			(layer "B.SilkS")
		)
		(fp_line
			(start -2.23266 -1.4351)
			(end 2.2352 -1.4351)
			(stroke
				(width 0.0254)
				(type default)
			)
			(layer "B.SilkS")
		)
		(fp_line
			(start 2.2352 -1.4224)
			(end -2.2225 -1.4224)
			(stroke
				(width 0.0254)
				(type default)
			)
			(layer "B.SilkS")
		)
		(fp_line
			(start -2.23266 -1.4097)
			(end 2.2352 -1.4097)
			(stroke
				(width 0.0254)
				(type default)
			)
			(layer "B.SilkS")
		)
		(fp_line
			(start 2.2352 -1.397)
			(end -2.2225 -1.397)
			(stroke
				(width 0.0254)
				(type default)
			)
			(layer "B.SilkS")
		)
		(fp_line
			(start -2.23266 -1.3843)
			(end 2.2352 -1.3843)
			(stroke
				(width 0.0254)
				(type default)
			)
			(layer "B.SilkS")
		)
		(fp_line
			(start 2.2352 -1.3716)
			(end -2.2225 -1.3716)
			(stroke
				(width 0.0254)
				(type default)
			)
			(layer "B.SilkS")
		)
		(fp_line
			(start -2.23266 -1.3589)
			(end 2.2352 -1.3589)
			(stroke
				(width 0.0254)
				(type default)
			)
			(layer "B.SilkS")
		)
		(fp_line
			(start 2.2352 -1.3462)
			(end -2.2225 -1.3462)
			(stroke
				(width 0.0254)
				(type default)
			)
			(layer "B.SilkS")
		)
		(fp_line
			(start -2.23266 -1.3335)
			(end 2.2352 -1.3335)
			(stroke
				(width 0.0254)
				(type default)
			)
			(layer "B.SilkS")
		)
		(fp_line
			(start 2.2352 -1.3208)
			(end -2.2225 -1.3208)
			(stroke
				(width 0.0254)
				(type default)
			)
			(layer "B.SilkS")
		)
		(fp_line
			(start -2.23266 -1.3081)
			(end 2.2352 -1.3081)
			(stroke
				(width 0.0254)
				(type default)
			)
			(layer "B.SilkS")
		)
		(fp_line
			(start 2.2352 -1.2954)
			(end -2.2225 -1.2954)
			(stroke
				(width 0.0254)
				(type default)
			)
			(layer "B.SilkS")
		)
		(fp_line
			(start -2.23266 -1.2827)
			(end 2.2352 -1.2827)
			(stroke
				(width 0.0254)
				(type default)
			)
			(layer "B.SilkS")
		)
		(fp_line
			(start 2.2352 -1.27)
			(end -2.2225 -1.27)
			(stroke
				(width 0.0254)
				(type default)
			)
			(layer "B.SilkS")
		)
		(fp_line
			(start -2.23266 -1.2573)
			(end 2.2352 -1.2573)
			(stroke
				(width 0.0254)
				(type default)
			)
			(layer "B.SilkS")
		)
		(fp_line
			(start 2.2352 -1.2446)
			(end -2.2225 -1.2446)
			(stroke
				(width 0.0254)
				(type default)
			)
			(layer "B.SilkS")
		)
		(fp_line
			(start -2.23266 -1.2319)
			(end 2.2352 -1.2319)
			(stroke
				(width 0.0254)
				(type default)
			)
			(layer "B.SilkS")
		)
		(fp_line
			(start 2.2352 -1.2192)
			(end -2.2225 -1.2192)
			(stroke
				(width 0.0254)
				(type default)
			)
			(layer "B.SilkS")
		)
		(fp_line
			(start -2.23266 -1.2065)
			(end 2.2352 -1.2065)
			(stroke
				(width 0.0254)
				(type default)
			)
			(layer "B.SilkS")
		)
		(fp_line
			(start 2.2352 -1.1938)
			(end -2.2225 -1.1938)
			(stroke
				(width 0.0254)
				(type default)
			)
			(layer "B.SilkS")
		)
		(fp_line
			(start -2.23266 -1.1811)
			(end 2.2352 -1.1811)
			(stroke
				(width 0.0254)
				(type default)
			)
			(layer "B.SilkS")
		)
		(fp_line
			(start 2.2352 -1.1684)
			(end -2.2225 -1.1684)
			(stroke
				(width 0.0254)
				(type default)
			)
			(layer "B.SilkS")
		)
		(fp_line
			(start -2.23266 -1.1557)
			(end 2.2352 -1.1557)
			(stroke
				(width 0.0254)
				(type default)
			)
			(layer "B.SilkS")
		)
		(fp_line
			(start 2.2352 -1.143)
			(end -2.2225 -1.143)
			(stroke
				(width 0.0254)
				(type default)
			)
			(layer "B.SilkS")
		)
		(fp_line
			(start -2.23266 -1.1303)
			(end 2.2352 -1.1303)
			(stroke
				(width 0.0254)
				(type default)
			)
			(layer "B.SilkS")
		)
		(fp_line
			(start 2.2352 -1.1176)
			(end -2.2225 -1.1176)
			(stroke
				(width 0.0254)
				(type default)
			)
			(layer "B.SilkS")
		)
		(fp_line
			(start -2.23266 -1.1049)
			(end 2.2352 -1.1049)
			(stroke
				(width 0.0254)
				(type default)
			)
			(layer "B.SilkS")
		)
		(fp_line
			(start 2.2352 -1.0922)
			(end -2.2225 -1.0922)
			(stroke
				(width 0.0254)
				(type default)
			)
			(layer "B.SilkS")
		)
		(fp_line
			(start -2.23266 -1.0795)
			(end 2.2352 -1.0795)
			(stroke
				(width 0.0254)
				(type default)
			)
			(layer "B.SilkS")
		)
		(fp_line
			(start 2.2352 -1.0668)
			(end -2.2225 -1.0668)
			(stroke
				(width 0.0254)
				(type default)
			)
			(layer "B.SilkS")
		)
		(fp_line
			(start -2.23266 -1.0541)
			(end 2.2352 -1.0541)
			(stroke
				(width 0.0254)
				(type default)
			)
			(layer "B.SilkS")
		)
		(fp_line
			(start 2.2352 -1.0414)
			(end -2.2225 -1.0414)
			(stroke
				(width 0.0254)
				(type default)
			)
			(layer "B.SilkS")
		)
		(fp_line
			(start -2.23266 -1.0287)
			(end 2.2352 -1.0287)
			(stroke
				(width 0.0254)
				(type default)
			)
			(layer "B.SilkS")
		)
		(fp_line
			(start 2.2352 -1.016)
			(end -2.2225 -1.016)
			(stroke
				(width 0.0254)
				(type default)
			)
			(layer "B.SilkS")
		)
		(fp_line
			(start -2.23266 -1.0033)
			(end 2.2352 -1.0033)
			(stroke
				(width 0.0254)
				(type default)
			)
			(layer "B.SilkS")
		)
		(fp_line
			(start 2.2352 -0.9906)
			(end -2.2225 -0.9906)
			(stroke
				(width 0.0254)
				(type default)
			)
			(layer "B.SilkS")
		)
		(fp_line
			(start -2.23266 -0.9779)
			(end 2.2352 -0.9779)
			(stroke
				(width 0.0254)
				(type default)
			)
			(layer "B.SilkS")
		)
		(fp_line
			(start 2.2352 -0.9652)
			(end -2.2225 -0.9652)
			(stroke
				(width 0.0254)
				(type default)
			)
			(layer "B.SilkS")
		)
		(fp_line
			(start -2.23266 -0.9525)
			(end 2.2352 -0.9525)
			(stroke
				(width 0.0254)
				(type default)
			)
			(layer "B.SilkS")
		)
		(fp_line
			(start 2.2352 -0.9398)
			(end -2.2225 -0.9398)
			(stroke
				(width 0.0254)
				(type default)
			)
			(layer "B.SilkS")
		)
		(fp_line
			(start -2.23266 -0.9271)
			(end 2.2352 -0.9271)
			(stroke
				(width 0.0254)
				(type default)
			)
			(layer "B.SilkS")
		)
		(fp_line
			(start 2.2352 -0.9144)
			(end -2.2225 -0.9144)
			(stroke
				(width 0.0254)
				(type default)
			)
			(layer "B.SilkS")
		)
		(fp_line
			(start -2.23266 -0.9017)
			(end 2.2352 -0.9017)
			(stroke
				(width 0.0254)
				(type default)
			)
			(layer "B.SilkS")
		)
		(fp_line
			(start 2.2352 -0.889)
			(end -2.2225 -0.889)
			(stroke
				(width 0.0254)
				(type default)
			)
			(layer "B.SilkS")
		)
		(fp_line
			(start -2.23266 -0.8763)
			(end 2.2352 -0.8763)
			(stroke
				(width 0.0254)
				(type default)
			)
			(layer "B.SilkS")
		)
		(fp_line
			(start 2.2352 -0.8636)
			(end -2.2225 -0.8636)
			(stroke
				(width 0.0254)
				(type default)
			)
			(layer "B.SilkS")
		)
		(fp_line
			(start -2.23266 -0.8509)
			(end 2.2352 -0.8509)
			(stroke
				(width 0.0254)
				(type default)
			)
			(layer "B.SilkS")
		)
		(fp_line
			(start 2.2352 -0.8382)
			(end -2.2225 -0.8382)
			(stroke
				(width 0.0254)
				(type default)
			)
			(layer "B.SilkS")
		)
		(fp_line
			(start -2.23266 -0.8255)
			(end 2.2352 -0.8255)
			(stroke
				(width 0.0254)
				(type default)
			)
			(layer "B.SilkS")
		)
		(fp_line
			(start 2.2352 -0.8128)
			(end -2.2225 -0.8128)
			(stroke
				(width 0.0254)
				(type default)
			)
			(layer "B.SilkS")
		)
		(fp_line
			(start -2.23266 -0.8001)
			(end 2.2352 -0.8001)
			(stroke
				(width 0.0254)
				(type default)
			)
			(layer "B.SilkS")
		)
		(fp_line
			(start 2.2352 -0.7874)
			(end -2.2225 -0.7874)
			(stroke
				(width 0.0254)
				(type default)
			)
			(layer "B.SilkS")
		)
		(fp_line
			(start -2.23266 -0.7747)
			(end 2.2352 -0.7747)
			(stroke
				(width 0.0254)
				(type default)
			)
			(layer "B.SilkS")
		)
		(fp_line
			(start 2.2352 -0.762)
			(end -2.2225 -0.762)
			(stroke
				(width 0.0254)
				(type default)
			)
			(layer "B.SilkS")
		)
		(fp_line
			(start -2.23266 -0.7493)
			(end 2.2352 -0.7493)
			(stroke
				(width 0.0254)
				(type default)
			)
			(layer "B.SilkS")
		)
		(fp_line
			(start 2.2352 -0.7366)
			(end -2.2225 -0.7366)
			(stroke
				(width 0.0254)
				(type default)
			)
			(layer "B.SilkS")
		)
		(fp_line
			(start -2.23266 -0.7239)
			(end 2.2352 -0.7239)
			(stroke
				(width 0.0254)
				(type default)
			)
			(layer "B.SilkS")
		)
		(fp_line
			(start 2.2352 -0.7112)
			(end -2.2225 -0.7112)
			(stroke
				(width 0.0254)
				(type default)
			)
			(layer "B.SilkS")
		)
		(fp_line
			(start -2.23266 -0.6985)
			(end 2.2352 -0.6985)
			(stroke
				(width 0.0254)
				(type default)
			)
			(layer "B.SilkS")
		)
		(fp_line
			(start 2.2352 -0.6858)
			(end -2.2225 -0.6858)
			(stroke
				(width 0.0254)
				(type default)
			)
			(layer "B.SilkS")
		)
		(fp_line
			(start -2.23266 -0.6731)
			(end 2.2352 -0.6731)
			(stroke
				(width 0.0254)
				(type default)
			)
			(layer "B.SilkS")
		)
		(fp_line
			(start 2.2352 -0.6604)
			(end -2.2225 -0.6604)
			(stroke
				(width 0.0254)
				(type default)
			)
			(layer "B.SilkS")
		)
		(fp_line
			(start -2.23266 -0.6477)
			(end 2.2352 -0.6477)
			(stroke
				(width 0.0254)
				(type default)
			)
			(layer "B.SilkS")
		)
		(fp_line
			(start 2.2352 -0.635)
			(end -2.2225 -0.635)
			(stroke
				(width 0.0254)
				(type default)
			)
			(layer "B.SilkS")
		)
		(fp_line
			(start -2.23266 -0.6223)
			(end 2.2352 -0.6223)
			(stroke
				(width 0.0254)
				(type default)
			)
			(layer "B.SilkS")
		)
		(fp_line
			(start 2.2352 -0.6096)
			(end -2.2225 -0.6096)
			(stroke
				(width 0.0254)
				(type default)
			)
			(layer "B.SilkS")
		)
		(fp_line
			(start -2.23266 -0.5969)
			(end 2.2352 -0.5969)
			(stroke
				(width 0.0254)
				(type default)
			)
			(layer "B.SilkS")
		)
		(fp_line
			(start 2.2352 -0.5842)
			(end -2.2225 -0.5842)
			(stroke
				(width 0.0254)
				(type default)
			)
			(layer "B.SilkS")
		)
		(fp_line
			(start -2.23266 -0.5715)
			(end 2.2352 -0.5715)
			(stroke
				(width 0.0254)
				(type default)
			)
			(layer "B.SilkS")
		)
		(fp_line
			(start 2.2352 -0.5588)
			(end -2.2225 -0.5588)
			(stroke
				(width 0.0254)
				(type default)
			)
			(layer "B.SilkS")
		)
		(fp_line
			(start -2.23266 -0.5461)
			(end 2.2352 -0.5461)
			(stroke
				(width 0.0254)
				(type default)
			)
			(layer "B.SilkS")
		)
		(fp_line
			(start 2.2352 -0.5334)
			(end -2.2225 -0.5334)
			(stroke
				(width 0.0254)
				(type default)
			)
			(layer "B.SilkS")
		)
		(fp_line
			(start -2.23266 -0.5207)
			(end 2.2352 -0.5207)
			(stroke
				(width 0.0254)
				(type default)
			)
			(layer "B.SilkS")
		)
		(fp_line
			(start 2.2352 -0.508)
			(end -2.2225 -0.508)
			(stroke
				(width 0.0254)
				(type default)
			)
			(layer "B.SilkS")
		)
		(fp_line
			(start -2.23266 -0.4953)
			(end 2.2352 -0.4953)
			(stroke
				(width 0.0254)
				(type default)
			)
			(layer "B.SilkS")
		)
		(fp_line
			(start 2.2352 -0.4826)
			(end -2.2225 -0.4826)
			(stroke
				(width 0.0254)
				(type default)
			)
			(layer "B.SilkS")
		)
		(fp_line
			(start -2.23266 -0.4699)
			(end 2.2352 -0.4699)
			(stroke
				(width 0.0254)
				(type default)
			)
			(layer "B.SilkS")
		)
		(fp_line
			(start 2.2352 -0.4572)
			(end -2.2225 -0.4572)
			(stroke
				(width 0.0254)
				(type default)
			)
			(layer "B.SilkS")
		)
		(fp_line
			(start -2.23266 -0.4445)
			(end 2.2352 -0.4445)
			(stroke
				(width 0.0254)
				(type default)
			)
			(layer "B.SilkS")
		)
		(fp_line
			(start 2.2352 -0.4318)
			(end -2.2225 -0.4318)
			(stroke
				(width 0.0254)
				(type default)
			)
			(layer "B.SilkS")
		)
		(fp_line
			(start -2.23266 -0.4191)
			(end 2.2352 -0.4191)
			(stroke
				(width 0.0254)
				(type default)
			)
			(layer "B.SilkS")
		)
		(fp_line
			(start 2.2352 -0.4064)
			(end -2.2225 -0.4064)
			(stroke
				(width 0.0254)
				(type default)
			)
			(layer "B.SilkS")
		)
		(fp_line
			(start -2.23266 -0.3937)
			(end 2.2352 -0.3937)
			(stroke
				(width 0.0254)
				(type default)
			)
			(layer "B.SilkS")
		)
		(fp_line
			(start 2.2352 -0.381)
			(end -2.2225 -0.381)
			(stroke
				(width 0.0254)
				(type default)
			)
			(layer "B.SilkS")
		)
		(fp_line
			(start -2.23266 -0.3683)
			(end 2.2352 -0.3683)
			(stroke
				(width 0.0254)
				(type default)
			)
			(layer "B.SilkS")
		)
		(fp_line
			(start 2.2352 -0.3556)
			(end -2.2225 -0.3556)
			(stroke
				(width 0.0254)
				(type default)
			)
			(layer "B.SilkS")
		)
		(fp_line
			(start -2.23266 -0.3429)
			(end 2.2352 -0.3429)
			(stroke
				(width 0.0254)
				(type default)
			)
			(layer "B.SilkS")
		)
		(fp_line
			(start 2.2352 -0.3302)
			(end -2.2225 -0.3302)
			(stroke
				(width 0.0254)
				(type default)
			)
			(layer "B.SilkS")
		)
		(fp_line
			(start -2.23266 -0.3175)
			(end 2.2352 -0.3175)
			(stroke
				(width 0.0254)
				(type default)
			)
			(layer "B.SilkS")
		)
		(fp_line
			(start 2.2352 -0.3048)
			(end -2.2225 -0.3048)
			(stroke
				(width 0.0254)
				(type default)
			)
			(layer "B.SilkS")
		)
		(fp_line
			(start -2.23266 -0.2921)
			(end 2.2352 -0.2921)
			(stroke
				(width 0.0254)
				(type default)
			)
			(layer "B.SilkS")
		)
		(fp_line
			(start 2.2352 -0.2794)
			(end -2.2225 -0.2794)
			(stroke
				(width 0.0254)
				(type default)
			)
			(layer "B.SilkS")
		)
		(fp_line
			(start -2.23266 -0.2667)
			(end 2.2352 -0.2667)
			(stroke
				(width 0.0254)
				(type default)
			)
			(layer "B.SilkS")
		)
		(fp_line
			(start 2.2352 -0.254)
			(end -2.2225 -0.254)
			(stroke
				(width 0.0254)
				(type default)
			)
			(layer "B.SilkS")
		)
		(fp_line
			(start -2.23266 -0.2413)
			(end 2.2352 -0.2413)
			(stroke
				(width 0.0254)
				(type default)
			)
			(layer "B.SilkS")
		)
		(fp_line
			(start 2.2352 -0.2286)
			(end -2.2225 -0.2286)
			(stroke
				(width 0.0254)
				(type default)
			)
			(layer "B.SilkS")
		)
		(fp_line
			(start -2.23266 -0.2159)
			(end 2.2352 -0.2159)
			(stroke
				(width 0.0254)
				(type default)
			)
			(layer "B.SilkS")
		)
		(fp_line
			(start 2.2352 -0.2032)
			(end -2.2225 -0.2032)
			(stroke
				(width 0.0254)
				(type default)
			)
			(layer "B.SilkS")
		)
		(fp_line
			(start -2.23266 -0.1905)
			(end 2.2352 -0.1905)
			(stroke
				(width 0.0254)
				(type default)
			)
			(layer "B.SilkS")
		)
		(fp_line
			(start 2.2352 -0.1778)
			(end -2.2225 -0.1778)
			(stroke
				(width 0.0254)
				(type default)
			)
			(layer "B.SilkS")
		)
		(fp_line
			(start -2.23266 -0.1651)
			(end 2.2352 -0.1651)
			(stroke
				(width 0.0254)
				(type default)
			)
			(layer "B.SilkS")
		)
		(fp_line
			(start 2.2352 -0.1524)
			(end -2.2225 -0.1524)
			(stroke
				(width 0.0254)
				(type default)
			)
			(layer "B.SilkS")
		)
		(fp_line
			(start -2.23266 -0.1397)
			(end 2.2352 -0.1397)
			(stroke
				(width 0.0254)
				(type default)
			)
			(layer "B.SilkS")
		)
		(fp_line
			(start 2.2352 -0.127)
			(end -2.2225 -0.127)
			(stroke
				(width 0.0254)
				(type default)
			)
			(layer "B.SilkS")
		)
		(fp_line
			(start -2.23266 -0.1143)
			(end 2.2352 -0.1143)
			(stroke
				(width 0.0254)
				(type default)
			)
			(layer "B.SilkS")
		)
		(fp_line
			(start 2.2352 -0.1016)
			(end -2.2225 -0.1016)
			(stroke
				(width 0.0254)
				(type default)
			)
			(layer "B.SilkS")
		)
		(fp_line
			(start -2.23266 -0.0889)
			(end 2.2352 -0.0889)
			(stroke
				(width 0.0254)
				(type default)
			)
			(layer "B.SilkS")
		)
		(fp_line
			(start 2.2352 -0.0762)
			(end -2.2225 -0.0762)
			(stroke
				(width 0.0254)
				(type default)
			)
			(layer "B.SilkS")
		)
		(fp_line
			(start -2.23266 -0.0635)
			(end 2.2352 -0.0635)
			(stroke
				(width 0.0254)
				(type default)
			)
			(layer "B.SilkS")
		)
		(fp_line
			(start 2.2352 -0.0508)
			(end -2.2225 -0.0508)
			(stroke
				(width 0.0254)
				(type default)
			)
			(layer "B.SilkS")
		)
		(fp_line
			(start -2.23266 -0.0381)
			(end 2.2352 -0.0381)
			(stroke
				(width 0.0254)
				(type default)
			)
			(layer "B.SilkS")
		)
		(fp_line
			(start 2.2352 -0.0254)
			(end -2.2225 -0.0254)
			(stroke
				(width 0.0254)
				(type default)
			)
			(layer "B.SilkS")
		)
		(fp_line
			(start -2.23266 -0.0127)
			(end 2.2352 -0.0127)
			(stroke
				(width 0.0254)
				(type default)
			)
			(layer "B.SilkS")
		)
		(fp_line
			(start 2.2352 0)
			(end -2.2225 0)
			(stroke
				(width 0.0254)
				(type default)
			)
			(layer "B.SilkS")
		)
		(fp_line
			(start 2.032 0)
			(end 2.794 -0.762)
			(stroke
				(width 0.2032)
				(type default)
			)
			(layer "B.SilkS")
		)
		(fp_line
			(start 2.032 0)
			(end 2.794 0.762)
			(stroke
				(width 0.2032)
				(type default)
			)
			(layer "B.SilkS")
		)
		(fp_line
			(start 1.016 0)
			(end -1.016 0)
			(stroke
				(width 0.1)
				(type default)
			)
			(layer "B.SilkS")
		)
		(fp_line
			(start -2.23266 0.0127)
			(end 2.2352 0.0127)
			(stroke
				(width 0.0254)
				(type default)
			)
			(layer "B.SilkS")
		)
		(fp_line
			(start 2.2352 0.0254)
			(end -2.2225 0.0254)
			(stroke
				(width 0.0254)
				(type default)
			)
			(layer "B.SilkS")
		)
		(fp_line
			(start -2.23266 0.0381)
			(end 2.2352 0.0381)
			(stroke
				(width 0.0254)
				(type default)
			)
			(layer "B.SilkS")
		)
		(fp_line
			(start 2.2352 0.0508)
			(end -2.2225 0.0508)
			(stroke
				(width 0.0254)
				(type default)
			)
			(layer "B.SilkS")
		)
		(fp_line
			(start -2.23266 0.0635)
			(end 2.2352 0.0635)
			(stroke
				(width 0.0254)
				(type default)
			)
			(layer "B.SilkS")
		)
		(fp_line
			(start 2.2352 0.0762)
			(end -2.2225 0.0762)
			(stroke
				(width 0.0254)
				(type default)
			)
			(layer "B.SilkS")
		)
		(fp_line
			(start -2.23266 0.0889)
			(end 2.2352 0.0889)
			(stroke
				(width 0.0254)
				(type default)
			)
			(layer "B.SilkS")
		)
		(fp_line
			(start 2.2352 0.1016)
			(end -2.2225 0.1016)
			(stroke
				(width 0.0254)
				(type default)
			)
			(layer "B.SilkS")
		)
		(fp_line
			(start -2.23266 0.1143)
			(end 2.2352 0.1143)
			(stroke
				(width 0.0254)
				(type default)
			)
			(layer "B.SilkS")
		)
		(fp_line
			(start 2.2352 0.127)
			(end -2.2225 0.127)
			(stroke
				(width 0.0254)
				(type default)
			)
			(layer "B.SilkS")
		)
		(fp_line
			(start -2.23266 0.1397)
			(end 2.2352 0.1397)
			(stroke
				(width 0.0254)
				(type default)
			)
			(layer "B.SilkS")
		)
		(fp_line
			(start 2.2352 0.1524)
			(end -2.2225 0.1524)
			(stroke
				(width 0.0254)
				(type default)
			)
			(layer "B.SilkS")
		)
		(fp_line
			(start -2.23266 0.1651)
			(end 2.2352 0.1651)
			(stroke
				(width 0.0254)
				(type default)
			)
			(layer "B.SilkS")
		)
		(fp_line
			(start 2.2352 0.1778)
			(end -2.2225 0.1778)
			(stroke
				(width 0.0254)
				(type default)
			)
			(layer "B.SilkS")
		)
		(fp_line
			(start -2.23266 0.1905)
			(end 2.2352 0.1905)
			(stroke
				(width 0.0254)
				(type default)
			)
			(layer "B.SilkS")
		)
		(fp_line
			(start 2.2352 0.2032)
			(end -2.2225 0.2032)
			(stroke
				(width 0.0254)
				(type default)
			)
			(layer "B.SilkS")
		)
		(fp_line
			(start -2.23266 0.2159)
			(end 2.2352 0.2159)
			(stroke
				(width 0.0254)
				(type default)
			)
			(layer "B.SilkS")
		)
		(fp_line
			(start 2.2352 0.2286)
			(end -2.2225 0.2286)
			(stroke
				(width 0.0254)
				(type default)
			)
			(layer "B.SilkS")
		)
		(fp_line
			(start -2.23266 0.2413)
			(end 2.2352 0.2413)
			(stroke
				(width 0.0254)
				(type default)
			)
			(layer "B.SilkS")
		)
		(fp_line
			(start 2.2352 0.254)
			(end -2.2225 0.254)
			(stroke
				(width 0.0254)
				(type default)
			)
			(layer "B.SilkS")
		)
		(fp_line
			(start -2.23266 0.2667)
			(end 2.2352 0.2667)
			(stroke
				(width 0.0254)
				(type default)
			)
			(layer "B.SilkS")
		)
		(fp_line
			(start 2.2352 0.2794)
			(end -2.2225 0.2794)
			(stroke
				(width 0.0254)
				(type default)
			)
			(layer "B.SilkS")
		)
		(fp_line
			(start -2.23266 0.2921)
			(end 2.2352 0.2921)
			(stroke
				(width 0.0254)
				(type default)
			)
			(layer "B.SilkS")
		)
		(fp_line
			(start 2.2352 0.3048)
			(end -2.2225 0.3048)
			(stroke
				(width 0.0254)
				(type default)
			)
			(layer "B.SilkS")
		)
		(fp_line
			(start -2.23266 0.3175)
			(end 2.2352 0.3175)
			(stroke
				(width 0.0254)
				(type default)
			)
			(layer "B.SilkS")
		)
		(fp_line
			(start 2.2352 0.3302)
			(end -2.2225 0.3302)
			(stroke
				(width 0.0254)
				(type default)
			)
			(layer "B.SilkS")
		)
		(fp_line
			(start -2.23266 0.3429)
			(end 2.2352 0.3429)
			(stroke
				(width 0.0254)
				(type default)
			)
			(layer "B.SilkS")
		)
		(fp_line
			(start 2.2352 0.3556)
			(end -2.2225 0.3556)
			(stroke
				(width 0.0254)
				(type default)
			)
			(layer "B.SilkS")
		)
		(fp_line
			(start -2.23266 0.3683)
			(end 2.2352 0.3683)
			(stroke
				(width 0.0254)
				(type default)
			)
			(layer "B.SilkS")
		)
		(fp_line
			(start 2.2352 0.381)
			(end -2.2225 0.381)
			(stroke
				(width 0.0254)
				(type default)
			)
			(layer "B.SilkS")
		)
		(fp_line
			(start -2.23266 0.3937)
			(end 2.2352 0.3937)
			(stroke
				(width 0.0254)
				(type default)
			)
			(layer "B.SilkS")
		)
		(fp_line
			(start 2.2352 0.4064)
			(end -2.2225 0.4064)
			(stroke
				(width 0.0254)
				(type default)
			)
			(layer "B.SilkS")
		)
		(fp_line
			(start -2.23266 0.4191)
			(end 2.2352 0.4191)
			(stroke
				(width 0.0254)
				(type default)
			)
			(layer "B.SilkS")
		)
		(fp_line
			(start 2.2352 0.4318)
			(end -2.2225 0.4318)
			(stroke
				(width 0.0254)
				(type default)
			)
			(layer "B.SilkS")
		)
		(fp_line
			(start -2.23266 0.4445)
			(end 2.2352 0.4445)
			(stroke
				(width 0.0254)
				(type default)
			)
			(layer "B.SilkS")
		)
		(fp_line
			(start 2.2352 0.4572)
			(end -2.2225 0.4572)
			(stroke
				(width 0.0254)
				(type default)
			)
			(layer "B.SilkS")
		)
		(fp_line
			(start -2.23266 0.4699)
			(end 2.2352 0.4699)
			(stroke
				(width 0.0254)
				(type default)
			)
			(layer "B.SilkS")
		)
		(fp_line
			(start 2.2352 0.4826)
			(end -2.2225 0.4826)
			(stroke
				(width 0.0254)
				(type default)
			)
			(layer "B.SilkS")
		)
		(fp_line
			(start -2.23266 0.4953)
			(end 2.2352 0.4953)
			(stroke
				(width 0.0254)
				(type default)
			)
			(layer "B.SilkS")
		)
		(fp_line
			(start 2.2352 0.508)
			(end -2.2225 0.508)
			(stroke
				(width 0.0254)
				(type default)
			)
			(layer "B.SilkS")
		)
		(fp_line
			(start -2.23266 0.5207)
			(end 2.2352 0.5207)
			(stroke
				(width 0.0254)
				(type default)
			)
			(layer "B.SilkS")
		)
		(fp_line
			(start 2.2352 0.5334)
			(end -2.2225 0.5334)
			(stroke
				(width 0.0254)
				(type default)
			)
			(layer "B.SilkS")
		)
		(fp_line
			(start -2.23266 0.5461)
			(end 2.2352 0.5461)
			(stroke
				(width 0.0254)
				(type default)
			)
			(layer "B.SilkS")
		)
		(fp_line
			(start 2.2352 0.5588)
			(end -2.2225 0.5588)
			(stroke
				(width 0.0254)
				(type default)
			)
			(layer "B.SilkS")
		)
		(fp_line
			(start -2.23266 0.5715)
			(end 2.2352 0.5715)
			(stroke
				(width 0.0254)
				(type default)
			)
			(layer "B.SilkS")
		)
		(fp_line
			(start 2.2352 0.5842)
			(end -2.2225 0.5842)
			(stroke
				(width 0.0254)
				(type default)
			)
			(layer "B.SilkS")
		)
		(fp_line
			(start -2.23266 0.5969)
			(end 2.2352 0.5969)
			(stroke
				(width 0.0254)
				(type default)
			)
			(layer "B.SilkS")
		)
		(fp_line
			(start 2.2352 0.6096)
			(end -2.2225 0.6096)
			(stroke
				(width 0.0254)
				(type default)
			)
			(layer "B.SilkS")
		)
		(fp_line
			(start -2.23266 0.6223)
			(end 2.2352 0.6223)
			(stroke
				(width 0.0254)
				(type default)
			)
			(layer "B.SilkS")
		)
		(fp_line
			(start 2.2352 0.635)
			(end -2.2225 0.635)
			(stroke
				(width 0.0254)
				(type default)
			)
			(layer "B.SilkS")
		)
		(fp_line
			(start -2.23266 0.6477)
			(end 2.2352 0.6477)
			(stroke
				(width 0.0254)
				(type default)
			)
			(layer "B.SilkS")
		)
		(fp_line
			(start 2.2352 0.6604)
			(end -2.2225 0.6604)
			(stroke
				(width 0.0254)
				(type default)
			)
			(layer "B.SilkS")
		)
		(fp_line
			(start -2.23266 0.6731)
			(end 2.2352 0.6731)
			(stroke
				(width 0.0254)
				(type default)
			)
			(layer "B.SilkS")
		)
		(fp_line
			(start 2.2352 0.6858)
			(end -2.2225 0.6858)
			(stroke
				(width 0.0254)
				(type default)
			)
			(layer "B.SilkS")
		)
		(fp_line
			(start -2.23266 0.6985)
			(end 2.2352 0.6985)
			(stroke
				(width 0.0254)
				(type default)
			)
			(layer "B.SilkS")
		)
		(fp_line
			(start 2.2352 0.7112)
			(end -2.2225 0.7112)
			(stroke
				(width 0.0254)
				(type default)
			)
			(layer "B.SilkS")
		)
		(fp_line
			(start -2.23266 0.7239)
			(end 2.2352 0.7239)
			(stroke
				(width 0.0254)
				(type default)
			)
			(layer "B.SilkS")
		)
		(fp_line
			(start 2.2352 0.7366)
			(end -2.2225 0.7366)
			(stroke
				(width 0.0254)
				(type default)
			)
			(layer "B.SilkS")
		)
		(fp_line
			(start -2.23266 0.7493)
			(end 2.2352 0.7493)
			(stroke
				(width 0.0254)
				(type default)
			)
			(layer "B.SilkS")
		)
		(fp_line
			(start 2.2352 0.762)
			(end -2.2225 0.762)
			(stroke
				(width 0.0254)
				(type default)
			)
			(layer "B.SilkS")
		)
		(fp_line
			(start -2.23266 0.7747)
			(end 2.2352 0.7747)
			(stroke
				(width 0.0254)
				(type default)
			)
			(layer "B.SilkS")
		)
		(fp_line
			(start 2.2352 0.7874)
			(end -2.2225 0.7874)
			(stroke
				(width 0.0254)
				(type default)
			)
			(layer "B.SilkS")
		)
		(fp_line
			(start -2.23266 0.8001)
			(end 2.2352 0.8001)
			(stroke
				(width 0.0254)
				(type default)
			)
			(layer "B.SilkS")
		)
		(fp_line
			(start 2.2352 0.8128)
			(end -2.2225 0.8128)
			(stroke
				(width 0.0254)
				(type default)
			)
			(layer "B.SilkS")
		)
		(fp_line
			(start -2.23266 0.8255)
			(end 2.2352 0.8255)
			(stroke
				(width 0.0254)
				(type default)
			)
			(layer "B.SilkS")
		)
		(fp_line
			(start 2.2352 0.8382)
			(end -2.2225 0.8382)
			(stroke
				(width 0.0254)
				(type default)
			)
			(layer "B.SilkS")
		)
		(fp_line
			(start -2.23266 0.8509)
			(end 2.2352 0.8509)
			(stroke
				(width 0.0254)
				(type default)
			)
			(layer "B.SilkS")
		)
		(fp_line
			(start 2.2352 0.8636)
			(end -2.2225 0.8636)
			(stroke
				(width 0.0254)
				(type default)
			)
			(layer "B.SilkS")
		)
		(fp_line
			(start -2.23266 0.8763)
			(end 2.2352 0.8763)
			(stroke
				(width 0.0254)
				(type default)
			)
			(layer "B.SilkS")
		)
		(fp_line
			(start 2.2352 0.889)
			(end -2.2225 0.889)
			(stroke
				(width 0.0254)
				(type default)
			)
			(layer "B.SilkS")
		)
		(fp_line
			(start -2.23266 0.9017)
			(end 2.2352 0.9017)
			(stroke
				(width 0.0254)
				(type default)
			)
			(layer "B.SilkS")
		)
		(fp_line
			(start 2.2352 0.9144)
			(end -2.2225 0.9144)
			(stroke
				(width 0.0254)
				(type default)
			)
			(layer "B.SilkS")
		)
		(fp_line
			(start -2.23266 0.9271)
			(end 2.2352 0.9271)
			(stroke
				(width 0.0254)
				(type default)
			)
			(layer "B.SilkS")
		)
		(fp_line
			(start 2.2352 0.9398)
			(end -2.2225 0.9398)
			(stroke
				(width 0.0254)
				(type default)
			)
			(layer "B.SilkS")
		)
		(fp_line
			(start -2.23266 0.9525)
			(end 2.2352 0.9525)
			(stroke
				(width 0.0254)
				(type default)
			)
			(layer "B.SilkS")
		)
		(fp_line
			(start 2.2352 0.9652)
			(end -2.2225 0.9652)
			(stroke
				(width 0.0254)
				(type default)
			)
			(layer "B.SilkS")
		)
		(fp_line
			(start -2.23266 0.9779)
			(end 2.2352 0.9779)
			(stroke
				(width 0.0254)
				(type default)
			)
			(layer "B.SilkS")
		)
		(fp_line
			(start 2.2352 0.9906)
			(end -2.2225 0.9906)
			(stroke
				(width 0.0254)
				(type default)
			)
			(layer "B.SilkS")
		)
		(fp_line
			(start -2.23266 1.0033)
			(end 2.2352 1.0033)
			(stroke
				(width 0.0254)
				(type default)
			)
			(layer "B.SilkS")
		)
		(fp_line
			(start 2.2352 1.016)
			(end -2.2225 1.016)
			(stroke
				(width 0.0254)
				(type default)
			)
			(layer "B.SilkS")
		)
		(fp_line
			(start 0 1.016)
			(end 0 -1.016)
			(stroke
				(width 0.1)
				(type default)
			)
			(layer "B.SilkS")
		)
		(fp_line
			(start -2.23266 1.0287)
			(end 2.2352 1.0287)
			(stroke
				(width 0.0254)
				(type default)
			)
			(layer "B.SilkS")
		)
		(fp_line
			(start 2.2352 1.0414)
			(end -2.2225 1.0414)
			(stroke
				(width 0.0254)
				(type default)
			)
			(layer "B.SilkS")
		)
		(fp_line
			(start -2.23266 1.0541)
			(end 2.2352 1.0541)
			(stroke
				(width 0.0254)
				(type default)
			)
			(layer "B.SilkS")
		)
		(fp_line
			(start 2.2352 1.0668)
			(end -2.2225 1.0668)
			(stroke
				(width 0.0254)
				(type default)
			)
			(layer "B.SilkS")
		)
		(fp_line
			(start -2.23266 1.0795)
			(end 2.2352 1.0795)
			(stroke
				(width 0.0254)
				(type default)
			)
			(layer "B.SilkS")
		)
		(fp_line
			(start 2.2352 1.0922)
			(end -2.2225 1.0922)
			(stroke
				(width 0.0254)
				(type default)
			)
			(layer "B.SilkS")
		)
		(fp_line
			(start -2.23266 1.1049)
			(end 2.2352 1.1049)
			(stroke
				(width 0.0254)
				(type default)
			)
			(layer "B.SilkS")
		)
		(fp_line
			(start 2.2352 1.1176)
			(end -2.2225 1.1176)
			(stroke
				(width 0.0254)
				(type default)
			)
			(layer "B.SilkS")
		)
		(fp_line
			(start -2.23266 1.1303)
			(end 2.2352 1.1303)
			(stroke
				(width 0.0254)
				(type default)
			)
			(layer "B.SilkS")
		)
		(fp_line
			(start 2.2352 1.143)
			(end -2.2225 1.143)
			(stroke
				(width 0.0254)
				(type default)
			)
			(layer "B.SilkS")
		)
		(fp_line
			(start -2.23266 1.1557)
			(end 2.2352 1.1557)
			(stroke
				(width 0.0254)
				(type default)
			)
			(layer "B.SilkS")
		)
		(fp_line
			(start 2.2352 1.1684)
			(end -2.2225 1.1684)
			(stroke
				(width 0.0254)
				(type default)
			)
			(layer "B.SilkS")
		)
		(fp_line
			(start -2.23266 1.1811)
			(end 2.2352 1.1811)
			(stroke
				(width 0.0254)
				(type default)
			)
			(layer "B.SilkS")
		)
		(fp_line
			(start 2.2352 1.1938)
			(end -2.2225 1.1938)
			(stroke
				(width 0.0254)
				(type default)
			)
			(layer "B.SilkS")
		)
		(fp_line
			(start -2.23266 1.2065)
			(end 2.2352 1.2065)
			(stroke
				(width 0.0254)
				(type default)
			)
			(layer "B.SilkS")
		)
		(fp_line
			(start 2.2352 1.2192)
			(end -2.2225 1.2192)
			(stroke
				(width 0.0254)
				(type default)
			)
			(layer "B.SilkS")
		)
		(fp_line
			(start -2.23266 1.2319)
			(end 2.2352 1.2319)
			(stroke
				(width 0.0254)
				(type default)
			)
			(layer "B.SilkS")
		)
		(fp_line
			(start 2.2352 1.2446)
			(end -2.2225 1.2446)
			(stroke
				(width 0.0254)
				(type default)
			)
			(layer "B.SilkS")
		)
		(fp_line
			(start -2.23266 1.2573)
			(end 2.2352 1.2573)
			(stroke
				(width 0.0254)
				(type default)
			)
			(layer "B.SilkS")
		)
		(fp_line
			(start 2.2352 1.27)
			(end -2.2225 1.27)
			(stroke
				(width 0.0254)
				(type default)
			)
			(layer "B.SilkS")
		)
		(fp_line
			(start -2.23266 1.2827)
			(end 2.2352 1.2827)
			(stroke
				(width 0.0254)
				(type default)
			)
			(layer "B.SilkS")
		)
		(fp_line
			(start 2.2352 1.2954)
			(end -2.2225 1.2954)
			(stroke
				(width 0.0254)
				(type default)
			)
			(layer "B.SilkS")
		)
		(fp_line
			(start -2.23266 1.3081)
			(end 2.2352 1.3081)
			(stroke
				(width 0.0254)
				(type default)
			)
			(layer "B.SilkS")
		)
		(fp_line
			(start 2.2352 1.3208)
			(end -2.2225 1.3208)
			(stroke
				(width 0.0254)
				(type default)
			)
			(layer "B.SilkS")
		)
		(fp_line
			(start -2.23266 1.3335)
			(end 2.2352 1.3335)
			(stroke
				(width 0.0254)
				(type default)
			)
			(layer "B.SilkS")
		)
		(fp_line
			(start 2.2352 1.3462)
			(end -2.2225 1.3462)
			(stroke
				(width 0.0254)
				(type default)
			)
			(layer "B.SilkS")
		)
		(fp_line
			(start -2.23266 1.3589)
			(end 2.2352 1.3589)
			(stroke
				(width 0.0254)
				(type default)
			)
			(layer "B.SilkS")
		)
		(fp_line
			(start 2.2352 1.3716)
			(end -2.2225 1.3716)
			(stroke
				(width 0.0254)
				(type default)
			)
			(layer "B.SilkS")
		)
		(fp_line
			(start -2.23266 1.3843)
			(end 2.2352 1.3843)
			(stroke
				(width 0.0254)
				(type default)
			)
			(layer "B.SilkS")
		)
		(fp_line
			(start 2.2352 1.397)
			(end -2.2225 1.397)
			(stroke
				(width 0.0254)
				(type default)
			)
			(layer "B.SilkS")
		)
		(fp_line
			(start -2.23266 1.4097)
			(end 2.2352 1.4097)
			(stroke
				(width 0.0254)
				(type default)
			)
			(layer "B.SilkS")
		)
		(fp_line
			(start 2.2352 1.4224)
			(end -2.2225 1.4224)
			(stroke
				(width 0.0254)
				(type default)
			)
			(layer "B.SilkS")
		)
		(fp_line
			(start -2.23266 1.4351)
			(end 2.2352 1.4351)
			(stroke
				(width 0.0254)
				(type default)
			)
			(layer "B.SilkS")
		)
		(fp_line
			(start 2.2352 1.4478)
			(end -2.2225 1.4478)
			(stroke
				(width 0.0254)
				(type default)
			)
			(layer "B.SilkS")
		)
		(fp_line
			(start -2.23266 1.4605)
			(end 2.2352 1.4605)
			(stroke
				(width 0.0254)
				(type default)
			)
			(layer "B.SilkS")
		)
		(fp_line
			(start 2.2352 1.4732)
			(end -2.2225 1.4732)
			(stroke
				(width 0.0254)
				(type default)
			)
			(layer "B.SilkS")
		)
		(fp_line
			(start -2.23266 1.4859)
			(end 2.2352 1.4859)
			(stroke
				(width 0.0254)
				(type default)
			)
			(layer "B.SilkS")
		)
		(fp_line
			(start 2.2352 1.4986)
			(end -2.2225 1.4986)
			(stroke
				(width 0.0254)
				(type default)
			)
			(layer "B.SilkS")
		)
		(fp_line
			(start -2.23266 1.5113)
			(end 2.2352 1.5113)
			(stroke
				(width 0.0254)
				(type default)
			)
			(layer "B.SilkS")
		)
		(fp_line
			(start 2.2352 1.524)
			(end -2.2225 1.524)
			(stroke
				(width 0.0254)
				(type default)
			)
			(layer "B.SilkS")
		)
		(fp_line
			(start -2.23266 1.5367)
			(end 2.2352 1.5367)
			(stroke
				(width 0.0254)
				(type default)
			)
			(layer "B.SilkS")
		)
		(fp_line
			(start 2.2352 1.5494)
			(end -2.2225 1.5494)
			(stroke
				(width 0.0254)
				(type default)
			)
			(layer "B.SilkS")
		)
		(fp_line
			(start -2.23266 1.5621)
			(end 2.2352 1.5621)
			(stroke
				(width 0.0254)
				(type default)
			)
			(layer "B.SilkS")
		)
		(fp_line
			(start 2.2352 1.5748)
			(end -2.2225 1.5748)
			(stroke
				(width 0.0254)
				(type default)
			)
			(layer "B.SilkS")
		)
		(fp_line
			(start -2.23266 1.5875)
			(end 2.2352 1.5875)
			(stroke
				(width 0.0254)
				(type default)
			)
			(layer "B.SilkS")
		)
		(fp_line
			(start 2.2352 1.6002)
			(end -2.2225 1.6002)
			(stroke
				(width 0.0254)
				(type default)
			)
			(layer "B.SilkS")
		)
		(fp_line
			(start -2.23266 1.6129)
			(end 2.2352 1.6129)
			(stroke
				(width 0.0254)
				(type default)
			)
			(layer "B.SilkS")
		)
		(fp_line
			(start 2.2352 1.6256)
			(end -2.2225 1.6256)
			(stroke
				(width 0.0254)
				(type default)
			)
			(layer "B.SilkS")
		)
		(fp_line
			(start -2.23266 1.6383)
			(end 2.2352 1.6383)
			(stroke
				(width 0.0254)
				(type default)
			)
			(layer "B.SilkS")
		)
		(fp_line
			(start 2.2352 1.651)
			(end -2.2225 1.651)
			(stroke
				(width 0.0254)
				(type default)
			)
			(layer "B.SilkS")
		)
		(fp_line
			(start -2.159 1.651)
			(end 2.794 1.651)
			(stroke
				(width 0.2032)
				(type default)
			)
			(layer "B.SilkS")
		)
		(fp_line
			(start -2.23266 1.6637)
			(end 2.2352 1.6637)
			(stroke
				(width 0.0254)
				(type default)
			)
			(layer "B.SilkS")
		)
		(fp_line
			(start 2.2352 1.6764)
			(end -2.2225 1.6764)
			(stroke
				(width 0.0254)
				(type default)
			)
			(layer "B.SilkS")
		)
		(fp_line
			(start -2.23266 1.6891)
			(end 2.2352 1.6891)
			(stroke
				(width 0.0254)
				(type default)
			)
			(layer "B.SilkS")
		)
		(fp_line
			(start 2.2352 1.7018)
			(end -2.2225 1.7018)
			(stroke
				(width 0.0254)
				(type default)
			)
			(layer "B.SilkS")
		)
		(fp_line
			(start -2.23266 1.7145)
			(end 2.2352 1.7145)
			(stroke
				(width 0.0254)
				(type default)
			)
			(layer "B.SilkS")
		)
		(fp_line
			(start 2.2352 1.7272)
			(end -2.2225 1.7272)
			(stroke
				(width 0.0254)
				(type default)
			)
			(layer "B.SilkS")
		)
		(fp_line
			(start -2.23266 1.7399)
			(end 2.2352 1.7399)
			(stroke
				(width 0.0254)
				(type default)
			)
			(layer "B.SilkS")
		)
		(fp_line
			(start 2.2352 1.7526)
			(end -2.2225 1.7526)
			(stroke
				(width 0.0254)
				(type default)
			)
			(layer "B.SilkS")
		)
		(fp_line
			(start -2.23266 1.7653)
			(end 2.2352 1.7653)
			(stroke
				(width 0.0254)
				(type default)
			)
			(layer "B.SilkS")
		)
		(fp_line
			(start 2.2352 1.778)
			(end -2.2225 1.778)
			(stroke
				(width 0.0254)
				(type default)
			)
			(layer "B.SilkS")
		)
		(fp_line
			(start -2.23266 1.7907)
			(end 2.2352 1.7907)
			(stroke
				(width 0.0254)
				(type default)
			)
			(layer "B.SilkS")
		)
		(fp_line
			(start 2.2352 1.8034)
			(end -2.2225 1.8034)
			(stroke
				(width 0.0254)
				(type default)
			)
			(layer "B.SilkS")
		)
		(fp_line
			(start -2.23266 1.8161)
			(end 2.2352 1.8161)
			(stroke
				(width 0.0254)
				(type default)
			)
			(layer "B.SilkS")
		)
		(fp_line
			(start -2.23266 1.8288)
			(end 2.2352 1.8288)
			(stroke
				(width 0.0254)
				(type default)
			)
			(layer "B.SilkS")
		)
		(fp_line
			(start 2.2352 1.8415)
			(end 2.2352 -1.8415)
			(stroke
				(width 0.0254)
				(type default)
			)
			(layer "B.SilkS")
		)
		(fp_line
			(start -2.2352 1.8415)
			(end 2.2352 1.8415)
			(stroke
				(width 0.0254)
				(type default)
			)
			(layer "B.SilkS")
		)
		(fp_line
			(start 2.794 4.064)
			(end 2.794 1.651)
			(stroke
				(width 0.508)
				(type default)
			)
			(layer "B.SilkS")
		)
		(fp_poly
			(pts
				(xy 2.794 3.81) (xy -2.794 3.81) (xy -2.794 -3.81) (xy 2.794 -3.81)
			)
			(stroke
				(width 0)
				(type default)
			)
			(fill no)
			(layer "B.CrtYd")
		)
		(fp_poly
			(pts
				(xy 2.794 -3.81) (xy -2.794 -3.81) (xy -2.794 3.81) (xy 2.794 3.81)
			)
			(stroke
				(width 0)
				(type default)
			)
			(fill no)
			(layer "B.Fab")
		)
		(pad "1" smd rect
			(at 1.95072 2.8194 270)
			(size 0.3556 1.524)
			(layers "B.Cu" "B.Mask" "B.Paste")
			(net "PCIE_RST_R_N")
		)
		(pad "2" smd rect
			(at 1.30048 2.8194 270)
			(size 0.3556 1.524)
			(layers "B.Cu" "B.Mask" "B.Paste")
			(net "UART_COMP_R_TX")
		)
		(pad "3" smd rect
			(at 0.65024 2.8194 270)
			(size 0.3556 1.524)
			(layers "B.Cu" "B.Mask" "B.Paste")
			(net "UART_COMP_OUT_TX")
		)
		(pad "4" smd rect
			(at 0 2.8194 270)
			(size 0.3556 1.524)
			(layers "B.Cu" "B.Mask" "B.Paste")
			(net "PCIE_RST_R_N")
		)
		(pad "5" smd rect
			(at -0.65024 2.8194 270)
			(size 0.3556 1.524)
			(layers "B.Cu" "B.Mask" "B.Paste")
			(net "UART_COMP_IN_RX_AND_R")
		)
		(pad "6" smd rect
			(at -1.30048 2.8194 270)
			(size 0.3556 1.524)
			(layers "B.Cu" "B.Mask" "B.Paste")
			(net "UART_COMP_R_RX")
		)
		(pad "7" smd rect
			(at -1.95072 2.8194 270)
			(size 0.3556 1.524)
			(layers "B.Cu" "B.Mask" "B.Paste")
			(net "GND")
		)
		(pad "8" smd rect
			(at -1.95072 -2.8194 270)
			(size 0.3556 1.524)
			(layers "B.Cu" "B.Mask" "B.Paste")
			(net "UART_EXP_BMC_TX")
		)
		(pad "9" smd rect
			(at -1.30048 -2.8194 270)
			(size 0.3556 1.524)
			(layers "B.Cu" "B.Mask" "B.Paste")
			(net "UART_SDB_TX_R")
		)
		(pad "10" smd rect
			(at -0.65024 -2.8194 270)
			(size 0.3556 1.524)
			(layers "B.Cu" "B.Mask" "B.Paste")
			(net "EXP_UART_EN_R")
		)
		(pad "11" smd rect
			(at 0 -2.8194 270)
			(size 0.3556 1.524)
			(layers "B.Cu" "B.Mask" "B.Paste")
			(net "UART_SDB_RX")
		)
		(pad "12" smd rect
			(at 0.65024 -2.8194 270)
			(size 0.3556 1.524)
			(layers "B.Cu" "B.Mask" "B.Paste")
			(net "UART_EXP_BMC_RX")
		)
		(pad "13" smd rect
			(at 1.30048 -2.8194 270)
			(size 0.3556 1.524)
			(layers "B.Cu" "B.Mask" "B.Paste")
			(net "EXP_UART_EN_R")
		)
		(pad "14" smd rect
			(at 1.95072 -2.8194 270)
			(size 0.3556 1.524)
			(layers "B.Cu" "B.Mask" "B.Paste")
			(net "P3V3_STBY")
		)
	)
	(footprint ""
		(layer "B.Cu")
		(at 47.4472 -151.2824)
		(property "Reference" "TP190"
			(at 0 0 0)
			(layer "B.SilkS")
			(hide yes)
			(effects
				(font
					(size 1.27 1.27)
				)
				(justify mirror)
			)
		)
		(property "Value" "TPAD28-2-GP"
			(at 0.0127 -1.6637 0)
			(unlocked yes)
			(layer "B.Fab")
			(hide yes)
			(effects
				(font
					(size 1.016 1.016)
					(thickness 0.1524)
				)
				(justify mirror)
			)
		)
		(property "Device Type" "TPAD28"
			(at 0.0127 -3.1877 0)
			(unlocked yes)
			(layer "B.Fab")
			(hide yes)
			(effects
				(font
					(size 1.016 1.016)
					(thickness 0.1524)
				)
				(justify mirror)
			)
		)
		(duplicate_pad_numbers_are_jumpers no)
		(fp_poly
			(pts
				(arc
					(start 0.3556 0)
					(mid -0.3556 0)
					(end 0.3556 0)
				)
			)
			(stroke
				(width 0)
				(type default)
			)
			(fill no)
			(layer "B.CrtYd")
		)
		(fp_poly
			(pts
				(arc
					(start 0.6096 0)
					(mid -0.6096 0)
					(end 0.6096 0)
				)
			)
			(stroke
				(width 0)
				(type default)
			)
			(fill no)
			(layer "B.Fab")
		)
		(pad "1" smd circle
			(at 0 0 180)
			(size 0.7112 0.7112)
			(layers "B.Cu" "B.Mask" "B.Paste")
			(net "TP_BMC_GPIOL4")
		)
	)
	(footprint ""
		(layer "B.Cu")
		(at 33.9344 -156.464)
		(property "Reference" "R776"
			(at 0 0 0)
			(layer "B.SilkS")
			(hide yes)
			(effects
				(font
					(size 1.27 1.27)
				)
				(justify mirror)
			)
		)
		(property "Value" "1KR2F-3-GP"
			(at -0.064008 -3.993896 0)
			(unlocked yes)
			(layer "B.Fab")
			(hide yes)
			(effects
				(font
					(size 1.016 1.016)
					(thickness 0.1524)
				)
				(justify mirror)
			)
		)
		(property "Device Type" "R402H16"
			(at -0.064008 -5.517896 0)
			(unlocked yes)
			(layer "B.Fab")
			(hide yes)
			(effects
				(font
					(size 1.016 1.016)
					(thickness 0.1524)
				)
				(justify mirror)
			)
		)
		(duplicate_pad_numbers_are_jumpers no)
		(fp_line
			(start -0.508 -0.9398)
			(end 0.508 -0.9398)
			(stroke
				(width 0.1524)
				(type default)
			)
			(layer "B.SilkS")
		)
		(fp_line
			(start 0.508 -0.9398)
			(end 0.508 0.9398)
			(stroke
				(width 0.1524)
				(type default)
			)
			(layer "B.SilkS")
		)
		(fp_rect
			(start 0.508 0.9398)
			(end -0.508 -0.9398)
			(stroke
				(width 0)
				(type default)
			)
			(fill no)
			(layer "B.CrtYd")
		)
		(fp_rect
			(start 0.508 0.9398)
			(end -0.508 -0.9398)
			(stroke
				(width 0)
				(type default)
			)
			(fill no)
			(layer "B.Fab")
		)
		(pad "1" smd custom
			(at 0 -0.4445 180)
			(size 0.1397 0.1397)
			(layers "B.Cu" "B.Mask" "B.Paste")
			(net "P1V2_STBY")
			(options
				(clearance outline)
				(anchor circle)
			)
			(primitives
				(gr_poly
					(pts
						(arc
							(start -0.1778 0.2794)
							(mid -0.249642 0.249642)
							(end -0.2794 0.1778)
						)
						(arc
							(start -0.2794 -0.1778)
							(mid -0.249642 -0.249642)
							(end -0.1778 -0.2794)
						)
						(arc
							(start 0.1778 -0.2794)
							(mid 0.249642 -0.249642)
							(end 0.2794 -0.1778)
						)
						(arc
							(start 0.2794 0.1778)
							(mid 0.249642 0.249642)
							(end 0.1778 0.2794)
						)
					)
					(width 0)
					(fill yes)
				)
			)
		)
		(pad "2" smd custom
			(at 0 0.4445 180)
			(size 0.1397 0.1397)
			(layers "B.Cu" "B.Mask" "B.Paste")
			(net "ADC_P1V2_STBY")
			(options
				(clearance outline)
				(anchor circle)
			)
			(primitives
				(gr_poly
					(pts
						(arc
							(start -0.1778 0.2794)
							(mid -0.249642 0.249642)
							(end -0.2794 0.1778)
						)
						(arc
							(start -0.2794 -0.1778)
							(mid -0.249642 -0.249642)
							(end -0.1778 -0.2794)
						)
						(arc
							(start 0.1778 -0.2794)
							(mid 0.249642 -0.249642)
							(end 0.2794 -0.1778)
						)
						(arc
							(start 0.2794 0.1778)
							(mid 0.249642 0.249642)
							(end 0.1778 0.2794)
						)
					)
					(width 0)
					(fill yes)
				)
			)
		)
	)
	(footprint ""
		(layer "B.Cu")
		(at 111.6838 -9.6012 90)
		(property "Reference" "R461"
			(at 0 0 90)
			(layer "B.SilkS")
			(hide yes)
			(effects
				(font
					(size 1.27 1.27)
				)
				(justify mirror)
			)
		)
		(property "Value" "100KR2J-4-GP"
			(at -0.064008 -3.993896 90)
			(unlocked yes)
			(layer "B.Fab")
			(hide yes)
			(effects
				(font
					(size 1.016 1.016)
					(thickness 0.1524)
				)
				(justify mirror)
			)
		)
		(property "Device Type" "R402H15"
			(at -0.064008 -5.517896 90)
			(unlocked yes)
			(layer "B.Fab")
			(hide yes)
			(effects
				(font
					(size 1.016 1.016)
					(thickness 0.1524)
				)
				(justify mirror)
			)
		)
		(duplicate_pad_numbers_are_jumpers no)
		(fp_line
			(start 0.508 -0.9398)
			(end 0.508 0.9398)
			(stroke
				(width 0.1524)
				(type default)
			)
			(layer "B.SilkS")
		)
		(fp_line
			(start -0.508 -0.9398)
			(end 0.508 -0.9398)
			(stroke
				(width 0.1524)
				(type default)
			)
			(layer "B.SilkS")
		)
		(fp_rect
			(start 0.508 0.9398)
			(end -0.508 -0.9398)
			(stroke
				(width 0)
				(type default)
			)
			(fill no)
			(layer "B.CrtYd")
		)
		(fp_rect
			(start 0.508 0.9398)
			(end -0.508 -0.9398)
			(stroke
				(width 0)
				(type default)
			)
			(fill no)
			(layer "B.Fab")
		)
		(pad "1" smd custom
			(at 0 -0.4445 270)
			(size 0.1397 0.1397)
			(layers "B.Cu" "B.Mask" "B.Paste")
			(net "MB0_VCAP_R")
			(options
				(clearance outline)
				(anchor circle)
			)
			(primitives
				(gr_poly
					(pts
						(arc
							(start -0.1778 0.2794)
							(mid -0.249642 0.249642)
							(end -0.2794 0.1778)
						)
						(arc
							(start -0.2794 -0.1778)
							(mid -0.249642 -0.249642)
							(end -0.1778 -0.2794)
						)
						(arc
							(start 0.1778 -0.2794)
							(mid 0.249642 -0.249642)
							(end 0.2794 -0.1778)
						)
						(arc
							(start 0.2794 0.1778)
							(mid 0.249642 0.249642)
							(end 0.1778 0.2794)
						)
					)
					(width 0)
					(fill yes)
				)
			)
		)
		(pad "2" smd custom
			(at 0 0.4445 270)
			(size 0.1397 0.1397)
			(layers "B.Cu" "B.Mask" "B.Paste")
			(net "MB0_ISTART_R")
			(options
				(clearance outline)
				(anchor circle)
			)
			(primitives
				(gr_poly
					(pts
						(arc
							(start -0.1778 0.2794)
							(mid -0.249642 0.249642)
							(end -0.2794 0.1778)
						)
						(arc
							(start -0.2794 -0.1778)
							(mid -0.249642 -0.249642)
							(end -0.1778 -0.2794)
						)
						(arc
							(start 0.1778 -0.2794)
							(mid 0.249642 -0.249642)
							(end 0.2794 -0.1778)
						)
						(arc
							(start 0.2794 0.1778)
							(mid 0.249642 0.249642)
							(end 0.1778 0.2794)
						)
					)
					(width 0)
					(fill yes)
				)
			)
		)
	)
	(footprint ""
		(layer "B.Cu")
		(at 207.014064 -88.090756 180)
		(property "Reference" "R802"
			(at 0 0 0)
			(layer "B.SilkS")
			(hide yes)
			(effects
				(font
					(size 1.27 1.27)
				)
				(justify mirror)
			)
		)
		(property "Value" "4K7R2F-GP"
			(at -0.064008 -3.993896 180)
			(unlocked yes)
			(layer "B.Fab")
			(hide yes)
			(effects
				(font
					(size 1.016 1.016)
					(thickness 0.1524)
				)
				(justify mirror)
			)
		)
		(property "Device Type" "R402H16"
			(at -0.064008 -5.517896 180)
			(unlocked yes)
			(layer "B.Fab")
			(hide yes)
			(effects
				(font
					(size 1.016 1.016)
					(thickness 0.1524)
				)
				(justify mirror)
			)
		)
		(duplicate_pad_numbers_are_jumpers no)
		(fp_line
			(start 0.508 -0.9398)
			(end 0.508 0.9398)
			(stroke
				(width 0.1524)
				(type default)
			)
			(layer "B.SilkS")
		)
		(fp_line
			(start -0.508 -0.9398)
			(end 0.508 -0.9398)
			(stroke
				(width 0.1524)
				(type default)
			)
			(layer "B.SilkS")
		)
		(fp_rect
			(start 0.508 0.9398)
			(end -0.508 -0.9398)
			(stroke
				(width 0)
				(type default)
			)
			(fill no)
			(layer "B.CrtYd")
		)
		(fp_rect
			(start 0.508 0.9398)
			(end -0.508 -0.9398)
			(stroke
				(width 0)
				(type default)
			)
			(fill no)
			(layer "B.Fab")
		)
		(pad "1" smd custom
			(at 0 -0.4445)
			(size 0.1397 0.1397)
			(layers "B.Cu" "B.Mask" "B.Paste")
			(net "Q21_G")
			(options
				(clearance outline)
				(anchor circle)
			)
			(primitives
				(gr_poly
					(pts
						(arc
							(start -0.1778 0.2794)
							(mid -0.249642 0.249642)
							(end -0.2794 0.1778)
						)
						(arc
							(start -0.2794 -0.1778)
							(mid -0.249642 -0.249642)
							(end -0.1778 -0.2794)
						)
						(arc
							(start 0.1778 -0.2794)
							(mid 0.249642 -0.249642)
							(end 0.2794 -0.1778)
						)
						(arc
							(start 0.2794 0.1778)
							(mid 0.249642 0.249642)
							(end 0.1778 0.2794)
						)
					)
					(width 0)
					(fill yes)
				)
			)
		)
		(pad "2" smd custom
			(at 0 0.4445)
			(size 0.1397 0.1397)
			(layers "B.Cu" "B.Mask" "B.Paste")
			(net "P3V3_STBY")
			(options
				(clearance outline)
				(anchor circle)
			)
			(primitives
				(gr_poly
					(pts
						(arc
							(start -0.1778 0.2794)
							(mid -0.249642 0.249642)
							(end -0.2794 0.1778)
						)
						(arc
							(start -0.2794 -0.1778)
							(mid -0.249642 -0.249642)
							(end -0.1778 -0.2794)
						)
						(arc
							(start 0.1778 -0.2794)
							(mid 0.249642 -0.249642)
							(end 0.2794 -0.1778)
						)
						(arc
							(start 0.2794 0.1778)
							(mid 0.249642 0.249642)
							(end 0.1778 0.2794)
						)
					)
					(width 0)
					(fill yes)
				)
			)
		)
	)
	(footprint ""
		(layer "B.Cu")
		(at 56.9722 -140.335)
		(property "Reference" "TP76"
			(at 0 0 0)
			(layer "B.SilkS")
			(hide yes)
			(effects
				(font
					(size 1.27 1.27)
				)
				(justify mirror)
			)
		)
		(property "Value" "TPAD28-2-GP"
			(at 0.0127 -1.6637 0)
			(unlocked yes)
			(layer "B.Fab")
			(hide yes)
			(effects
				(font
					(size 1.016 1.016)
					(thickness 0.1524)
				)
				(justify mirror)
			)
		)
		(property "Device Type" "TPAD28"
			(at 0.0127 -3.1877 0)
			(unlocked yes)
			(layer "B.Fab")
			(hide yes)
			(effects
				(font
					(size 1.016 1.016)
					(thickness 0.1524)
				)
				(justify mirror)
			)
		)
		(duplicate_pad_numbers_are_jumpers no)
		(fp_poly
			(pts
				(arc
					(start 0.3556 0)
					(mid -0.3556 0)
					(end 0.3556 0)
				)
			)
			(stroke
				(width 0)
				(type default)
			)
			(fill no)
			(layer "B.CrtYd")
		)
		(fp_poly
			(pts
				(arc
					(start 0.6096 0)
					(mid -0.6096 0)
					(end 0.6096 0)
				)
			)
			(stroke
				(width 0)
				(type default)
			)
			(fill no)
			(layer "B.Fab")
		)
		(pad "1" smd circle
			(at 0 0 180)
			(size 0.7112 0.7112)
			(layers "B.Cu" "B.Mask" "B.Paste")
			(net "TP_BMC_GPIOI3")
		)
	)
	(footprint ""
		(layer "B.Cu")
		(at 54.102 -132.08 180)
		(property "Reference" "C115"
			(at 0 0 0)
			(layer "B.SilkS")
			(hide yes)
			(effects
				(font
					(size 1.27 1.27)
				)
				(justify mirror)
			)
		)
		(property "Value" "SC10U6D3V3KX-1-GP"
			(at 0 -2.8194 180)
			(unlocked yes)
			(layer "B.Fab")
			(hide yes)
			(effects
				(font
					(size 1.016 1.016)
					(thickness 0.1524)
				)
				(justify mirror)
			)
		)
		(property "Device Type" "C603H40"
			(at 0 -4.3434 180)
			(unlocked yes)
			(layer "B.Fab")
			(hide yes)
			(effects
				(font
					(size 1.016 1.016)
					(thickness 0.1524)
				)
				(justify mirror)
			)
		)
		(duplicate_pad_numbers_are_jumpers no)
		(fp_line
			(start -0.508 0)
			(end 0.508 0)
			(stroke
				(width 0.2032)
				(type default)
			)
			(layer "B.SilkS")
		)
		(fp_rect
			(start 0.5842 1.3335)
			(end -0.5842 -1.3335)
			(stroke
				(width 0)
				(type default)
			)
			(fill no)
			(layer "B.CrtYd")
		)
		(fp_rect
			(start 0.5842 1.3335)
			(end -0.5842 -1.3335)
			(stroke
				(width 0)
				(type default)
			)
			(fill no)
			(layer "B.Fab")
		)
		(pad "1" smd custom
			(at 0 -0.762)
			(size 0.2159 0.2159)
			(layers "B.Cu" "B.Mask" "B.Paste")
			(net "GND")
			(options
				(clearance outline)
				(anchor circle)
			)
			(primitives
				(gr_poly
					(pts
						(arc
							(start -0.3302 0.4318)
							(mid -0.402042 0.402042)
							(end -0.4318 0.3302)
						)
						(arc
							(start -0.4318 -0.3302)
							(mid -0.402042 -0.402042)
							(end -0.3302 -0.4318)
						)
						(arc
							(start 0.3302 -0.4318)
							(mid 0.402042 -0.402042)
							(end 0.4318 -0.3302)
						)
						(arc
							(start 0.4318 0.3302)
							(mid 0.402042 0.402042)
							(end 0.3302 0.4318)
						)
					)
					(width 0)
					(fill yes)
				)
			)
		)
		(pad "2" smd custom
			(at 0 0.762)
			(size 0.2159 0.2159)
			(layers "B.Cu" "B.Mask" "B.Paste")
			(net "P1V15_STBY")
			(options
				(clearance outline)
				(anchor circle)
			)
			(primitives
				(gr_poly
					(pts
						(arc
							(start -0.3302 0.4318)
							(mid -0.402042 0.402042)
							(end -0.4318 0.3302)
						)
						(arc
							(start -0.4318 -0.3302)
							(mid -0.402042 -0.402042)
							(end -0.3302 -0.4318)
						)
						(arc
							(start 0.3302 -0.4318)
							(mid 0.402042 -0.402042)
							(end 0.4318 -0.3302)
						)
						(arc
							(start 0.4318 0.3302)
							(mid 0.402042 0.402042)
							(end 0.3302 0.4318)
						)
					)
					(width 0)
					(fill yes)
				)
			)
		)
	)
	(footprint ""
		(layer "B.Cu")
		(at 36.585398 -140.280644)
		(property "Reference" "C104"
			(at 0 0 0)
			(layer "B.SilkS")
			(hide yes)
			(effects
				(font
					(size 1.27 1.27)
				)
				(justify mirror)
			)
		)
		(property "Value" "SC10U6D3V3KX-1-GP"
			(at 0 -2.8194 0)
			(unlocked yes)
			(layer "B.Fab")
			(hide yes)
			(effects
				(font
					(size 1.016 1.016)
					(thickness 0.1524)
				)
				(justify mirror)
			)
		)
		(property "Device Type" "C603H40"
			(at 0 -4.3434 0)
			(unlocked yes)
			(layer "B.Fab")
			(hide yes)
			(effects
				(font
					(size 1.016 1.016)
					(thickness 0.1524)
				)
				(justify mirror)
			)
		)
		(duplicate_pad_numbers_are_jumpers no)
		(fp_line
			(start -0.508 0)
			(end 0.508 0)
			(stroke
				(width 0.2032)
				(type default)
			)
			(layer "B.SilkS")
		)
		(fp_rect
			(start 0.5842 1.3335)
			(end -0.5842 -1.3335)
			(stroke
				(width 0)
				(type default)
			)
			(fill no)
			(layer "B.CrtYd")
		)
		(fp_rect
			(start 0.5842 1.3335)
			(end -0.5842 -1.3335)
			(stroke
				(width 0)
				(type default)
			)
			(fill no)
			(layer "B.Fab")
		)
		(pad "1" smd custom
			(at 0 -0.762 180)
			(size 0.2159 0.2159)
			(layers "B.Cu" "B.Mask" "B.Paste")
			(net "GND")
			(options
				(clearance outline)
				(anchor circle)
			)
			(primitives
				(gr_poly
					(pts
						(arc
							(start -0.3302 0.4318)
							(mid -0.402042 0.402042)
							(end -0.4318 0.3302)
						)
						(arc
							(start -0.4318 -0.3302)
							(mid -0.402042 -0.402042)
							(end -0.3302 -0.4318)
						)
						(arc
							(start 0.3302 -0.4318)
							(mid 0.402042 -0.402042)
							(end 0.4318 -0.3302)
						)
						(arc
							(start 0.4318 0.3302)
							(mid 0.402042 0.402042)
							(end 0.3302 0.4318)
						)
					)
					(width 0)
					(fill yes)
				)
			)
		)
		(pad "2" smd custom
			(at 0 0.762 180)
			(size 0.2159 0.2159)
			(layers "B.Cu" "B.Mask" "B.Paste")
			(net "P3V3_STBY")
			(options
				(clearance outline)
				(anchor circle)
			)
			(primitives
				(gr_poly
					(pts
						(arc
							(start -0.3302 0.4318)
							(mid -0.402042 0.402042)
							(end -0.4318 0.3302)
						)
						(arc
							(start -0.4318 -0.3302)
							(mid -0.402042 -0.402042)
							(end -0.3302 -0.4318)
						)
						(arc
							(start 0.3302 -0.4318)
							(mid 0.402042 -0.402042)
							(end 0.4318 -0.3302)
						)
						(arc
							(start 0.4318 0.3302)
							(mid 0.402042 0.402042)
							(end 0.3302 0.4318)
						)
					)
					(width 0)
					(fill yes)
				)
			)
		)
	)
	(footprint ""
		(layer "B.Cu")
		(at 55.788052 -146.395186)
		(property "Reference" "TP81"
			(at 0 0 0)
			(layer "B.SilkS")
			(hide yes)
			(effects
				(font
					(size 1.27 1.27)
				)
				(justify mirror)
			)
		)
		(property "Value" "TPAD28-2-GP"
			(at 0.0127 -1.6637 0)
			(unlocked yes)
			(layer "B.Fab")
			(hide yes)
			(effects
				(font
					(size 1.016 1.016)
					(thickness 0.1524)
				)
				(justify mirror)
			)
		)
		(property "Device Type" "TPAD28"
			(at 0.0127 -3.1877 0)
			(unlocked yes)
			(layer "B.Fab")
			(hide yes)
			(effects
				(font
					(size 1.016 1.016)
					(thickness 0.1524)
				)
				(justify mirror)
			)
		)
		(duplicate_pad_numbers_are_jumpers no)
		(fp_poly
			(pts
				(arc
					(start 0.3556 0)
					(mid -0.3556 0)
					(end 0.3556 0)
				)
			)
			(stroke
				(width 0)
				(type default)
			)
			(fill no)
			(layer "B.CrtYd")
		)
		(fp_poly
			(pts
				(arc
					(start 0.6096 0)
					(mid -0.6096 0)
					(end 0.6096 0)
				)
			)
			(stroke
				(width 0)
				(type default)
			)
			(fill no)
			(layer "B.Fab")
		)
		(pad "1" smd circle
			(at 0 0 180)
			(size 0.7112 0.7112)
			(layers "B.Cu" "B.Mask" "B.Paste")
			(net "JTAG_BMC_TCK")
		)
	)
	(footprint ""
		(layer "B.Cu")
		(at 37.80536 -140.29309 180)
		(property "Reference" "C99"
			(at 0 0 0)
			(layer "B.SilkS")
			(hide yes)
			(effects
				(font
					(size 1.27 1.27)
				)
				(justify mirror)
			)
		)
		(property "Value" "SC1U16V3KX-5GP"
			(at 0 -2.8194 180)
			(unlocked yes)
			(layer "B.Fab")
			(hide yes)
			(effects
				(font
					(size 1.016 1.016)
					(thickness 0.1524)
				)
				(justify mirror)
			)
		)
		(property "Device Type" "C603H36"
			(at 0 -4.3434 180)
			(unlocked yes)
			(layer "B.Fab")
			(hide yes)
			(effects
				(font
					(size 1.016 1.016)
					(thickness 0.1524)
				)
				(justify mirror)
			)
		)
		(duplicate_pad_numbers_are_jumpers no)
		(fp_line
			(start -0.508 0)
			(end 0.508 0)
			(stroke
				(width 0.2032)
				(type default)
			)
			(layer "B.SilkS")
		)
		(fp_rect
			(start 0.5842 1.3335)
			(end -0.5842 -1.3335)
			(stroke
				(width 0)
				(type default)
			)
			(fill no)
			(layer "B.CrtYd")
		)
		(fp_rect
			(start 0.5842 1.3335)
			(end -0.5842 -1.3335)
			(stroke
				(width 0)
				(type default)
			)
			(fill no)
			(layer "B.Fab")
		)
		(pad "1" smd custom
			(at 0 -0.762)
			(size 0.2159 0.2159)
			(layers "B.Cu" "B.Mask" "B.Paste")
			(net "P3V3_STBY")
			(options
				(clearance outline)
				(anchor circle)
			)
			(primitives
				(gr_poly
					(pts
						(arc
							(start -0.3302 0.4318)
							(mid -0.402042 0.402042)
							(end -0.4318 0.3302)
						)
						(arc
							(start -0.4318 -0.3302)
							(mid -0.402042 -0.402042)
							(end -0.3302 -0.4318)
						)
						(arc
							(start 0.3302 -0.4318)
							(mid 0.402042 -0.402042)
							(end 0.4318 -0.3302)
						)
						(arc
							(start 0.4318 0.3302)
							(mid 0.402042 0.402042)
							(end 0.3302 0.4318)
						)
					)
					(width 0)
					(fill yes)
				)
			)
		)
		(pad "2" smd custom
			(at 0 0.762)
			(size 0.2159 0.2159)
			(layers "B.Cu" "B.Mask" "B.Paste")
			(net "GND")
			(options
				(clearance outline)
				(anchor circle)
			)
			(primitives
				(gr_poly
					(pts
						(arc
							(start -0.3302 0.4318)
							(mid -0.402042 0.402042)
							(end -0.4318 0.3302)
						)
						(arc
							(start -0.4318 -0.3302)
							(mid -0.402042 -0.402042)
							(end -0.3302 -0.4318)
						)
						(arc
							(start 0.3302 -0.4318)
							(mid 0.402042 -0.402042)
							(end 0.4318 -0.3302)
						)
						(arc
							(start 0.4318 0.3302)
							(mid 0.402042 0.402042)
							(end 0.3302 0.4318)
						)
					)
					(width 0)
					(fill yes)
				)
			)
		)
	)
	(footprint ""
		(layer "B.Cu")
		(at 60.2742 -138.5316)
		(property "Reference" "R272"
			(at 0 0 0)
			(layer "B.SilkS")
			(hide yes)
			(effects
				(font
					(size 1.27 1.27)
				)
				(justify mirror)
			)
		)
		(property "Value" "4K7R2F-GP"
			(at -0.064008 -3.993896 0)
			(unlocked yes)
			(layer "B.Fab")
			(hide yes)
			(effects
				(font
					(size 1.016 1.016)
					(thickness 0.1524)
				)
				(justify mirror)
			)
		)
		(property "Device Type" "R402H16"
			(at -0.064008 -5.517896 0)
			(unlocked yes)
			(layer "B.Fab")
			(hide yes)
			(effects
				(font
					(size 1.016 1.016)
					(thickness 0.1524)
				)
				(justify mirror)
			)
		)
		(duplicate_pad_numbers_are_jumpers no)
		(fp_line
			(start -0.508 -0.9398)
			(end 0.508 -0.9398)
			(stroke
				(width 0.1524)
				(type default)
			)
			(layer "B.SilkS")
		)
		(fp_line
			(start 0.508 -0.9398)
			(end 0.508 0.9398)
			(stroke
				(width 0.1524)
				(type default)
			)
			(layer "B.SilkS")
		)
		(fp_rect
			(start 0.508 0.9398)
			(end -0.508 -0.9398)
			(stroke
				(width 0)
				(type default)
			)
			(fill no)
			(layer "B.CrtYd")
		)
		(fp_rect
			(start 0.508 0.9398)
			(end -0.508 -0.9398)
			(stroke
				(width 0)
				(type default)
			)
			(fill no)
			(layer "B.Fab")
		)
		(pad "1" smd custom
			(at 0 -0.4445 180)
			(size 0.1397 0.1397)
			(layers "B.Cu" "B.Mask" "B.Paste")
			(net "SYS_PWR_LED")
			(options
				(clearance outline)
				(anchor circle)
			)
			(primitives
				(gr_poly
					(pts
						(arc
							(start -0.1778 0.2794)
							(mid -0.249642 0.249642)
							(end -0.2794 0.1778)
						)
						(arc
							(start -0.2794 -0.1778)
							(mid -0.249642 -0.249642)
							(end -0.1778 -0.2794)
						)
						(arc
							(start 0.1778 -0.2794)
							(mid 0.249642 -0.249642)
							(end 0.2794 -0.1778)
						)
						(arc
							(start 0.2794 0.1778)
							(mid 0.249642 0.249642)
							(end 0.1778 0.2794)
						)
					)
					(width 0)
					(fill yes)
				)
			)
		)
		(pad "2" smd custom
			(at 0 0.4445 180)
			(size 0.1397 0.1397)
			(layers "B.Cu" "B.Mask" "B.Paste")
			(net "P3V3_STBY")
			(options
				(clearance outline)
				(anchor circle)
			)
			(primitives
				(gr_poly
					(pts
						(arc
							(start -0.1778 0.2794)
							(mid -0.249642 0.249642)
							(end -0.2794 0.1778)
						)
						(arc
							(start -0.2794 -0.1778)
							(mid -0.249642 -0.249642)
							(end -0.1778 -0.2794)
						)
						(arc
							(start 0.1778 -0.2794)
							(mid 0.249642 -0.249642)
							(end 0.2794 -0.1778)
						)
						(arc
							(start 0.2794 0.1778)
							(mid 0.249642 0.249642)
							(end 0.1778 0.2794)
						)
					)
					(width 0)
					(fill yes)
				)
			)
		)
	)
	(footprint ""
		(layer "B.Cu")
		(at 61.75502 -143.949928 90)
		(property "Reference" "R153"
			(at 0 0 90)
			(layer "B.SilkS")
			(hide yes)
			(effects
				(font
					(size 1.27 1.27)
				)
				(justify mirror)
			)
		)
		(property "Value" "0R2J-2-GP"
			(at -0.064008 -3.993896 90)
			(unlocked yes)
			(layer "B.Fab")
			(hide yes)
			(effects
				(font
					(size 1.016 1.016)
					(thickness 0.1524)
				)
				(justify mirror)
			)
		)
		(property "Device Type" "R402H16"
			(at -0.064008 -5.517896 90)
			(unlocked yes)
			(layer "B.Fab")
			(hide yes)
			(effects
				(font
					(size 1.016 1.016)
					(thickness 0.1524)
				)
				(justify mirror)
			)
		)
		(duplicate_pad_numbers_are_jumpers no)
		(fp_line
			(start 0.508 -0.9398)
			(end 0.508 0.9398)
			(stroke
				(width 0.1524)
				(type default)
			)
			(layer "B.SilkS")
		)
		(fp_line
			(start -0.508 -0.9398)
			(end 0.508 -0.9398)
			(stroke
				(width 0.1524)
				(type default)
			)
			(layer "B.SilkS")
		)
		(fp_rect
			(start 0.508 0.9398)
			(end -0.508 -0.9398)
			(stroke
				(width 0)
				(type default)
			)
			(fill no)
			(layer "B.CrtYd")
		)
		(fp_rect
			(start 0.508 0.9398)
			(end -0.508 -0.9398)
			(stroke
				(width 0)
				(type default)
			)
			(fill no)
			(layer "B.Fab")
		)
		(pad "1" smd custom
			(at 0 -0.4445 270)
			(size 0.1397 0.1397)
			(layers "B.Cu" "B.Mask" "B.Paste")
			(net "BMC_SMB10_DAT")
			(options
				(clearance outline)
				(anchor circle)
			)
			(primitives
				(gr_poly
					(pts
						(arc
							(start -0.1778 0.2794)
							(mid -0.249642 0.249642)
							(end -0.2794 0.1778)
						)
						(arc
							(start -0.2794 -0.1778)
							(mid -0.249642 -0.249642)
							(end -0.1778 -0.2794)
						)
						(arc
							(start 0.1778 -0.2794)
							(mid 0.249642 -0.249642)
							(end 0.2794 -0.1778)
						)
						(arc
							(start 0.2794 0.1778)
							(mid 0.249642 0.249642)
							(end 0.1778 0.2794)
						)
					)
					(width 0)
					(fill yes)
				)
			)
		)
		(pad "2" smd custom
			(at 0 0.4445 270)
			(size 0.1397 0.1397)
			(layers "B.Cu" "B.Mask" "B.Paste")
			(net "I2C_EXP_LOC_SDA_OUT")
			(options
				(clearance outline)
				(anchor circle)
			)
			(primitives
				(gr_poly
					(pts
						(arc
							(start -0.1778 0.2794)
							(mid -0.249642 0.249642)
							(end -0.2794 0.1778)
						)
						(arc
							(start -0.2794 -0.1778)
							(mid -0.249642 -0.249642)
							(end -0.1778 -0.2794)
						)
						(arc
							(start 0.1778 -0.2794)
							(mid 0.249642 -0.249642)
							(end 0.2794 -0.1778)
						)
						(arc
							(start 0.2794 0.1778)
							(mid 0.249642 0.249642)
							(end 0.1778 0.2794)
						)
					)
					(width 0)
					(fill yes)
				)
			)
		)
	)
	(footprint ""
		(layer "B.Cu")
		(at 76.2 -151.9428 -90)
		(property "Reference" "U16"
			(at 0 0 90)
			(layer "B.SilkS")
			(hide yes)
			(effects
				(font
					(size 1.27 1.27)
				)
				(justify mirror)
			)
		)
		(property "Value" "NX3L1G66GW-GP"
			(at 2.3368 -8.6868 270)
			(unlocked yes)
			(layer "B.Fab")
			(hide yes)
			(effects
				(font
					(size 1.016 1.016)
					(thickness 0.1524)
				)
				(justify mirror)
			)
		)
		(property "Device Type" "SC70-5H44"
			(at 2.3114 -10.414 270)
			(unlocked yes)
			(layer "B.Fab")
			(hide yes)
			(effects
				(font
					(size 1.016 1.016)
					(thickness 0.1524)
				)
				(justify mirror)
			)
		)
		(duplicate_pad_numbers_are_jumpers no)
		(fp_line
			(start -1.27 1.7018)
			(end 1.27 1.7018)
			(stroke
				(width 0.1524)
				(type default)
			)
			(layer "B.SilkS")
		)
		(fp_line
			(start 1.27 1.7018)
			(end 1.27 -1.7018)
			(stroke
				(width 0.1524)
				(type default)
			)
			(layer "B.SilkS")
		)
		(fp_line
			(start -1.27 -1.7018)
			(end -1.27 1.7018)
			(stroke
				(width 0.1524)
				(type default)
			)
			(layer "B.SilkS")
		)
		(fp_line
			(start 1.27 -1.7018)
			(end -1.27 -1.7018)
			(stroke
				(width 0.1524)
				(type default)
			)
			(layer "B.SilkS")
		)
		(fp_line
			(start -1.3843 -1.8034)
			(end -1.3843 -1.1176)
			(stroke
				(width 0.3302)
				(type default)
			)
			(layer "B.SilkS")
		)
		(fp_line
			(start -0.6604 -1.8034)
			(end -1.3843 -1.8034)
			(stroke
				(width 0.3302)
				(type default)
			)
			(layer "B.SilkS")
		)
		(fp_rect
			(start 1.524 1.9558)
			(end -1.524 -1.9558)
			(stroke
				(width 0)
				(type default)
			)
			(fill no)
			(layer "B.CrtYd")
		)
		(fp_poly
			(pts
				(xy 1.524 -1.9558) (xy -1.524 -1.9558) (xy -1.524 1.9558) (xy 1.524 1.9558)
			)
			(stroke
				(width 0)
				(type default)
			)
			(fill no)
			(layer "B.Fab")
		)
		(pad "1" smd rect
			(at -0.65024 -0.8255 90)
			(size 0.4064 1.2192)
			(layers "B.Cu" "B.Mask" "B.Paste")
			(net "I2C_BMC_COMP_ALERT_N_R")
		)
		(pad "2" smd rect
			(at 0 -0.8255 90)
			(size 0.4064 1.2192)
			(layers "B.Cu" "B.Mask" "B.Paste")
			(net "I2C_COMP_ALERT_N")
		)
		(pad "3" smd rect
			(at 0.65024 -0.8255 90)
			(size 0.4064 1.2192)
			(layers "B.Cu" "B.Mask" "B.Paste")
			(net "GND")
		)
		(pad "4" smd rect
			(at 0.65024 0.8255 90)
			(size 0.4064 1.2192)
			(layers "B.Cu" "B.Mask" "B.Paste")
			(net "COMP_PWR_EN")
		)
		(pad "5" smd rect
			(at -0.65024 0.8255 90)
			(size 0.4064 1.2192)
			(layers "B.Cu" "B.Mask" "B.Paste")
			(net "P3V3_STBY")
		)
	)
	(footprint ""
		(layer "B.Cu")
		(at 91.245182 -171.118784 90)
		(property "Reference" "R418"
			(at 0 0 90)
			(layer "B.SilkS")
			(hide yes)
			(effects
				(font
					(size 1.27 1.27)
				)
				(justify mirror)
			)
		)
		(property "Value" "0R2J-2-GP"
			(at -0.064008 -3.993896 90)
			(unlocked yes)
			(layer "B.Fab")
			(hide yes)
			(effects
				(font
					(size 1.016 1.016)
					(thickness 0.1524)
				)
				(justify mirror)
			)
		)
		(property "Device Type" "R402H16"
			(at -0.064008 -5.517896 90)
			(unlocked yes)
			(layer "B.Fab")
			(hide yes)
			(effects
				(font
					(size 1.016 1.016)
					(thickness 0.1524)
				)
				(justify mirror)
			)
		)
		(duplicate_pad_numbers_are_jumpers no)
		(fp_line
			(start 0.508 -0.9398)
			(end 0.508 0.9398)
			(stroke
				(width 0.1524)
				(type default)
			)
			(layer "B.SilkS")
		)
		(fp_line
			(start -0.508 -0.9398)
			(end 0.508 -0.9398)
			(stroke
				(width 0.1524)
				(type default)
			)
			(layer "B.SilkS")
		)
		(fp_rect
			(start 0.508 0.9398)
			(end -0.508 -0.9398)
			(stroke
				(width 0)
				(type default)
			)
			(fill no)
			(layer "B.CrtYd")
		)
		(fp_rect
			(start 0.508 0.9398)
			(end -0.508 -0.9398)
			(stroke
				(width 0)
				(type default)
			)
			(fill no)
			(layer "B.Fab")
		)
		(pad "1" smd custom
			(at 0 -0.4445 270)
			(size 0.1397 0.1397)
			(layers "B.Cu" "B.Mask" "B.Paste")
			(net "UART_COMP_R_TX")
			(options
				(clearance outline)
				(anchor circle)
			)
			(primitives
				(gr_poly
					(pts
						(arc
							(start -0.1778 0.2794)
							(mid -0.249642 0.249642)
							(end -0.2794 0.1778)
						)
						(arc
							(start -0.2794 -0.1778)
							(mid -0.249642 -0.249642)
							(end -0.1778 -0.2794)
						)
						(arc
							(start 0.1778 -0.2794)
							(mid 0.249642 -0.249642)
							(end 0.2794 -0.1778)
						)
						(arc
							(start 0.2794 0.1778)
							(mid 0.249642 0.249642)
							(end 0.1778 0.2794)
						)
					)
					(width 0)
					(fill yes)
				)
			)
		)
		(pad "2" smd custom
			(at 0 0.4445 270)
			(size 0.1397 0.1397)
			(layers "B.Cu" "B.Mask" "B.Paste")
			(net "UART_COMP_TX")
			(options
				(clearance outline)
				(anchor circle)
			)
			(primitives
				(gr_poly
					(pts
						(arc
							(start -0.1778 0.2794)
							(mid -0.249642 0.249642)
							(end -0.2794 0.1778)
						)
						(arc
							(start -0.2794 -0.1778)
							(mid -0.249642 -0.249642)
							(end -0.1778 -0.2794)
						)
						(arc
							(start 0.1778 -0.2794)
							(mid 0.249642 -0.249642)
							(end 0.2794 -0.1778)
						)
						(arc
							(start 0.2794 0.1778)
							(mid 0.249642 0.249642)
							(end 0.1778 0.2794)
						)
					)
					(width 0)
					(fill yes)
				)
			)
		)
	)
	(footprint ""
		(layer "B.Cu")
		(at 91.68892 -149.526244)
		(property "Reference" "C14"
			(at 0 0 0)
			(layer "B.SilkS")
			(hide yes)
			(effects
				(font
					(size 1.27 1.27)
				)
				(justify mirror)
			)
		)
		(property "Value" "SC1KP50V2KX-1GP"
			(at -1.1811 -2.7051 0)
			(unlocked yes)
			(layer "B.Fab")
			(hide yes)
			(effects
				(font
					(size 1.016 1.016)
					(thickness 0.1524)
				)
				(justify mirror)
			)
		)
		(property "Device Type" "C402H22"
			(at -1.1811 -4.2291 0)
			(unlocked yes)
			(layer "B.Fab")
			(hide yes)
			(effects
				(font
					(size 1.016 1.016)
					(thickness 0.1524)
				)
				(justify mirror)
			)
		)
		(duplicate_pad_numbers_are_jumpers no)
		(fp_rect
			(start 0.4318 0.9525)
			(end -0.4318 -0.9525)
			(stroke
				(width 0)
				(type default)
			)
			(fill no)
			(layer "B.CrtYd")
		)
		(fp_rect
			(start 0.4318 0.9525)
			(end -0.4318 -0.9525)
			(stroke
				(width 0)
				(type default)
			)
			(fill no)
			(layer "B.Fab")
		)
		(pad "1" smd custom
			(at 0 -0.4445 180)
			(size 0.1524 0.1524)
			(layers "B.Cu" "B.Mask" "B.Paste")
			(net "USB_OCS_N1")
			(options
				(clearance outline)
				(anchor circle)
			)
			(primitives
				(gr_poly
					(pts
						(arc
							(start 0.3048 0.2032)
							(mid 0.275042 0.275042)
							(end 0.2032 0.3048)
						)
						(arc
							(start -0.2032 0.3048)
							(mid -0.275042 0.275042)
							(end -0.3048 0.2032)
						)
						(arc
							(start -0.3048 -0.2032)
							(mid -0.275042 -0.275042)
							(end -0.2032 -0.3048)
						)
						(arc
							(start 0.2032 -0.3048)
							(mid 0.275042 -0.275042)
							(end 0.3048 -0.2032)
						)
					)
					(width 0)
					(fill yes)
				)
			)
		)
		(pad "2" smd custom
			(at 0 0.4445 180)
			(size 0.1524 0.1524)
			(layers "B.Cu" "B.Mask" "B.Paste")
			(net "GND")
			(options
				(clearance outline)
				(anchor circle)
			)
			(primitives
				(gr_poly
					(pts
						(arc
							(start 0.3048 0.2032)
							(mid 0.275042 0.275042)
							(end 0.2032 0.3048)
						)
						(arc
							(start -0.2032 0.3048)
							(mid -0.275042 0.275042)
							(end -0.3048 0.2032)
						)
						(arc
							(start -0.3048 -0.2032)
							(mid -0.275042 -0.275042)
							(end -0.2032 -0.3048)
						)
						(arc
							(start 0.2032 -0.3048)
							(mid 0.275042 -0.275042)
							(end 0.3048 -0.2032)
						)
					)
					(width 0)
					(fill yes)
				)
			)
		)
	)
	(footprint ""
		(layer "B.Cu")
		(at 45.144436 -157.25648 -90)
		(property "Reference" "R697"
			(at 0 0 90)
			(layer "B.SilkS")
			(hide yes)
			(effects
				(font
					(size 1.27 1.27)
				)
				(justify mirror)
			)
		)
		(property "Value" "4K7R2F-GP"
			(at -0.064008 -3.993896 270)
			(unlocked yes)
			(layer "B.Fab")
			(hide yes)
			(effects
				(font
					(size 1.016 1.016)
					(thickness 0.1524)
				)
				(justify mirror)
			)
		)
		(property "Device Type" "R402H16"
			(at -0.064008 -5.517896 270)
			(unlocked yes)
			(layer "B.Fab")
			(hide yes)
			(effects
				(font
					(size 1.016 1.016)
					(thickness 0.1524)
				)
				(justify mirror)
			)
		)
		(duplicate_pad_numbers_are_jumpers no)
		(fp_line
			(start -0.508 -0.9398)
			(end 0.508 -0.9398)
			(stroke
				(width 0.1524)
				(type default)
			)
			(layer "B.SilkS")
		)
		(fp_line
			(start 0.508 -0.9398)
			(end 0.508 0.9398)
			(stroke
				(width 0.1524)
				(type default)
			)
			(layer "B.SilkS")
		)
		(fp_rect
			(start 0.508 0.9398)
			(end -0.508 -0.9398)
			(stroke
				(width 0)
				(type default)
			)
			(fill no)
			(layer "B.CrtYd")
		)
		(fp_rect
			(start 0.508 0.9398)
			(end -0.508 -0.9398)
			(stroke
				(width 0)
				(type default)
			)
			(fill no)
			(layer "B.Fab")
		)
		(pad "1" smd custom
			(at 0 -0.4445 90)
			(size 0.1397 0.1397)
			(layers "B.Cu" "B.Mask" "B.Paste")
			(net "P3V3_STBY")
			(options
				(clearance outline)
				(anchor circle)
			)
			(primitives
				(gr_poly
					(pts
						(arc
							(start -0.1778 0.2794)
							(mid -0.249642 0.249642)
							(end -0.2794 0.1778)
						)
						(arc
							(start -0.2794 -0.1778)
							(mid -0.249642 -0.249642)
							(end -0.1778 -0.2794)
						)
						(arc
							(start 0.1778 -0.2794)
							(mid 0.249642 -0.249642)
							(end 0.2794 -0.1778)
						)
						(arc
							(start 0.2794 0.1778)
							(mid 0.249642 0.249642)
							(end 0.1778 0.2794)
						)
					)
					(width 0)
					(fill yes)
				)
			)
		)
		(pad "2" smd custom
			(at 0 0.4445 90)
			(size 0.1397 0.1397)
			(layers "B.Cu" "B.Mask" "B.Paste")
			(net "PCIE_WAKE_N")
			(options
				(clearance outline)
				(anchor circle)
			)
			(primitives
				(gr_poly
					(pts
						(arc
							(start -0.1778 0.2794)
							(mid -0.249642 0.249642)
							(end -0.2794 0.1778)
						)
						(arc
							(start -0.2794 -0.1778)
							(mid -0.249642 -0.249642)
							(end -0.1778 -0.2794)
						)
						(arc
							(start 0.1778 -0.2794)
							(mid 0.249642 -0.249642)
							(end 0.2794 -0.1778)
						)
						(arc
							(start 0.2794 0.1778)
							(mid 0.249642 0.249642)
							(end 0.1778 0.2794)
						)
					)
					(width 0)
					(fill yes)
				)
			)
		)
	)
	(footprint ""
		(layer "B.Cu")
		(at 22.011386 -131.007358 180)
		(property "Reference" "R261"
			(at 0 0 0)
			(layer "B.SilkS")
			(hide yes)
			(effects
				(font
					(size 1.27 1.27)
				)
				(justify mirror)
			)
		)
		(property "Value" "120R2F-GP"
			(at -0.064008 -3.993896 180)
			(unlocked yes)
			(layer "B.Fab")
			(hide yes)
			(effects
				(font
					(size 1.016 1.016)
					(thickness 0.1524)
				)
				(justify mirror)
			)
		)
		(property "Device Type" "R402H16"
			(at -0.064008 -5.517896 180)
			(unlocked yes)
			(layer "B.Fab")
			(hide yes)
			(effects
				(font
					(size 1.016 1.016)
					(thickness 0.1524)
				)
				(justify mirror)
			)
		)
		(duplicate_pad_numbers_are_jumpers no)
		(fp_line
			(start 0.508 -0.9398)
			(end 0.508 0.9398)
			(stroke
				(width 0.1524)
				(type default)
			)
			(layer "B.SilkS")
		)
		(fp_line
			(start -0.508 -0.9398)
			(end 0.508 -0.9398)
			(stroke
				(width 0.1524)
				(type default)
			)
			(layer "B.SilkS")
		)
		(fp_rect
			(start 0.508 0.9398)
			(end -0.508 -0.9398)
			(stroke
				(width 0)
				(type default)
			)
			(fill no)
			(layer "B.CrtYd")
		)
		(fp_rect
			(start 0.508 0.9398)
			(end -0.508 -0.9398)
			(stroke
				(width 0)
				(type default)
			)
			(fill no)
			(layer "B.Fab")
		)
		(pad "1" smd custom
			(at 0 -0.4445)
			(size 0.1397 0.1397)
			(layers "B.Cu" "B.Mask" "B.Paste")
			(net "MEMA_13")
			(options
				(clearance outline)
				(anchor circle)
			)
			(primitives
				(gr_poly
					(pts
						(arc
							(start -0.1778 0.2794)
							(mid -0.249642 0.249642)
							(end -0.2794 0.1778)
						)
						(arc
							(start -0.2794 -0.1778)
							(mid -0.249642 -0.249642)
							(end -0.1778 -0.2794)
						)
						(arc
							(start 0.1778 -0.2794)
							(mid 0.249642 -0.249642)
							(end 0.2794 -0.1778)
						)
						(arc
							(start 0.2794 0.1778)
							(mid 0.249642 0.249642)
							(end 0.1778 0.2794)
						)
					)
					(width 0)
					(fill yes)
				)
			)
		)
		(pad "2" smd custom
			(at 0 0.4445)
			(size 0.1397 0.1397)
			(layers "B.Cu" "B.Mask" "B.Paste")
			(net "P1V2_STBY")
			(options
				(clearance outline)
				(anchor circle)
			)
			(primitives
				(gr_poly
					(pts
						(arc
							(start -0.1778 0.2794)
							(mid -0.249642 0.249642)
							(end -0.2794 0.1778)
						)
						(arc
							(start -0.2794 -0.1778)
							(mid -0.249642 -0.249642)
							(end -0.1778 -0.2794)
						)
						(arc
							(start 0.1778 -0.2794)
							(mid 0.249642 -0.249642)
							(end 0.2794 -0.1778)
						)
						(arc
							(start 0.2794 0.1778)
							(mid 0.249642 0.249642)
							(end 0.1778 0.2794)
						)
					)
					(width 0)
					(fill yes)
				)
			)
		)
	)
	(footprint ""
		(layer "B.Cu")
		(at 226.600004 -51.137566 90)
		(property "Reference" "C153"
			(at 0 0 90)
			(layer "B.SilkS")
			(hide yes)
			(effects
				(font
					(size 1.27 1.27)
				)
				(justify mirror)
			)
		)
		(property "Value" "SC10U16V5KX-7-GP-U"
			(at 0.0762 -6.1214 90)
			(unlocked yes)
			(layer "B.Fab")
			(hide yes)
			(effects
				(font
					(size 1.016 1.016)
					(thickness 0.1524)
				)
				(justify mirror)
			)
		)
		(property "Device Type" "C805H58"
			(at 0.0762 -8.1534 90)
			(unlocked yes)
			(layer "B.Fab")
			(hide yes)
			(effects
				(font
					(size 1.016 1.016)
					(thickness 0.1524)
				)
				(justify mirror)
			)
		)
		(duplicate_pad_numbers_are_jumpers no)
		(fp_line
			(start -0.635 0)
			(end 0.635 0)
			(stroke
				(width 0.508)
				(type default)
			)
			(layer "B.SilkS")
		)
		(fp_rect
			(start 0.9652 1.778)
			(end -0.9652 -1.778)
			(stroke
				(width 0)
				(type default)
			)
			(fill no)
			(layer "B.CrtYd")
		)
		(fp_poly
			(pts
				(xy 0.9652 -1.778) (xy -0.9652 -1.778) (xy -0.9652 1.778) (xy 0.9652 1.778)
			)
			(stroke
				(width 0)
				(type default)
			)
			(fill no)
			(layer "B.Fab")
		)
		(pad "1" smd rect
			(at 0 -0.9652 270)
			(size 1.397 1.143)
			(layers "B.Cu" "B.Mask" "B.Paste")
			(net "P12V_STBY_VIN_PU1")
		)
		(pad "2" smd rect
			(at 0 0.9652 270)
			(size 1.397 1.143)
			(layers "B.Cu" "B.Mask" "B.Paste")
			(net "GND")
		)
	)
	(footprint ""
		(layer "B.Cu")
		(at 113.386362 -8.8138)
		(property "Reference" "C150"
			(at 0 0 0)
			(layer "B.SilkS")
			(hide yes)
			(effects
				(font
					(size 1.27 1.27)
				)
				(justify mirror)
			)
		)
		(property "Value" "SCD1U50V3KX-GP"
			(at 0 -2.8194 0)
			(unlocked yes)
			(layer "B.Fab")
			(hide yes)
			(effects
				(font
					(size 1.016 1.016)
					(thickness 0.1524)
				)
				(justify mirror)
			)
		)
		(property "Device Type" "C603H36"
			(at 0 -4.3434 0)
			(unlocked yes)
			(layer "B.Fab")
			(hide yes)
			(effects
				(font
					(size 1.016 1.016)
					(thickness 0.1524)
				)
				(justify mirror)
			)
		)
		(duplicate_pad_numbers_are_jumpers no)
		(fp_line
			(start -0.508 0)
			(end 0.508 0)
			(stroke
				(width 0.2032)
				(type default)
			)
			(layer "B.SilkS")
		)
		(fp_rect
			(start 0.5842 1.3335)
			(end -0.5842 -1.3335)
			(stroke
				(width 0)
				(type default)
			)
			(fill no)
			(layer "B.CrtYd")
		)
		(fp_rect
			(start 0.5842 1.3335)
			(end -0.5842 -1.3335)
			(stroke
				(width 0)
				(type default)
			)
			(fill no)
			(layer "B.Fab")
		)
		(pad "1" smd custom
			(at 0 -0.762 180)
			(size 0.2159 0.2159)
			(layers "B.Cu" "B.Mask" "B.Paste")
			(net "MB0_ISTART_R")
			(options
				(clearance outline)
				(anchor circle)
			)
			(primitives
				(gr_poly
					(pts
						(arc
							(start -0.3302 0.4318)
							(mid -0.402042 0.402042)
							(end -0.4318 0.3302)
						)
						(arc
							(start -0.4318 -0.3302)
							(mid -0.402042 -0.402042)
							(end -0.3302 -0.4318)
						)
						(arc
							(start 0.3302 -0.4318)
							(mid 0.402042 -0.402042)
							(end 0.4318 -0.3302)
						)
						(arc
							(start 0.4318 0.3302)
							(mid 0.402042 0.402042)
							(end 0.3302 0.4318)
						)
					)
					(width 0)
					(fill yes)
				)
			)
		)
		(pad "2" smd custom
			(at 0 0.762 180)
			(size 0.2159 0.2159)
			(layers "B.Cu" "B.Mask" "B.Paste")
			(net "AGND_CURRENT_MON")
			(options
				(clearance outline)
				(anchor circle)
			)
			(primitives
				(gr_poly
					(pts
						(arc
							(start -0.3302 0.4318)
							(mid -0.402042 0.402042)
							(end -0.4318 0.3302)
						)
						(arc
							(start -0.4318 -0.3302)
							(mid -0.402042 -0.402042)
							(end -0.3302 -0.4318)
						)
						(arc
							(start 0.3302 -0.4318)
							(mid 0.402042 -0.402042)
							(end 0.4318 -0.3302)
						)
						(arc
							(start 0.4318 0.3302)
							(mid 0.402042 0.402042)
							(end 0.3302 0.4318)
						)
					)
					(width 0)
					(fill yes)
				)
			)
		)
	)
	(footprint ""
		(layer "B.Cu")
		(at 49.911 -154.8384 180)
		(property "Reference" "R298"
			(at 0 0 0)
			(layer "B.SilkS")
			(hide yes)
			(effects
				(font
					(size 1.27 1.27)
				)
				(justify mirror)
			)
		)
		(property "Value" "0R2J-2-GP"
			(at -0.064008 -3.993896 180)
			(unlocked yes)
			(layer "B.Fab")
			(hide yes)
			(effects
				(font
					(size 1.016 1.016)
					(thickness 0.1524)
				)
				(justify mirror)
			)
		)
		(property "Device Type" "R402H16"
			(at -0.064008 -5.517896 180)
			(unlocked yes)
			(layer "B.Fab")
			(hide yes)
			(effects
				(font
					(size 1.016 1.016)
					(thickness 0.1524)
				)
				(justify mirror)
			)
		)
		(duplicate_pad_numbers_are_jumpers no)
		(fp_line
			(start 0.508 -0.9398)
			(end 0.508 0.9398)
			(stroke
				(width 0.1524)
				(type default)
			)
			(layer "B.SilkS")
		)
		(fp_line
			(start -0.508 -0.9398)
			(end 0.508 -0.9398)
			(stroke
				(width 0.1524)
				(type default)
			)
			(layer "B.SilkS")
		)
		(fp_rect
			(start 0.508 0.9398)
			(end -0.508 -0.9398)
			(stroke
				(width 0)
				(type default)
			)
			(fill no)
			(layer "B.CrtYd")
		)
		(fp_rect
			(start 0.508 0.9398)
			(end -0.508 -0.9398)
			(stroke
				(width 0)
				(type default)
			)
			(fill no)
			(layer "B.Fab")
		)
		(pad "1" smd custom
			(at 0 -0.4445)
			(size 0.1397 0.1397)
			(layers "B.Cu" "B.Mask" "B.Paste")
			(net "UART_BMC_R_RX")
			(options
				(clearance outline)
				(anchor circle)
			)
			(primitives
				(gr_poly
					(pts
						(arc
							(start -0.1778 0.2794)
							(mid -0.249642 0.249642)
							(end -0.2794 0.1778)
						)
						(arc
							(start -0.2794 -0.1778)
							(mid -0.249642 -0.249642)
							(end -0.1778 -0.2794)
						)
						(arc
							(start 0.1778 -0.2794)
							(mid 0.249642 -0.249642)
							(end 0.2794 -0.1778)
						)
						(arc
							(start 0.2794 0.1778)
							(mid 0.249642 0.249642)
							(end 0.1778 0.2794)
						)
					)
					(width 0)
					(fill yes)
				)
			)
		)
		(pad "2" smd custom
			(at 0 0.4445)
			(size 0.1397 0.1397)
			(layers "B.Cu" "B.Mask" "B.Paste")
			(net "UART_BMC_RX")
			(options
				(clearance outline)
				(anchor circle)
			)
			(primitives
				(gr_poly
					(pts
						(arc
							(start -0.1778 0.2794)
							(mid -0.249642 0.249642)
							(end -0.2794 0.1778)
						)
						(arc
							(start -0.2794 -0.1778)
							(mid -0.249642 -0.249642)
							(end -0.1778 -0.2794)
						)
						(arc
							(start 0.1778 -0.2794)
							(mid 0.249642 -0.249642)
							(end 0.2794 -0.1778)
						)
						(arc
							(start 0.2794 0.1778)
							(mid 0.249642 0.249642)
							(end 0.1778 0.2794)
						)
					)
					(width 0)
					(fill yes)
				)
			)
		)
	)
	(footprint ""
		(layer "B.Cu")
		(at 219.277692 -88.57361 90)
		(property "Reference" "C653"
			(at 0 0 90)
			(layer "B.SilkS")
			(hide yes)
			(effects
				(font
					(size 1.27 1.27)
				)
				(justify mirror)
			)
		)
		(property "Value" "SCD1U16V2KX-3GP"
			(at -1.1811 -2.7051 90)
			(unlocked yes)
			(layer "B.Fab")
			(hide yes)
			(effects
				(font
					(size 1.016 1.016)
					(thickness 0.1524)
				)
				(justify mirror)
			)
		)
		(property "Device Type" "C402H22"
			(at -1.1811 -4.2291 90)
			(unlocked yes)
			(layer "B.Fab")
			(hide yes)
			(effects
				(font
					(size 1.016 1.016)
					(thickness 0.1524)
				)
				(justify mirror)
			)
		)
		(duplicate_pad_numbers_are_jumpers no)
		(fp_rect
			(start 0.4318 0.9525)
			(end -0.4318 -0.9525)
			(stroke
				(width 0)
				(type default)
			)
			(fill no)
			(layer "B.CrtYd")
		)
		(fp_rect
			(start 0.4318 0.9525)
			(end -0.4318 -0.9525)
			(stroke
				(width 0)
				(type default)
			)
			(fill no)
			(layer "B.Fab")
		)
		(pad "1" smd custom
			(at 0 -0.4445 270)
			(size 0.1524 0.1524)
			(layers "B.Cu" "B.Mask" "B.Paste")
			(net "P3V3_M2_VBST_RC")
			(options
				(clearance outline)
				(anchor circle)
			)
			(primitives
				(gr_poly
					(pts
						(arc
							(start 0.3048 0.2032)
							(mid 0.275042 0.275042)
							(end 0.2032 0.3048)
						)
						(arc
							(start -0.2032 0.3048)
							(mid -0.275042 0.275042)
							(end -0.3048 0.2032)
						)
						(arc
							(start -0.3048 -0.2032)
							(mid -0.275042 -0.275042)
							(end -0.2032 -0.3048)
						)
						(arc
							(start 0.2032 -0.3048)
							(mid 0.275042 -0.275042)
							(end 0.3048 -0.2032)
						)
					)
					(width 0)
					(fill yes)
				)
			)
		)
		(pad "2" smd custom
			(at 0 0.4445 270)
			(size 0.1524 0.1524)
			(layers "B.Cu" "B.Mask" "B.Paste")
			(net "P3V3_M2_LL")
			(options
				(clearance outline)
				(anchor circle)
			)
			(primitives
				(gr_poly
					(pts
						(arc
							(start 0.3048 0.2032)
							(mid 0.275042 0.275042)
							(end 0.2032 0.3048)
						)
						(arc
							(start -0.2032 0.3048)
							(mid -0.275042 0.275042)
							(end -0.3048 0.2032)
						)
						(arc
							(start -0.3048 -0.2032)
							(mid -0.275042 -0.275042)
							(end -0.2032 -0.3048)
						)
						(arc
							(start 0.2032 -0.3048)
							(mid 0.275042 -0.275042)
							(end 0.3048 -0.2032)
						)
					)
					(width 0)
					(fill yes)
				)
			)
		)
	)
	(footprint ""
		(layer "B.Cu")
		(at 43.129454 -120.210072 -90)
		(property "Reference" "R344"
			(at 0 0 90)
			(layer "B.SilkS")
			(hide yes)
			(effects
				(font
					(size 1.27 1.27)
				)
				(justify mirror)
			)
		)
		(property "Value" "0R2J-2-GP"
			(at -0.064008 -3.993896 270)
			(unlocked yes)
			(layer "B.Fab")
			(hide yes)
			(effects
				(font
					(size 1.016 1.016)
					(thickness 0.1524)
				)
				(justify mirror)
			)
		)
		(property "Device Type" "R402H16"
			(at -0.064008 -5.517896 270)
			(unlocked yes)
			(layer "B.Fab")
			(hide yes)
			(effects
				(font
					(size 1.016 1.016)
					(thickness 0.1524)
				)
				(justify mirror)
			)
		)
		(duplicate_pad_numbers_are_jumpers no)
		(fp_line
			(start -0.508 -0.9398)
			(end 0.508 -0.9398)
			(stroke
				(width 0.1524)
				(type default)
			)
			(layer "B.SilkS")
		)
		(fp_line
			(start 0.508 -0.9398)
			(end 0.508 0.9398)
			(stroke
				(width 0.1524)
				(type default)
			)
			(layer "B.SilkS")
		)
		(fp_rect
			(start 0.508 0.9398)
			(end -0.508 -0.9398)
			(stroke
				(width 0)
				(type default)
			)
			(fill no)
			(layer "B.CrtYd")
		)
		(fp_rect
			(start 0.508 0.9398)
			(end -0.508 -0.9398)
			(stroke
				(width 0)
				(type default)
			)
			(fill no)
			(layer "B.Fab")
		)
		(pad "1" smd custom
			(at 0 -0.4445 90)
			(size 0.1397 0.1397)
			(layers "B.Cu" "B.Mask" "B.Paste")
			(net "TEMP_3_SCL")
			(options
				(clearance outline)
				(anchor circle)
			)
			(primitives
				(gr_poly
					(pts
						(arc
							(start -0.1778 0.2794)
							(mid -0.249642 0.249642)
							(end -0.2794 0.1778)
						)
						(arc
							(start -0.2794 -0.1778)
							(mid -0.249642 -0.249642)
							(end -0.1778 -0.2794)
						)
						(arc
							(start 0.1778 -0.2794)
							(mid 0.249642 -0.249642)
							(end 0.2794 -0.1778)
						)
						(arc
							(start 0.2794 0.1778)
							(mid 0.249642 0.249642)
							(end 0.1778 0.2794)
						)
					)
					(width 0)
					(fill yes)
				)
			)
		)
		(pad "2" smd custom
			(at 0 0.4445 90)
			(size 0.1397 0.1397)
			(layers "B.Cu" "B.Mask" "B.Paste")
			(net "I2C_IOM_SCL")
			(options
				(clearance outline)
				(anchor circle)
			)
			(primitives
				(gr_poly
					(pts
						(arc
							(start -0.1778 0.2794)
							(mid -0.249642 0.249642)
							(end -0.2794 0.1778)
						)
						(arc
							(start -0.2794 -0.1778)
							(mid -0.249642 -0.249642)
							(end -0.1778 -0.2794)
						)
						(arc
							(start 0.1778 -0.2794)
							(mid 0.249642 -0.249642)
							(end 0.2794 -0.1778)
						)
						(arc
							(start 0.2794 0.1778)
							(mid 0.249642 0.249642)
							(end 0.1778 0.2794)
						)
					)
					(width 0)
					(fill yes)
				)
			)
		)
	)
	(footprint ""
		(layer "B.Cu")
		(at 224.056956 -101.165152 -90)
		(property "Reference" "C635"
			(at 0 0 90)
			(layer "B.SilkS")
			(hide yes)
			(effects
				(font
					(size 1.27 1.27)
				)
				(justify mirror)
			)
		)
		(property "Value" "SC10U16V5KX-7-GP-U"
			(at 0.0762 -6.1214 270)
			(unlocked yes)
			(layer "B.Fab")
			(hide yes)
			(effects
				(font
					(size 1.016 1.016)
					(thickness 0.1524)
				)
				(justify mirror)
			)
		)
		(property "Device Type" "C805H58"
			(at 0.0762 -8.1534 270)
			(unlocked yes)
			(layer "B.Fab")
			(hide yes)
			(effects
				(font
					(size 1.016 1.016)
					(thickness 0.1524)
				)
				(justify mirror)
			)
		)
		(duplicate_pad_numbers_are_jumpers no)
		(fp_line
			(start -0.635 0)
			(end 0.635 0)
			(stroke
				(width 0.508)
				(type default)
			)
			(layer "B.SilkS")
		)
		(fp_rect
			(start 0.9652 1.778)
			(end -0.9652 -1.778)
			(stroke
				(width 0)
				(type default)
			)
			(fill no)
			(layer "B.CrtYd")
		)
		(fp_poly
			(pts
				(xy 0.9652 -1.778) (xy -0.9652 -1.778) (xy -0.9652 1.778) (xy 0.9652 1.778)
			)
			(stroke
				(width 0)
				(type default)
			)
			(fill no)
			(layer "B.Fab")
		)
		(pad "1" smd rect
			(at 0 -0.9652 90)
			(size 1.397 1.143)
			(layers "B.Cu" "B.Mask" "B.Paste")
			(net "P12V_STBY_VIN_U81")
		)
		(pad "2" smd rect
			(at 0 0.9652 90)
			(size 1.397 1.143)
			(layers "B.Cu" "B.Mask" "B.Paste")
			(net "GND")
		)
	)
	(footprint ""
		(layer "B.Cu")
		(at 45.300392 -144.335754 90)
		(property "Reference" "C56"
			(at 0 0 90)
			(layer "B.SilkS")
			(hide yes)
			(effects
				(font
					(size 1.27 1.27)
				)
				(justify mirror)
			)
		)
		(property "Value" "SC1U16V3KX-5GP"
			(at 0 -2.8194 90)
			(unlocked yes)
			(layer "B.Fab")
			(hide yes)
			(effects
				(font
					(size 1.016 1.016)
					(thickness 0.1524)
				)
				(justify mirror)
			)
		)
		(property "Device Type" "C603H36"
			(at 0 -4.3434 90)
			(unlocked yes)
			(layer "B.Fab")
			(hide yes)
			(effects
				(font
					(size 1.016 1.016)
					(thickness 0.1524)
				)
				(justify mirror)
			)
		)
		(duplicate_pad_numbers_are_jumpers no)
		(fp_line
			(start -0.508 0)
			(end 0.508 0)
			(stroke
				(width 0.2032)
				(type default)
			)
			(layer "B.SilkS")
		)
		(fp_rect
			(start 0.5842 1.3335)
			(end -0.5842 -1.3335)
			(stroke
				(width 0)
				(type default)
			)
			(fill no)
			(layer "B.CrtYd")
		)
		(fp_rect
			(start 0.5842 1.3335)
			(end -0.5842 -1.3335)
			(stroke
				(width 0)
				(type default)
			)
			(fill no)
			(layer "B.Fab")
		)
		(pad "1" smd custom
			(at 0 -0.762 270)
			(size 0.2159 0.2159)
			(layers "B.Cu" "B.Mask" "B.Paste")
			(net "P1V2_STBY")
			(options
				(clearance outline)
				(anchor circle)
			)
			(primitives
				(gr_poly
					(pts
						(arc
							(start -0.3302 0.4318)
							(mid -0.402042 0.402042)
							(end -0.4318 0.3302)
						)
						(arc
							(start -0.4318 -0.3302)
							(mid -0.402042 -0.402042)
							(end -0.3302 -0.4318)
						)
						(arc
							(start 0.3302 -0.4318)
							(mid 0.402042 -0.402042)
							(end 0.4318 -0.3302)
						)
						(arc
							(start 0.4318 0.3302)
							(mid 0.402042 0.402042)
							(end 0.3302 0.4318)
						)
					)
					(width 0)
					(fill yes)
				)
			)
		)
		(pad "2" smd custom
			(at 0 0.762 270)
			(size 0.2159 0.2159)
			(layers "B.Cu" "B.Mask" "B.Paste")
			(net "GND")
			(options
				(clearance outline)
				(anchor circle)
			)
			(primitives
				(gr_poly
					(pts
						(arc
							(start -0.3302 0.4318)
							(mid -0.402042 0.402042)
							(end -0.4318 0.3302)
						)
						(arc
							(start -0.4318 -0.3302)
							(mid -0.402042 -0.402042)
							(end -0.3302 -0.4318)
						)
						(arc
							(start 0.3302 -0.4318)
							(mid 0.402042 -0.402042)
							(end 0.4318 -0.3302)
						)
						(arc
							(start 0.4318 0.3302)
							(mid 0.402042 0.402042)
							(end 0.3302 0.4318)
						)
					)
					(width 0)
					(fill yes)
				)
			)
		)
	)
	(footprint ""
		(layer "B.Cu")
		(at 19.144742 -129.077466 180)
		(property "Reference" "R235"
			(at 0 0 0)
			(layer "B.SilkS")
			(hide yes)
			(effects
				(font
					(size 1.27 1.27)
				)
				(justify mirror)
			)
		)
		(property "Value" "120R2F-GP"
			(at -0.064008 -3.993896 180)
			(unlocked yes)
			(layer "B.Fab")
			(hide yes)
			(effects
				(font
					(size 1.016 1.016)
					(thickness 0.1524)
				)
				(justify mirror)
			)
		)
		(property "Device Type" "R402H16"
			(at -0.064008 -5.517896 180)
			(unlocked yes)
			(layer "B.Fab")
			(hide yes)
			(effects
				(font
					(size 1.016 1.016)
					(thickness 0.1524)
				)
				(justify mirror)
			)
		)
		(duplicate_pad_numbers_are_jumpers no)
		(fp_line
			(start 0.508 -0.9398)
			(end 0.508 0.9398)
			(stroke
				(width 0.1524)
				(type default)
			)
			(layer "B.SilkS")
		)
		(fp_line
			(start -0.508 -0.9398)
			(end 0.508 -0.9398)
			(stroke
				(width 0.1524)
				(type default)
			)
			(layer "B.SilkS")
		)
		(fp_rect
			(start 0.508 0.9398)
			(end -0.508 -0.9398)
			(stroke
				(width 0)
				(type default)
			)
			(fill no)
			(layer "B.CrtYd")
		)
		(fp_rect
			(start 0.508 0.9398)
			(end -0.508 -0.9398)
			(stroke
				(width 0)
				(type default)
			)
			(fill no)
			(layer "B.Fab")
		)
		(pad "1" smd custom
			(at 0 -0.4445)
			(size 0.1397 0.1397)
			(layers "B.Cu" "B.Mask" "B.Paste")
			(net "GND")
			(options
				(clearance outline)
				(anchor circle)
			)
			(primitives
				(gr_poly
					(pts
						(arc
							(start -0.1778 0.2794)
							(mid -0.249642 0.249642)
							(end -0.2794 0.1778)
						)
						(arc
							(start -0.2794 -0.1778)
							(mid -0.249642 -0.249642)
							(end -0.1778 -0.2794)
						)
						(arc
							(start 0.1778 -0.2794)
							(mid 0.249642 -0.249642)
							(end 0.2794 -0.1778)
						)
						(arc
							(start 0.2794 0.1778)
							(mid 0.249642 0.249642)
							(end 0.1778 0.2794)
						)
					)
					(width 0)
					(fill yes)
				)
			)
		)
		(pad "2" smd custom
			(at 0 0.4445)
			(size 0.1397 0.1397)
			(layers "B.Cu" "B.Mask" "B.Paste")
			(net "MEMA_1")
			(options
				(clearance outline)
				(anchor circle)
			)
			(primitives
				(gr_poly
					(pts
						(arc
							(start -0.1778 0.2794)
							(mid -0.249642 0.249642)
							(end -0.2794 0.1778)
						)
						(arc
							(start -0.2794 -0.1778)
							(mid -0.249642 -0.249642)
							(end -0.1778 -0.2794)
						)
						(arc
							(start 0.1778 -0.2794)
							(mid 0.249642 -0.249642)
							(end 0.2794 -0.1778)
						)
						(arc
							(start 0.2794 0.1778)
							(mid 0.249642 0.249642)
							(end 0.1778 0.2794)
						)
					)
					(width 0)
					(fill yes)
				)
			)
		)
	)
	(footprint ""
		(layer "B.Cu")
		(at 224.989644 -74.10323 90)
		(property "Reference" "C650"
			(at 0 0 90)
			(layer "B.SilkS")
			(hide yes)
			(effects
				(font
					(size 1.27 1.27)
				)
				(justify mirror)
			)
		)
		(property "Value" "SC10U6D3V5KX-4GP"
			(at 0.0762 -6.1214 90)
			(unlocked yes)
			(layer "B.Fab")
			(hide yes)
			(effects
				(font
					(size 1.016 1.016)
					(thickness 0.1524)
				)
				(justify mirror)
			)
		)
		(property "Device Type" "C805H58"
			(at 0.0762 -8.1534 90)
			(unlocked yes)
			(layer "B.Fab")
			(hide yes)
			(effects
				(font
					(size 1.016 1.016)
					(thickness 0.1524)
				)
				(justify mirror)
			)
		)
		(duplicate_pad_numbers_are_jumpers no)
		(fp_line
			(start -0.635 0)
			(end 0.635 0)
			(stroke
				(width 0.508)
				(type default)
			)
			(layer "B.SilkS")
		)
		(fp_rect
			(start 0.9652 1.778)
			(end -0.9652 -1.778)
			(stroke
				(width 0)
				(type default)
			)
			(fill no)
			(layer "B.CrtYd")
		)
		(fp_poly
			(pts
				(xy 0.9652 -1.778) (xy -0.9652 -1.778) (xy -0.9652 1.778) (xy 0.9652 1.778)
			)
			(stroke
				(width 0)
				(type default)
			)
			(fill no)
			(layer "B.Fab")
		)
		(pad "1" smd rect
			(at 0 -0.9652 270)
			(size 1.397 1.143)
			(layers "B.Cu" "B.Mask" "B.Paste")
			(net "P3V3_M2")
		)
		(pad "2" smd rect
			(at 0 0.9652 270)
			(size 1.397 1.143)
			(layers "B.Cu" "B.Mask" "B.Paste")
			(net "GND")
		)
	)
	(footprint ""
		(layer "B.Cu")
		(at 92.45092 -140.05306 -90)
		(property "Reference" "C137"
			(at 0 0 90)
			(layer "B.SilkS")
			(hide yes)
			(effects
				(font
					(size 1.27 1.27)
				)
				(justify mirror)
			)
		)
		(property "Value" "SCD1U16V2KX-3GP"
			(at -1.1811 -2.7051 270)
			(unlocked yes)
			(layer "B.Fab")
			(hide yes)
			(effects
				(font
					(size 1.016 1.016)
					(thickness 0.1524)
				)
				(justify mirror)
			)
		)
		(property "Device Type" "C402H22"
			(at -1.1811 -4.2291 270)
			(unlocked yes)
			(layer "B.Fab")
			(hide yes)
			(effects
				(font
					(size 1.016 1.016)
					(thickness 0.1524)
				)
				(justify mirror)
			)
		)
		(duplicate_pad_numbers_are_jumpers no)
		(fp_rect
			(start 0.4318 0.9525)
			(end -0.4318 -0.9525)
			(stroke
				(width 0)
				(type default)
			)
			(fill no)
			(layer "B.CrtYd")
		)
		(fp_rect
			(start 0.4318 0.9525)
			(end -0.4318 -0.9525)
			(stroke
				(width 0)
				(type default)
			)
			(fill no)
			(layer "B.Fab")
		)
		(pad "1" smd custom
			(at 0 -0.4445 90)
			(size 0.1524 0.1524)
			(layers "B.Cu" "B.Mask" "B.Paste")
			(net "DEBUG_CARD_PRSNT")
			(options
				(clearance outline)
				(anchor circle)
			)
			(primitives
				(gr_poly
					(pts
						(arc
							(start 0.3048 0.2032)
							(mid 0.275042 0.275042)
							(end 0.2032 0.3048)
						)
						(arc
							(start -0.2032 0.3048)
							(mid -0.275042 0.275042)
							(end -0.3048 0.2032)
						)
						(arc
							(start -0.3048 -0.2032)
							(mid -0.275042 -0.275042)
							(end -0.2032 -0.3048)
						)
						(arc
							(start 0.2032 -0.3048)
							(mid 0.275042 -0.275042)
							(end 0.3048 -0.2032)
						)
					)
					(width 0)
					(fill yes)
				)
			)
		)
		(pad "2" smd custom
			(at 0 0.4445 90)
			(size 0.1524 0.1524)
			(layers "B.Cu" "B.Mask" "B.Paste")
			(net "GND")
			(options
				(clearance outline)
				(anchor circle)
			)
			(primitives
				(gr_poly
					(pts
						(arc
							(start 0.3048 0.2032)
							(mid 0.275042 0.275042)
							(end 0.2032 0.3048)
						)
						(arc
							(start -0.2032 0.3048)
							(mid -0.275042 0.275042)
							(end -0.3048 0.2032)
						)
						(arc
							(start -0.3048 -0.2032)
							(mid -0.275042 -0.275042)
							(end -0.2032 -0.3048)
						)
						(arc
							(start 0.2032 -0.3048)
							(mid 0.275042 -0.275042)
							(end 0.3048 -0.2032)
						)
					)
					(width 0)
					(fill yes)
				)
			)
		)
	)
	(footprint ""
		(layer "B.Cu")
		(at 24.869902 -131.007358 180)
		(property "Reference" "R245"
			(at 0 0 0)
			(layer "B.SilkS")
			(hide yes)
			(effects
				(font
					(size 1.27 1.27)
				)
				(justify mirror)
			)
		)
		(property "Value" "120R2F-GP"
			(at -0.064008 -3.993896 180)
			(unlocked yes)
			(layer "B.Fab")
			(hide yes)
			(effects
				(font
					(size 1.016 1.016)
					(thickness 0.1524)
				)
				(justify mirror)
			)
		)
		(property "Device Type" "R402H16"
			(at -0.064008 -5.517896 180)
			(unlocked yes)
			(layer "B.Fab")
			(hide yes)
			(effects
				(font
					(size 1.016 1.016)
					(thickness 0.1524)
				)
				(justify mirror)
			)
		)
		(duplicate_pad_numbers_are_jumpers no)
		(fp_line
			(start 0.508 -0.9398)
			(end 0.508 0.9398)
			(stroke
				(width 0.1524)
				(type default)
			)
			(layer "B.SilkS")
		)
		(fp_line
			(start -0.508 -0.9398)
			(end 0.508 -0.9398)
			(stroke
				(width 0.1524)
				(type default)
			)
			(layer "B.SilkS")
		)
		(fp_rect
			(start 0.508 0.9398)
			(end -0.508 -0.9398)
			(stroke
				(width 0)
				(type default)
			)
			(fill no)
			(layer "B.CrtYd")
		)
		(fp_rect
			(start 0.508 0.9398)
			(end -0.508 -0.9398)
			(stroke
				(width 0)
				(type default)
			)
			(fill no)
			(layer "B.Fab")
		)
		(pad "1" smd custom
			(at 0 -0.4445)
			(size 0.1397 0.1397)
			(layers "B.Cu" "B.Mask" "B.Paste")
			(net "MEMA_5")
			(options
				(clearance outline)
				(anchor circle)
			)
			(primitives
				(gr_poly
					(pts
						(arc
							(start -0.1778 0.2794)
							(mid -0.249642 0.249642)
							(end -0.2794 0.1778)
						)
						(arc
							(start -0.2794 -0.1778)
							(mid -0.249642 -0.249642)
							(end -0.1778 -0.2794)
						)
						(arc
							(start 0.1778 -0.2794)
							(mid 0.249642 -0.249642)
							(end 0.2794 -0.1778)
						)
						(arc
							(start 0.2794 0.1778)
							(mid 0.249642 0.249642)
							(end 0.1778 0.2794)
						)
					)
					(width 0)
					(fill yes)
				)
			)
		)
		(pad "2" smd custom
			(at 0 0.4445)
			(size 0.1397 0.1397)
			(layers "B.Cu" "B.Mask" "B.Paste")
			(net "P1V2_STBY")
			(options
				(clearance outline)
				(anchor circle)
			)
			(primitives
				(gr_poly
					(pts
						(arc
							(start -0.1778 0.2794)
							(mid -0.249642 0.249642)
							(end -0.2794 0.1778)
						)
						(arc
							(start -0.2794 -0.1778)
							(mid -0.249642 -0.249642)
							(end -0.1778 -0.2794)
						)
						(arc
							(start 0.1778 -0.2794)
							(mid 0.249642 -0.249642)
							(end 0.2794 -0.1778)
						)
						(arc
							(start 0.2794 0.1778)
							(mid 0.249642 0.249642)
							(end 0.1778 0.2794)
						)
					)
					(width 0)
					(fill yes)
				)
			)
		)
	)
	(footprint ""
		(layer "B.Cu")
		(at 37.521642 -155.929584)
		(property "Reference" "R777"
			(at 0 0 0)
			(layer "B.SilkS")
			(hide yes)
			(effects
				(font
					(size 1.27 1.27)
				)
				(justify mirror)
			)
		)
		(property "Value" "1KR2F-3-GP"
			(at -0.064008 -3.993896 0)
			(unlocked yes)
			(layer "B.Fab")
			(hide yes)
			(effects
				(font
					(size 1.016 1.016)
					(thickness 0.1524)
				)
				(justify mirror)
			)
		)
		(property "Device Type" "R402H16"
			(at -0.064008 -5.517896 0)
			(unlocked yes)
			(layer "B.Fab")
			(hide yes)
			(effects
				(font
					(size 1.016 1.016)
					(thickness 0.1524)
				)
				(justify mirror)
			)
		)
		(duplicate_pad_numbers_are_jumpers no)
		(fp_line
			(start -0.508 -0.9398)
			(end 0.508 -0.9398)
			(stroke
				(width 0.1524)
				(type default)
			)
			(layer "B.SilkS")
		)
		(fp_line
			(start 0.508 -0.9398)
			(end 0.508 0.9398)
			(stroke
				(width 0.1524)
				(type default)
			)
			(layer "B.SilkS")
		)
		(fp_rect
			(start 0.508 0.9398)
			(end -0.508 -0.9398)
			(stroke
				(width 0)
				(type default)
			)
			(fill no)
			(layer "B.CrtYd")
		)
		(fp_rect
			(start 0.508 0.9398)
			(end -0.508 -0.9398)
			(stroke
				(width 0)
				(type default)
			)
			(fill no)
			(layer "B.Fab")
		)
		(pad "1" smd custom
			(at 0 -0.4445 180)
			(size 0.1397 0.1397)
			(layers "B.Cu" "B.Mask" "B.Paste")
			(net "ADC_P1V2_STBY")
			(options
				(clearance outline)
				(anchor circle)
			)
			(primitives
				(gr_poly
					(pts
						(arc
							(start -0.1778 0.2794)
							(mid -0.249642 0.249642)
							(end -0.2794 0.1778)
						)
						(arc
							(start -0.2794 -0.1778)
							(mid -0.249642 -0.249642)
							(end -0.1778 -0.2794)
						)
						(arc
							(start 0.1778 -0.2794)
							(mid 0.249642 -0.249642)
							(end 0.2794 -0.1778)
						)
						(arc
							(start 0.2794 0.1778)
							(mid 0.249642 0.249642)
							(end 0.1778 0.2794)
						)
					)
					(width 0)
					(fill yes)
				)
			)
		)
		(pad "2" smd custom
			(at 0 0.4445 180)
			(size 0.1397 0.1397)
			(layers "B.Cu" "B.Mask" "B.Paste")
			(net "GND")
			(options
				(clearance outline)
				(anchor circle)
			)
			(primitives
				(gr_poly
					(pts
						(arc
							(start -0.1778 0.2794)
							(mid -0.249642 0.249642)
							(end -0.2794 0.1778)
						)
						(arc
							(start -0.2794 -0.1778)
							(mid -0.249642 -0.249642)
							(end -0.1778 -0.2794)
						)
						(arc
							(start 0.1778 -0.2794)
							(mid 0.249642 -0.249642)
							(end 0.2794 -0.1778)
						)
						(arc
							(start 0.2794 0.1778)
							(mid 0.249642 0.249642)
							(end 0.1778 0.2794)
						)
					)
					(width 0)
					(fill yes)
				)
			)
		)
	)
	(footprint ""
		(layer "B.Cu")
		(at 174.9552 -127.053086 90)
		(property "Reference" "C624"
			(at 0 0 90)
			(layer "B.SilkS")
			(hide yes)
			(effects
				(font
					(size 1.27 1.27)
				)
				(justify mirror)
			)
		)
		(property "Value" "SCD1U16V2KX-3GP"
			(at -1.1811 -2.7051 90)
			(unlocked yes)
			(layer "B.Fab")
			(hide yes)
			(effects
				(font
					(size 1.016 1.016)
					(thickness 0.1524)
				)
				(justify mirror)
			)
		)
		(property "Device Type" "C402H22"
			(at -1.1811 -4.2291 90)
			(unlocked yes)
			(layer "B.Fab")
			(hide yes)
			(effects
				(font
					(size 1.016 1.016)
					(thickness 0.1524)
				)
				(justify mirror)
			)
		)
		(duplicate_pad_numbers_are_jumpers no)
		(fp_rect
			(start 0.4318 0.9525)
			(end -0.4318 -0.9525)
			(stroke
				(width 0)
				(type default)
			)
			(fill no)
			(layer "B.CrtYd")
		)
		(fp_rect
			(start 0.4318 0.9525)
			(end -0.4318 -0.9525)
			(stroke
				(width 0)
				(type default)
			)
			(fill no)
			(layer "B.Fab")
		)
		(pad "1" smd custom
			(at 0 -0.4445 270)
			(size 0.1524 0.1524)
			(layers "B.Cu" "B.Mask" "B.Paste")
			(net "P3V3_M2")
			(options
				(clearance outline)
				(anchor circle)
			)
			(primitives
				(gr_poly
					(pts
						(arc
							(start 0.3048 0.2032)
							(mid 0.275042 0.275042)
							(end 0.2032 0.3048)
						)
						(arc
							(start -0.2032 0.3048)
							(mid -0.275042 0.275042)
							(end -0.3048 0.2032)
						)
						(arc
							(start -0.3048 -0.2032)
							(mid -0.275042 -0.275042)
							(end -0.2032 -0.3048)
						)
						(arc
							(start 0.2032 -0.3048)
							(mid 0.275042 -0.275042)
							(end 0.3048 -0.2032)
						)
					)
					(width 0)
					(fill yes)
				)
			)
		)
		(pad "2" smd custom
			(at 0 0.4445 270)
			(size 0.1524 0.1524)
			(layers "B.Cu" "B.Mask" "B.Paste")
			(net "GND")
			(options
				(clearance outline)
				(anchor circle)
			)
			(primitives
				(gr_poly
					(pts
						(arc
							(start 0.3048 0.2032)
							(mid 0.275042 0.275042)
							(end 0.2032 0.3048)
						)
						(arc
							(start -0.2032 0.3048)
							(mid -0.275042 0.275042)
							(end -0.3048 0.2032)
						)
						(arc
							(start -0.3048 -0.2032)
							(mid -0.275042 -0.275042)
							(end -0.2032 -0.3048)
						)
						(arc
							(start 0.2032 -0.3048)
							(mid 0.275042 -0.275042)
							(end 0.3048 -0.2032)
						)
					)
					(width 0)
					(fill yes)
				)
			)
		)
	)
	(footprint ""
		(layer "B.Cu")
		(at 91.895168 -158.915608 90)
		(property "Reference" "TP4"
			(at 0 0 90)
			(layer "B.SilkS")
			(hide yes)
			(effects
				(font
					(size 1.27 1.27)
				)
				(justify mirror)
			)
		)
		(property "Value" "TPAD28-2-GP"
			(at 0.0127 -1.6637 90)
			(unlocked yes)
			(layer "B.Fab")
			(hide yes)
			(effects
				(font
					(size 1.016 1.016)
					(thickness 0.1524)
				)
				(justify mirror)
			)
		)
		(property "Device Type" "TPAD28"
			(at 0.0127 -3.1877 90)
			(unlocked yes)
			(layer "B.Fab")
			(hide yes)
			(effects
				(font
					(size 1.016 1.016)
					(thickness 0.1524)
				)
				(justify mirror)
			)
		)
		(duplicate_pad_numbers_are_jumpers no)
		(fp_poly
			(pts
				(arc
					(start 0 0.3556)
					(mid 0 -0.3556)
					(end 0 0.3556)
				)
			)
			(stroke
				(width 0)
				(type default)
			)
			(fill no)
			(layer "B.CrtYd")
		)
		(fp_poly
			(pts
				(arc
					(start 0 0.6096)
					(mid 0 -0.6096)
					(end 0 0.6096)
				)
			)
			(stroke
				(width 0)
				(type default)
			)
			(fill no)
			(layer "B.Fab")
		)
		(pad "1" smd circle
			(at 0 0 270)
			(size 0.7112 0.7112)
			(layers "B.Cu" "B.Mask" "B.Paste")
			(net "PLLFILT")
		)
	)
	(footprint ""
		(layer "B.Cu")
		(at 32.5374 -161.2646 90)
		(property "Reference" "R698"
			(at 0 0 90)
			(layer "B.SilkS")
			(hide yes)
			(effects
				(font
					(size 1.27 1.27)
				)
				(justify mirror)
			)
		)
		(property "Value" "4K7R2F-GP"
			(at -0.064008 -3.993896 90)
			(unlocked yes)
			(layer "B.Fab")
			(hide yes)
			(effects
				(font
					(size 1.016 1.016)
					(thickness 0.1524)
				)
				(justify mirror)
			)
		)
		(property "Device Type" "R402H16"
			(at -0.064008 -5.517896 90)
			(unlocked yes)
			(layer "B.Fab")
			(hide yes)
			(effects
				(font
					(size 1.016 1.016)
					(thickness 0.1524)
				)
				(justify mirror)
			)
		)
		(duplicate_pad_numbers_are_jumpers no)
		(fp_line
			(start 0.508 -0.9398)
			(end 0.508 0.9398)
			(stroke
				(width 0.1524)
				(type default)
			)
			(layer "B.SilkS")
		)
		(fp_line
			(start -0.508 -0.9398)
			(end 0.508 -0.9398)
			(stroke
				(width 0.1524)
				(type default)
			)
			(layer "B.SilkS")
		)
		(fp_rect
			(start 0.508 0.9398)
			(end -0.508 -0.9398)
			(stroke
				(width 0)
				(type default)
			)
			(fill no)
			(layer "B.CrtYd")
		)
		(fp_rect
			(start 0.508 0.9398)
			(end -0.508 -0.9398)
			(stroke
				(width 0)
				(type default)
			)
			(fill no)
			(layer "B.Fab")
		)
		(pad "1" smd custom
			(at 0 -0.4445 270)
			(size 0.1397 0.1397)
			(layers "B.Cu" "B.Mask" "B.Paste")
			(net "P3V3_STBY")
			(options
				(clearance outline)
				(anchor circle)
			)
			(primitives
				(gr_poly
					(pts
						(arc
							(start -0.1778 0.2794)
							(mid -0.249642 0.249642)
							(end -0.2794 0.1778)
						)
						(arc
							(start -0.2794 -0.1778)
							(mid -0.249642 -0.249642)
							(end -0.1778 -0.2794)
						)
						(arc
							(start 0.1778 -0.2794)
							(mid 0.249642 -0.249642)
							(end 0.2794 -0.1778)
						)
						(arc
							(start 0.2794 0.1778)
							(mid 0.249642 0.249642)
							(end 0.1778 0.2794)
						)
					)
					(width 0)
					(fill yes)
				)
			)
		)
		(pad "2" smd custom
			(at 0 0.4445 270)
			(size 0.1397 0.1397)
			(layers "B.Cu" "B.Mask" "B.Paste")
			(net "IOM_TYPE1")
			(options
				(clearance outline)
				(anchor circle)
			)
			(primitives
				(gr_poly
					(pts
						(arc
							(start -0.1778 0.2794)
							(mid -0.249642 0.249642)
							(end -0.2794 0.1778)
						)
						(arc
							(start -0.2794 -0.1778)
							(mid -0.249642 -0.249642)
							(end -0.1778 -0.2794)
						)
						(arc
							(start 0.1778 -0.2794)
							(mid 0.249642 -0.249642)
							(end 0.2794 -0.1778)
						)
						(arc
							(start 0.2794 0.1778)
							(mid 0.249642 0.249642)
							(end 0.1778 0.2794)
						)
					)
					(width 0)
					(fill yes)
				)
			)
		)
	)
	(footprint ""
		(layer "B.Cu")
		(at 24.666702 -143.811244 180)
		(property "Reference" "C69"
			(at 0 0 0)
			(layer "B.SilkS")
			(hide yes)
			(effects
				(font
					(size 1.27 1.27)
				)
				(justify mirror)
			)
		)
		(property "Value" "SCD1U16V2KX-3GP"
			(at -1.1811 -2.7051 180)
			(unlocked yes)
			(layer "B.Fab")
			(hide yes)
			(effects
				(font
					(size 1.016 1.016)
					(thickness 0.1524)
				)
				(justify mirror)
			)
		)
		(property "Device Type" "C402H22"
			(at -1.1811 -4.2291 180)
			(unlocked yes)
			(layer "B.Fab")
			(hide yes)
			(effects
				(font
					(size 1.016 1.016)
					(thickness 0.1524)
				)
				(justify mirror)
			)
		)
		(duplicate_pad_numbers_are_jumpers no)
		(fp_rect
			(start 0.4318 0.9525)
			(end -0.4318 -0.9525)
			(stroke
				(width 0)
				(type default)
			)
			(fill no)
			(layer "B.CrtYd")
		)
		(fp_rect
			(start 0.4318 0.9525)
			(end -0.4318 -0.9525)
			(stroke
				(width 0)
				(type default)
			)
			(fill no)
			(layer "B.Fab")
		)
		(pad "1" smd custom
			(at 0 -0.4445)
			(size 0.1524 0.1524)
			(layers "B.Cu" "B.Mask" "B.Paste")
			(net "GND")
			(options
				(clearance outline)
				(anchor circle)
			)
			(primitives
				(gr_poly
					(pts
						(arc
							(start 0.3048 0.2032)
							(mid 0.275042 0.275042)
							(end 0.2032 0.3048)
						)
						(arc
							(start -0.2032 0.3048)
							(mid -0.275042 0.275042)
							(end -0.3048 0.2032)
						)
						(arc
							(start -0.3048 -0.2032)
							(mid -0.275042 -0.275042)
							(end -0.2032 -0.3048)
						)
						(arc
							(start 0.2032 -0.3048)
							(mid 0.275042 -0.275042)
							(end 0.3048 -0.2032)
						)
					)
					(width 0)
					(fill yes)
				)
			)
		)
		(pad "2" smd custom
			(at 0 0.4445)
			(size 0.1524 0.1524)
			(layers "B.Cu" "B.Mask" "B.Paste")
			(net "P1V2_STBY")
			(options
				(clearance outline)
				(anchor circle)
			)
			(primitives
				(gr_poly
					(pts
						(arc
							(start 0.3048 0.2032)
							(mid 0.275042 0.275042)
							(end 0.2032 0.3048)
						)
						(arc
							(start -0.2032 0.3048)
							(mid -0.275042 0.275042)
							(end -0.3048 0.2032)
						)
						(arc
							(start -0.3048 -0.2032)
							(mid -0.275042 -0.275042)
							(end -0.2032 -0.3048)
						)
						(arc
							(start 0.2032 -0.3048)
							(mid 0.275042 -0.275042)
							(end 0.3048 -0.2032)
						)
					)
					(width 0)
					(fill yes)
				)
			)
		)
	)
	(footprint ""
		(layer "B.Cu")
		(at 210.753706 -86.56828 90)
		(property "Reference" "R801"
			(at 0 0 90)
			(layer "B.SilkS")
			(hide yes)
			(effects
				(font
					(size 1.27 1.27)
				)
				(justify mirror)
			)
		)
		(property "Value" "4K7R2F-GP"
			(at -0.064008 -3.993896 90)
			(unlocked yes)
			(layer "B.Fab")
			(hide yes)
			(effects
				(font
					(size 1.016 1.016)
					(thickness 0.1524)
				)
				(justify mirror)
			)
		)
		(property "Device Type" "R402H16"
			(at -0.064008 -5.517896 90)
			(unlocked yes)
			(layer "B.Fab")
			(hide yes)
			(effects
				(font
					(size 1.016 1.016)
					(thickness 0.1524)
				)
				(justify mirror)
			)
		)
		(duplicate_pad_numbers_are_jumpers no)
		(fp_line
			(start 0.508 -0.9398)
			(end 0.508 0.9398)
			(stroke
				(width 0.1524)
				(type default)
			)
			(layer "B.SilkS")
		)
		(fp_line
			(start -0.508 -0.9398)
			(end 0.508 -0.9398)
			(stroke
				(width 0.1524)
				(type default)
			)
			(layer "B.SilkS")
		)
		(fp_rect
			(start 0.508 0.9398)
			(end -0.508 -0.9398)
			(stroke
				(width 0)
				(type default)
			)
			(fill no)
			(layer "B.CrtYd")
		)
		(fp_rect
			(start 0.508 0.9398)
			(end -0.508 -0.9398)
			(stroke
				(width 0)
				(type default)
			)
			(fill no)
			(layer "B.Fab")
		)
		(pad "1" smd custom
			(at 0 -0.4445 270)
			(size 0.1397 0.1397)
			(layers "B.Cu" "B.Mask" "B.Paste")
			(net "Q20_G")
			(options
				(clearance outline)
				(anchor circle)
			)
			(primitives
				(gr_poly
					(pts
						(arc
							(start -0.1778 0.2794)
							(mid -0.249642 0.249642)
							(end -0.2794 0.1778)
						)
						(arc
							(start -0.2794 -0.1778)
							(mid -0.249642 -0.249642)
							(end -0.1778 -0.2794)
						)
						(arc
							(start 0.1778 -0.2794)
							(mid 0.249642 -0.249642)
							(end 0.2794 -0.1778)
						)
						(arc
							(start 0.2794 0.1778)
							(mid 0.249642 0.249642)
							(end 0.1778 0.2794)
						)
					)
					(width 0)
					(fill yes)
				)
			)
		)
		(pad "2" smd custom
			(at 0 0.4445 270)
			(size 0.1397 0.1397)
			(layers "B.Cu" "B.Mask" "B.Paste")
			(net "P3V3")
			(options
				(clearance outline)
				(anchor circle)
			)
			(primitives
				(gr_poly
					(pts
						(arc
							(start -0.1778 0.2794)
							(mid -0.249642 0.249642)
							(end -0.2794 0.1778)
						)
						(arc
							(start -0.2794 -0.1778)
							(mid -0.249642 -0.249642)
							(end -0.1778 -0.2794)
						)
						(arc
							(start 0.1778 -0.2794)
							(mid 0.249642 -0.249642)
							(end 0.2794 -0.1778)
						)
						(arc
							(start 0.2794 0.1778)
							(mid 0.249642 0.249642)
							(end 0.1778 0.2794)
						)
					)
					(width 0)
					(fill yes)
				)
			)
		)
	)
	(footprint ""
		(layer "B.Cu")
		(at 58.7756 -128.3462 -90)
		(property "Reference" "R708"
			(at 0 0 90)
			(layer "B.SilkS")
			(hide yes)
			(effects
				(font
					(size 1.27 1.27)
				)
				(justify mirror)
			)
		)
		(property "Value" "10KR2F-2-GP"
			(at -0.064008 -3.993896 270)
			(unlocked yes)
			(layer "B.Fab")
			(hide yes)
			(effects
				(font
					(size 1.016 1.016)
					(thickness 0.1524)
				)
				(justify mirror)
			)
		)
		(property "Device Type" "R402H16"
			(at -0.064008 -5.517896 270)
			(unlocked yes)
			(layer "B.Fab")
			(hide yes)
			(effects
				(font
					(size 1.016 1.016)
					(thickness 0.1524)
				)
				(justify mirror)
			)
		)
		(duplicate_pad_numbers_are_jumpers no)
		(fp_line
			(start -0.508 -0.9398)
			(end 0.508 -0.9398)
			(stroke
				(width 0.1524)
				(type default)
			)
			(layer "B.SilkS")
		)
		(fp_line
			(start 0.508 -0.9398)
			(end 0.508 0.9398)
			(stroke
				(width 0.1524)
				(type default)
			)
			(layer "B.SilkS")
		)
		(fp_rect
			(start 0.508 0.9398)
			(end -0.508 -0.9398)
			(stroke
				(width 0)
				(type default)
			)
			(fill no)
			(layer "B.CrtYd")
		)
		(fp_rect
			(start 0.508 0.9398)
			(end -0.508 -0.9398)
			(stroke
				(width 0)
				(type default)
			)
			(fill no)
			(layer "B.Fab")
		)
		(pad "1" smd custom
			(at 0 -0.4445 90)
			(size 0.1397 0.1397)
			(layers "B.Cu" "B.Mask" "B.Paste")
			(net "SCC_STBY_PWR_EN")
			(options
				(clearance outline)
				(anchor circle)
			)
			(primitives
				(gr_poly
					(pts
						(arc
							(start -0.1778 0.2794)
							(mid -0.249642 0.249642)
							(end -0.2794 0.1778)
						)
						(arc
							(start -0.2794 -0.1778)
							(mid -0.249642 -0.249642)
							(end -0.1778 -0.2794)
						)
						(arc
							(start 0.1778 -0.2794)
							(mid 0.249642 -0.249642)
							(end 0.2794 -0.1778)
						)
						(arc
							(start 0.2794 0.1778)
							(mid 0.249642 0.249642)
							(end 0.1778 0.2794)
						)
					)
					(width 0)
					(fill yes)
				)
			)
		)
		(pad "2" smd custom
			(at 0 0.4445 90)
			(size 0.1397 0.1397)
			(layers "B.Cu" "B.Mask" "B.Paste")
			(net "GND")
			(options
				(clearance outline)
				(anchor circle)
			)
			(primitives
				(gr_poly
					(pts
						(arc
							(start -0.1778 0.2794)
							(mid -0.249642 0.249642)
							(end -0.2794 0.1778)
						)
						(arc
							(start -0.2794 -0.1778)
							(mid -0.249642 -0.249642)
							(end -0.1778 -0.2794)
						)
						(arc
							(start 0.1778 -0.2794)
							(mid 0.249642 -0.249642)
							(end 0.2794 -0.1778)
						)
						(arc
							(start 0.2794 0.1778)
							(mid 0.249642 0.249642)
							(end 0.1778 0.2794)
						)
					)
					(width 0)
					(fill yes)
				)
			)
		)
	)
	(footprint ""
		(layer "B.Cu")
		(at 229.02926 -101.966776 180)
		(property "Reference" "C637"
			(at 0 0 0)
			(layer "B.SilkS")
			(hide yes)
			(effects
				(font
					(size 1.27 1.27)
				)
				(justify mirror)
			)
		)
		(property "Value" "SC10U16V5KX-7-GP-U"
			(at 0.0762 -6.1214 180)
			(unlocked yes)
			(layer "B.Fab")
			(hide yes)
			(effects
				(font
					(size 1.016 1.016)
					(thickness 0.1524)
				)
				(justify mirror)
			)
		)
		(property "Device Type" "C805H58"
			(at 0.0762 -8.1534 180)
			(unlocked yes)
			(layer "B.Fab")
			(hide yes)
			(effects
				(font
					(size 1.016 1.016)
					(thickness 0.1524)
				)
				(justify mirror)
			)
		)
		(duplicate_pad_numbers_are_jumpers no)
		(fp_line
			(start -0.635 0)
			(end 0.635 0)
			(stroke
				(width 0.508)
				(type default)
			)
			(layer "B.SilkS")
		)
		(fp_rect
			(start 0.9652 1.778)
			(end -0.9652 -1.778)
			(stroke
				(width 0)
				(type default)
			)
			(fill no)
			(layer "B.CrtYd")
		)
		(fp_poly
			(pts
				(xy 0.9652 -1.778) (xy -0.9652 -1.778) (xy -0.9652 1.778) (xy 0.9652 1.778)
			)
			(stroke
				(width 0)
				(type default)
			)
			(fill no)
			(layer "B.Fab")
		)
		(pad "1" smd rect
			(at 0 -0.9652)
			(size 1.397 1.143)
			(layers "B.Cu" "B.Mask" "B.Paste")
			(net "P12V_STBY_VIN_U81")
		)
		(pad "2" smd rect
			(at 0 0.9652)
			(size 1.397 1.143)
			(layers "B.Cu" "B.Mask" "B.Paste")
			(net "GND")
		)
	)
	(footprint ""
		(layer "B.Cu")
		(at 43.331638 -137.122408)
		(property "Reference" "TP29"
			(at 0 0 0)
			(layer "B.SilkS")
			(hide yes)
			(effects
				(font
					(size 1.27 1.27)
				)
				(justify mirror)
			)
		)
		(property "Value" "TPAD28-2-GP"
			(at 0.0127 -1.6637 0)
			(unlocked yes)
			(layer "B.Fab")
			(hide yes)
			(effects
				(font
					(size 1.016 1.016)
					(thickness 0.1524)
				)
				(justify mirror)
			)
		)
		(property "Device Type" "TPAD28"
			(at 0.0127 -3.1877 0)
			(unlocked yes)
			(layer "B.Fab")
			(hide yes)
			(effects
				(font
					(size 1.016 1.016)
					(thickness 0.1524)
				)
				(justify mirror)
			)
		)
		(duplicate_pad_numbers_are_jumpers no)
		(fp_poly
			(pts
				(arc
					(start 0.3556 0)
					(mid -0.3556 0)
					(end 0.3556 0)
				)
			)
			(stroke
				(width 0)
				(type default)
			)
			(fill no)
			(layer "B.CrtYd")
		)
		(fp_poly
			(pts
				(arc
					(start 0.6096 0)
					(mid -0.6096 0)
					(end 0.6096 0)
				)
			)
			(stroke
				(width 0)
				(type default)
			)
			(fill no)
			(layer "B.Fab")
		)
		(pad "1" smd circle
			(at 0 0 180)
			(size 0.7112 0.7112)
			(layers "B.Cu" "B.Mask" "B.Paste")
			(net "TP_BMC_GPIOR5")
		)
	)
	(footprint ""
		(layer "B.Cu")
		(at 209.427064 -88.954356 -90)
		(property "Reference" "Q21"
			(at 0 0 90)
			(layer "B.SilkS")
			(hide yes)
			(effects
				(font
					(size 1.27 1.27)
				)
				(justify mirror)
			)
		)
		(property "Value" "2N7002K-1-GP"
			(at -0.127 -8.9662 270)
			(unlocked yes)
			(layer "B.Fab")
			(hide yes)
			(effects
				(font
					(size 1.016 1.016)
					(thickness 0.1524)
				)
				(justify mirror)
			)
		)
		(property "Device Type" "SOT23DGS2D4H44"
			(at -0.127 -10.4902 270)
			(unlocked yes)
			(layer "B.Fab")
			(hide yes)
			(effects
				(font
					(size 1.016 1.016)
					(thickness 0.1524)
				)
				(justify mirror)
			)
		)
		(duplicate_pad_numbers_are_jumpers no)
		(fp_line
			(start -1.651 1.778)
			(end -1.651 -1.778)
			(stroke
				(width 0.1524)
				(type default)
			)
			(layer "B.SilkS")
		)
		(fp_line
			(start 1.651 1.778)
			(end -1.651 1.778)
			(stroke
				(width 0.1524)
				(type default)
			)
			(layer "B.SilkS")
		)
		(fp_line
			(start -1.651 -1.778)
			(end 1.651 -1.778)
			(stroke
				(width 0.1524)
				(type default)
			)
			(layer "B.SilkS")
		)
		(fp_line
			(start 1.651 -1.778)
			(end 1.651 1.778)
			(stroke
				(width 0.1524)
				(type default)
			)
			(layer "B.SilkS")
		)
		(fp_poly
			(pts
				(xy 1.778 1.8796) (xy 1.778 -1.8796) (xy -1.778 -1.8796) (xy -1.778 1.8796)
			)
			(stroke
				(width 0)
				(type default)
			)
			(fill no)
			(layer "B.CrtYd")
		)
		(fp_poly
			(pts
				(xy 1.778 1.8796) (xy 1.778 -1.8796) (xy -1.778 -1.8796) (xy -1.778 1.8796)
			)
			(stroke
				(width 0)
				(type default)
			)
			(fill no)
			(layer "B.Fab")
		)
		(pad "D" smd custom
			(at 0 -0.9525 90)
			(size 0.1905 0.1905)
			(layers "B.Cu" "B.Mask" "B.Paste")
			(net "P3V3_PG")
			(options
				(clearance outline)
				(anchor circle)
			)
			(primitives
				(gr_poly
					(pts
						(arc
							(start -0.1778 -0.5715)
							(mid -0.321484 -0.511984)
							(end -0.381 -0.3683)
						)
						(arc
							(start -0.381 0.3683)
							(mid -0.321484 0.511984)
							(end -0.1778 0.5715)
						)
						(arc
							(start 0.1778 0.5715)
							(mid 0.321484 0.511984)
							(end 0.381 0.3683)
						)
						(arc
							(start 0.381 -0.3683)
							(mid 0.321484 -0.511984)
							(end 0.1778 -0.5715)
						)
					)
					(width 0)
					(fill yes)
				)
			)
		)
		(pad "G" smd custom
			(at 0.98425 0.9525 90)
			(size 0.1905 0.1905)
			(layers "B.Cu" "B.Mask" "B.Paste")
			(net "Q21_G")
			(options
				(clearance outline)
				(anchor circle)
			)
			(primitives
				(gr_poly
					(pts
						(arc
							(start -0.1778 -0.5715)
							(mid -0.321484 -0.511984)
							(end -0.381 -0.3683)
						)
						(arc
							(start -0.381 0.3683)
							(mid -0.321484 0.511984)
							(end -0.1778 0.5715)
						)
						(arc
							(start 0.1778 0.5715)
							(mid 0.321484 0.511984)
							(end 0.381 0.3683)
						)
						(arc
							(start 0.381 -0.3683)
							(mid 0.321484 -0.511984)
							(end 0.1778 -0.5715)
						)
					)
					(width 0)
					(fill yes)
				)
			)
		)
		(pad "S" smd custom
			(at -0.98425 0.9525 90)
			(size 0.1905 0.1905)
			(layers "B.Cu" "B.Mask" "B.Paste")
			(net "GND")
			(options
				(clearance outline)
				(anchor circle)
			)
			(primitives
				(gr_poly
					(pts
						(arc
							(start -0.1778 -0.5715)
							(mid -0.321484 -0.511984)
							(end -0.381 -0.3683)
						)
						(arc
							(start -0.381 0.3683)
							(mid -0.321484 0.511984)
							(end -0.1778 0.5715)
						)
						(arc
							(start 0.1778 0.5715)
							(mid 0.321484 0.511984)
							(end 0.381 0.3683)
						)
						(arc
							(start 0.381 -0.3683)
							(mid 0.321484 -0.511984)
							(end 0.1778 -0.5715)
						)
					)
					(width 0)
					(fill yes)
				)
			)
		)
	)
	(footprint ""
		(layer "B.Cu")
		(at 125.349 -16.6624)
		(property "Reference" "R445"
			(at 0 0 0)
			(layer "B.SilkS")
			(hide yes)
			(effects
				(font
					(size 1.27 1.27)
				)
				(justify mirror)
			)
		)
		(property "Value" "49K9R2F-L-GP"
			(at -0.064008 -3.993896 0)
			(unlocked yes)
			(layer "B.Fab")
			(hide yes)
			(effects
				(font
					(size 1.016 1.016)
					(thickness 0.1524)
				)
				(justify mirror)
			)
		)
		(property "Device Type" "R402H16"
			(at -0.064008 -5.517896 0)
			(unlocked yes)
			(layer "B.Fab")
			(hide yes)
			(effects
				(font
					(size 1.016 1.016)
					(thickness 0.1524)
				)
				(justify mirror)
			)
		)
		(duplicate_pad_numbers_are_jumpers no)
		(fp_line
			(start -0.508 -0.9398)
			(end 0.508 -0.9398)
			(stroke
				(width 0.1524)
				(type default)
			)
			(layer "B.SilkS")
		)
		(fp_line
			(start 0.508 -0.9398)
			(end 0.508 0.9398)
			(stroke
				(width 0.1524)
				(type default)
			)
			(layer "B.SilkS")
		)
		(fp_rect
			(start 0.508 0.9398)
			(end -0.508 -0.9398)
			(stroke
				(width 0)
				(type default)
			)
			(fill no)
			(layer "B.CrtYd")
		)
		(fp_rect
			(start 0.508 0.9398)
			(end -0.508 -0.9398)
			(stroke
				(width 0)
				(type default)
			)
			(fill no)
			(layer "B.Fab")
		)
		(pad "1" smd custom
			(at 0 -0.4445 180)
			(size 0.1397 0.1397)
			(layers "B.Cu" "B.Mask" "B.Paste")
			(net "P12V_IOM")
			(options
				(clearance outline)
				(anchor circle)
			)
			(primitives
				(gr_poly
					(pts
						(arc
							(start -0.1778 0.2794)
							(mid -0.249642 0.249642)
							(end -0.2794 0.1778)
						)
						(arc
							(start -0.2794 -0.1778)
							(mid -0.249642 -0.249642)
							(end -0.1778 -0.2794)
						)
						(arc
							(start 0.1778 -0.2794)
							(mid 0.249642 -0.249642)
							(end 0.2794 -0.1778)
						)
						(arc
							(start 0.2794 0.1778)
							(mid 0.249642 0.249642)
							(end 0.1778 0.2794)
						)
					)
					(width 0)
					(fill yes)
				)
			)
		)
		(pad "2" smd custom
			(at 0 0.4445 180)
			(size 0.1397 0.1397)
			(layers "B.Cu" "B.Mask" "B.Paste")
			(net "MB0_CM_OV_R")
			(options
				(clearance outline)
				(anchor circle)
			)
			(primitives
				(gr_poly
					(pts
						(arc
							(start -0.1778 0.2794)
							(mid -0.249642 0.249642)
							(end -0.2794 0.1778)
						)
						(arc
							(start -0.2794 -0.1778)
							(mid -0.249642 -0.249642)
							(end -0.1778 -0.2794)
						)
						(arc
							(start 0.1778 -0.2794)
							(mid 0.249642 -0.249642)
							(end 0.2794 -0.1778)
						)
						(arc
							(start 0.2794 0.1778)
							(mid 0.249642 0.249642)
							(end 0.1778 0.2794)
						)
					)
					(width 0)
					(fill yes)
				)
			)
		)
	)
	(footprint ""
		(layer "B.Cu")
		(at 44.221908 -145.810732 -90)
		(property "Reference" "R141"
			(at 0 0 90)
			(layer "B.SilkS")
			(hide yes)
			(effects
				(font
					(size 1.27 1.27)
				)
				(justify mirror)
			)
		)
		(property "Value" "1KR2D-1-GP"
			(at -0.064008 -3.993896 270)
			(unlocked yes)
			(layer "B.Fab")
			(hide yes)
			(effects
				(font
					(size 1.016 1.016)
					(thickness 0.1524)
				)
				(justify mirror)
			)
		)
		(property "Device Type" "R402H16"
			(at -0.064008 -5.517896 270)
			(unlocked yes)
			(layer "B.Fab")
			(hide yes)
			(effects
				(font
					(size 1.016 1.016)
					(thickness 0.1524)
				)
				(justify mirror)
			)
		)
		(duplicate_pad_numbers_are_jumpers no)
		(fp_line
			(start -0.508 -0.9398)
			(end 0.508 -0.9398)
			(stroke
				(width 0.1524)
				(type default)
			)
			(layer "B.SilkS")
		)
		(fp_line
			(start 0.508 -0.9398)
			(end 0.508 0.9398)
			(stroke
				(width 0.1524)
				(type default)
			)
			(layer "B.SilkS")
		)
		(fp_rect
			(start 0.508 0.9398)
			(end -0.508 -0.9398)
			(stroke
				(width 0)
				(type default)
			)
			(fill no)
			(layer "B.CrtYd")
		)
		(fp_rect
			(start 0.508 0.9398)
			(end -0.508 -0.9398)
			(stroke
				(width 0)
				(type default)
			)
			(fill no)
			(layer "B.Fab")
		)
		(pad "1" smd custom
			(at 0 -0.4445 90)
			(size 0.1397 0.1397)
			(layers "B.Cu" "B.Mask" "B.Paste")
			(net "P1V2_STBY")
			(options
				(clearance outline)
				(anchor circle)
			)
			(primitives
				(gr_poly
					(pts
						(arc
							(start -0.1778 0.2794)
							(mid -0.249642 0.249642)
							(end -0.2794 0.1778)
						)
						(arc
							(start -0.2794 -0.1778)
							(mid -0.249642 -0.249642)
							(end -0.1778 -0.2794)
						)
						(arc
							(start 0.1778 -0.2794)
							(mid 0.249642 -0.249642)
							(end 0.2794 -0.1778)
						)
						(arc
							(start 0.2794 0.1778)
							(mid 0.249642 0.249642)
							(end 0.1778 0.2794)
						)
					)
					(width 0)
					(fill yes)
				)
			)
		)
		(pad "2" smd custom
			(at 0 0.4445 90)
			(size 0.1397 0.1397)
			(layers "B.Cu" "B.Mask" "B.Paste")
			(net "DDR_VREF")
			(options
				(clearance outline)
				(anchor circle)
			)
			(primitives
				(gr_poly
					(pts
						(arc
							(start -0.1778 0.2794)
							(mid -0.249642 0.249642)
							(end -0.2794 0.1778)
						)
						(arc
							(start -0.2794 -0.1778)
							(mid -0.249642 -0.249642)
							(end -0.1778 -0.2794)
						)
						(arc
							(start 0.1778 -0.2794)
							(mid 0.249642 -0.249642)
							(end 0.2794 -0.1778)
						)
						(arc
							(start 0.2794 0.1778)
							(mid 0.249642 0.249642)
							(end 0.1778 0.2794)
						)
					)
					(width 0)
					(fill yes)
				)
			)
		)
	)
	(footprint ""
		(layer "B.Cu")
		(at 12.11199 -139.579604 90)
		(property "Reference" "R234"
			(at 0 0 90)
			(layer "B.SilkS")
			(hide yes)
			(effects
				(font
					(size 1.27 1.27)
				)
				(justify mirror)
			)
		)
		(property "Value" "120R2F-GP"
			(at -0.064008 -3.993896 90)
			(unlocked yes)
			(layer "B.Fab")
			(hide yes)
			(effects
				(font
					(size 1.016 1.016)
					(thickness 0.1524)
				)
				(justify mirror)
			)
		)
		(property "Device Type" "R402H16"
			(at -0.064008 -5.517896 90)
			(unlocked yes)
			(layer "B.Fab")
			(hide yes)
			(effects
				(font
					(size 1.016 1.016)
					(thickness 0.1524)
				)
				(justify mirror)
			)
		)
		(duplicate_pad_numbers_are_jumpers no)
		(fp_line
			(start 0.508 -0.9398)
			(end 0.508 0.9398)
			(stroke
				(width 0.1524)
				(type default)
			)
			(layer "B.SilkS")
		)
		(fp_line
			(start -0.508 -0.9398)
			(end 0.508 -0.9398)
			(stroke
				(width 0.1524)
				(type default)
			)
			(layer "B.SilkS")
		)
		(fp_rect
			(start 0.508 0.9398)
			(end -0.508 -0.9398)
			(stroke
				(width 0)
				(type default)
			)
			(fill no)
			(layer "B.CrtYd")
		)
		(fp_rect
			(start 0.508 0.9398)
			(end -0.508 -0.9398)
			(stroke
				(width 0)
				(type default)
			)
			(fill no)
			(layer "B.Fab")
		)
		(pad "1" smd custom
			(at 0 -0.4445 270)
			(size 0.1397 0.1397)
			(layers "B.Cu" "B.Mask" "B.Paste")
			(net "MEMA_0")
			(options
				(clearance outline)
				(anchor circle)
			)
			(primitives
				(gr_poly
					(pts
						(arc
							(start -0.1778 0.2794)
							(mid -0.249642 0.249642)
							(end -0.2794 0.1778)
						)
						(arc
							(start -0.2794 -0.1778)
							(mid -0.249642 -0.249642)
							(end -0.1778 -0.2794)
						)
						(arc
							(start 0.1778 -0.2794)
							(mid 0.249642 -0.249642)
							(end 0.2794 -0.1778)
						)
						(arc
							(start 0.2794 0.1778)
							(mid 0.249642 0.249642)
							(end 0.1778 0.2794)
						)
					)
					(width 0)
					(fill yes)
				)
			)
		)
		(pad "2" smd custom
			(at 0 0.4445 270)
			(size 0.1397 0.1397)
			(layers "B.Cu" "B.Mask" "B.Paste")
			(net "P1V2_STBY")
			(options
				(clearance outline)
				(anchor circle)
			)
			(primitives
				(gr_poly
					(pts
						(arc
							(start -0.1778 0.2794)
							(mid -0.249642 0.249642)
							(end -0.2794 0.1778)
						)
						(arc
							(start -0.2794 -0.1778)
							(mid -0.249642 -0.249642)
							(end -0.1778 -0.2794)
						)
						(arc
							(start 0.1778 -0.2794)
							(mid 0.249642 -0.249642)
							(end 0.2794 -0.1778)
						)
						(arc
							(start 0.2794 0.1778)
							(mid 0.249642 0.249642)
							(end 0.1778 0.2794)
						)
					)
					(width 0)
					(fill yes)
				)
			)
		)
	)
	(footprint ""
		(layer "B.Cu")
		(at 45.5676 -134.6454 180)
		(property "Reference" "R154"
			(at 0 0 0)
			(layer "B.SilkS")
			(hide yes)
			(effects
				(font
					(size 1.27 1.27)
				)
				(justify mirror)
			)
		)
		(property "Value" "0R2J-2-GP"
			(at -0.064008 -3.993896 180)
			(unlocked yes)
			(layer "B.Fab")
			(hide yes)
			(effects
				(font
					(size 1.016 1.016)
					(thickness 0.1524)
				)
				(justify mirror)
			)
		)
		(property "Device Type" "R402H16"
			(at -0.064008 -5.517896 180)
			(unlocked yes)
			(layer "B.Fab")
			(hide yes)
			(effects
				(font
					(size 1.016 1.016)
					(thickness 0.1524)
				)
				(justify mirror)
			)
		)
		(duplicate_pad_numbers_are_jumpers no)
		(fp_line
			(start 0.508 -0.9398)
			(end 0.508 0.9398)
			(stroke
				(width 0.1524)
				(type default)
			)
			(layer "B.SilkS")
		)
		(fp_line
			(start -0.508 -0.9398)
			(end 0.508 -0.9398)
			(stroke
				(width 0.1524)
				(type default)
			)
			(layer "B.SilkS")
		)
		(fp_rect
			(start 0.508 0.9398)
			(end -0.508 -0.9398)
			(stroke
				(width 0)
				(type default)
			)
			(fill no)
			(layer "B.CrtYd")
		)
		(fp_rect
			(start 0.508 0.9398)
			(end -0.508 -0.9398)
			(stroke
				(width 0)
				(type default)
			)
			(fill no)
			(layer "B.Fab")
		)
		(pad "1" smd custom
			(at 0 -0.4445)
			(size 0.1397 0.1397)
			(layers "B.Cu" "B.Mask" "B.Paste")
			(net "I2C_IOM_SDA")
			(options
				(clearance outline)
				(anchor circle)
			)
			(primitives
				(gr_poly
					(pts
						(arc
							(start -0.1778 0.2794)
							(mid -0.249642 0.249642)
							(end -0.2794 0.1778)
						)
						(arc
							(start -0.2794 -0.1778)
							(mid -0.249642 -0.249642)
							(end -0.1778 -0.2794)
						)
						(arc
							(start 0.1778 -0.2794)
							(mid 0.249642 -0.249642)
							(end 0.2794 -0.1778)
						)
						(arc
							(start 0.2794 0.1778)
							(mid 0.249642 0.249642)
							(end 0.1778 0.2794)
						)
					)
					(width 0)
					(fill yes)
				)
			)
		)
		(pad "2" smd custom
			(at 0 0.4445)
			(size 0.1397 0.1397)
			(layers "B.Cu" "B.Mask" "B.Paste")
			(net "BMC_SMB1_DAT")
			(options
				(clearance outline)
				(anchor circle)
			)
			(primitives
				(gr_poly
					(pts
						(arc
							(start -0.1778 0.2794)
							(mid -0.249642 0.249642)
							(end -0.2794 0.1778)
						)
						(arc
							(start -0.2794 -0.1778)
							(mid -0.249642 -0.249642)
							(end -0.1778 -0.2794)
						)
						(arc
							(start 0.1778 -0.2794)
							(mid 0.249642 -0.249642)
							(end 0.2794 -0.1778)
						)
						(arc
							(start 0.2794 0.1778)
							(mid 0.249642 0.249642)
							(end 0.1778 0.2794)
						)
					)
					(width 0)
					(fill yes)
				)
			)
		)
	)
	(footprint ""
		(layer "B.Cu")
		(at 47.126652 -136.169654 90)
		(property "Reference" "R140"
			(at 0 0 90)
			(layer "B.SilkS")
			(hide yes)
			(effects
				(font
					(size 1.27 1.27)
				)
				(justify mirror)
			)
		)
		(property "Value" "100KR2F-L1-GP"
			(at -0.064008 -3.993896 90)
			(unlocked yes)
			(layer "B.Fab")
			(hide yes)
			(effects
				(font
					(size 1.016 1.016)
					(thickness 0.1524)
				)
				(justify mirror)
			)
		)
		(property "Device Type" "R402H16"
			(at -0.064008 -5.517896 90)
			(unlocked yes)
			(layer "B.Fab")
			(hide yes)
			(effects
				(font
					(size 1.016 1.016)
					(thickness 0.1524)
				)
				(justify mirror)
			)
		)
		(duplicate_pad_numbers_are_jumpers no)
		(fp_line
			(start 0.508 -0.9398)
			(end 0.508 0.9398)
			(stroke
				(width 0.1524)
				(type default)
			)
			(layer "B.SilkS")
		)
		(fp_line
			(start -0.508 -0.9398)
			(end 0.508 -0.9398)
			(stroke
				(width 0.1524)
				(type default)
			)
			(layer "B.SilkS")
		)
		(fp_rect
			(start 0.508 0.9398)
			(end -0.508 -0.9398)
			(stroke
				(width 0)
				(type default)
			)
			(fill no)
			(layer "B.CrtYd")
		)
		(fp_rect
			(start 0.508 0.9398)
			(end -0.508 -0.9398)
			(stroke
				(width 0)
				(type default)
			)
			(fill no)
			(layer "B.Fab")
		)
		(pad "1" smd custom
			(at 0 -0.4445 270)
			(size 0.1397 0.1397)
			(layers "B.Cu" "B.Mask" "B.Paste")
			(net "GND")
			(options
				(clearance outline)
				(anchor circle)
			)
			(primitives
				(gr_poly
					(pts
						(arc
							(start -0.1778 0.2794)
							(mid -0.249642 0.249642)
							(end -0.2794 0.1778)
						)
						(arc
							(start -0.2794 -0.1778)
							(mid -0.249642 -0.249642)
							(end -0.1778 -0.2794)
						)
						(arc
							(start 0.1778 -0.2794)
							(mid 0.249642 -0.249642)
							(end 0.2794 -0.1778)
						)
						(arc
							(start 0.2794 0.1778)
							(mid 0.249642 0.249642)
							(end 0.1778 0.2794)
						)
					)
					(width 0)
					(fill yes)
				)
			)
		)
		(pad "2" smd custom
			(at 0 0.4445 270)
			(size 0.1397 0.1397)
			(layers "B.Cu" "B.Mask" "B.Paste")
			(net "PD_PERST_N")
			(options
				(clearance outline)
				(anchor circle)
			)
			(primitives
				(gr_poly
					(pts
						(arc
							(start -0.1778 0.2794)
							(mid -0.249642 0.249642)
							(end -0.2794 0.1778)
						)
						(arc
							(start -0.2794 -0.1778)
							(mid -0.249642 -0.249642)
							(end -0.1778 -0.2794)
						)
						(arc
							(start 0.1778 -0.2794)
							(mid 0.249642 -0.249642)
							(end 0.2794 -0.1778)
						)
						(arc
							(start 0.2794 0.1778)
							(mid 0.249642 0.249642)
							(end 0.1778 0.2794)
						)
					)
					(width 0)
					(fill yes)
				)
			)
		)
	)
	(footprint ""
		(layer "B.Cu")
		(at 12.091924 -132.402326 90)
		(property "Reference" "R238"
			(at 0 0 90)
			(layer "B.SilkS")
			(hide yes)
			(effects
				(font
					(size 1.27 1.27)
				)
				(justify mirror)
			)
		)
		(property "Value" "120R2F-GP"
			(at -0.064008 -3.993896 90)
			(unlocked yes)
			(layer "B.Fab")
			(hide yes)
			(effects
				(font
					(size 1.016 1.016)
					(thickness 0.1524)
				)
				(justify mirror)
			)
		)
		(property "Device Type" "R402H16"
			(at -0.064008 -5.517896 90)
			(unlocked yes)
			(layer "B.Fab")
			(hide yes)
			(effects
				(font
					(size 1.016 1.016)
					(thickness 0.1524)
				)
				(justify mirror)
			)
		)
		(duplicate_pad_numbers_are_jumpers no)
		(fp_line
			(start 0.508 -0.9398)
			(end 0.508 0.9398)
			(stroke
				(width 0.1524)
				(type default)
			)
			(layer "B.SilkS")
		)
		(fp_line
			(start -0.508 -0.9398)
			(end 0.508 -0.9398)
			(stroke
				(width 0.1524)
				(type default)
			)
			(layer "B.SilkS")
		)
		(fp_rect
			(start 0.508 0.9398)
			(end -0.508 -0.9398)
			(stroke
				(width 0)
				(type default)
			)
			(fill no)
			(layer "B.CrtYd")
		)
		(fp_rect
			(start 0.508 0.9398)
			(end -0.508 -0.9398)
			(stroke
				(width 0)
				(type default)
			)
			(fill no)
			(layer "B.Fab")
		)
		(pad "1" smd custom
			(at 0 -0.4445 270)
			(size 0.1397 0.1397)
			(layers "B.Cu" "B.Mask" "B.Paste")
			(net "MEMA_2")
			(options
				(clearance outline)
				(anchor circle)
			)
			(primitives
				(gr_poly
					(pts
						(arc
							(start -0.1778 0.2794)
							(mid -0.249642 0.249642)
							(end -0.2794 0.1778)
						)
						(arc
							(start -0.2794 -0.1778)
							(mid -0.249642 -0.249642)
							(end -0.1778 -0.2794)
						)
						(arc
							(start 0.1778 -0.2794)
							(mid 0.249642 -0.249642)
							(end 0.2794 -0.1778)
						)
						(arc
							(start 0.2794 0.1778)
							(mid 0.249642 0.249642)
							(end 0.1778 0.2794)
						)
					)
					(width 0)
					(fill yes)
				)
			)
		)
		(pad "2" smd custom
			(at 0 0.4445 270)
			(size 0.1397 0.1397)
			(layers "B.Cu" "B.Mask" "B.Paste")
			(net "P1V2_STBY")
			(options
				(clearance outline)
				(anchor circle)
			)
			(primitives
				(gr_poly
					(pts
						(arc
							(start -0.1778 0.2794)
							(mid -0.249642 0.249642)
							(end -0.2794 0.1778)
						)
						(arc
							(start -0.2794 -0.1778)
							(mid -0.249642 -0.249642)
							(end -0.1778 -0.2794)
						)
						(arc
							(start 0.1778 -0.2794)
							(mid 0.249642 -0.249642)
							(end 0.2794 -0.1778)
						)
						(arc
							(start 0.2794 0.1778)
							(mid 0.249642 0.249642)
							(end 0.1778 0.2794)
						)
					)
					(width 0)
					(fill yes)
				)
			)
		)
	)
	(footprint ""
		(layer "B.Cu")
		(at 57.926478 -135.777224 -90)
		(property "Reference" "R295"
			(at 0 0 90)
			(layer "B.SilkS")
			(hide yes)
			(effects
				(font
					(size 1.27 1.27)
				)
				(justify mirror)
			)
		)
		(property "Value" "0R2J-2-GP"
			(at -0.064008 -3.993896 270)
			(unlocked yes)
			(layer "B.Fab")
			(hide yes)
			(effects
				(font
					(size 1.016 1.016)
					(thickness 0.1524)
				)
				(justify mirror)
			)
		)
		(property "Device Type" "R402H16"
			(at -0.064008 -5.517896 270)
			(unlocked yes)
			(layer "B.Fab")
			(hide yes)
			(effects
				(font
					(size 1.016 1.016)
					(thickness 0.1524)
				)
				(justify mirror)
			)
		)
		(duplicate_pad_numbers_are_jumpers no)
		(fp_line
			(start -0.508 -0.9398)
			(end 0.508 -0.9398)
			(stroke
				(width 0.1524)
				(type default)
			)
			(layer "B.SilkS")
		)
		(fp_line
			(start 0.508 -0.9398)
			(end 0.508 0.9398)
			(stroke
				(width 0.1524)
				(type default)
			)
			(layer "B.SilkS")
		)
		(fp_rect
			(start 0.508 0.9398)
			(end -0.508 -0.9398)
			(stroke
				(width 0)
				(type default)
			)
			(fill no)
			(layer "B.CrtYd")
		)
		(fp_rect
			(start 0.508 0.9398)
			(end -0.508 -0.9398)
			(stroke
				(width 0)
				(type default)
			)
			(fill no)
			(layer "B.Fab")
		)
		(pad "1" smd custom
			(at 0 -0.4445 90)
			(size 0.1397 0.1397)
			(layers "B.Cu" "B.Mask" "B.Paste")
			(net "SCC_RMT_TYPE_0")
			(options
				(clearance outline)
				(anchor circle)
			)
			(primitives
				(gr_poly
					(pts
						(arc
							(start -0.1778 0.2794)
							(mid -0.249642 0.249642)
							(end -0.2794 0.1778)
						)
						(arc
							(start -0.2794 -0.1778)
							(mid -0.249642 -0.249642)
							(end -0.1778 -0.2794)
						)
						(arc
							(start 0.1778 -0.2794)
							(mid 0.249642 -0.249642)
							(end 0.2794 -0.1778)
						)
						(arc
							(start 0.2794 0.1778)
							(mid 0.249642 0.249642)
							(end 0.1778 0.2794)
						)
					)
					(width 0)
					(fill yes)
				)
			)
		)
		(pad "2" smd custom
			(at 0 0.4445 90)
			(size 0.1397 0.1397)
			(layers "B.Cu" "B.Mask" "B.Paste")
			(net "SCC_RMT_TYPE_0_R")
			(options
				(clearance outline)
				(anchor circle)
			)
			(primitives
				(gr_poly
					(pts
						(arc
							(start -0.1778 0.2794)
							(mid -0.249642 0.249642)
							(end -0.2794 0.1778)
						)
						(arc
							(start -0.2794 -0.1778)
							(mid -0.249642 -0.249642)
							(end -0.1778 -0.2794)
						)
						(arc
							(start 0.1778 -0.2794)
							(mid 0.249642 -0.249642)
							(end 0.2794 -0.1778)
						)
						(arc
							(start 0.2794 0.1778)
							(mid 0.249642 0.249642)
							(end 0.1778 0.2794)
						)
					)
					(width 0)
					(fill yes)
				)
			)
		)
	)
	(footprint ""
		(layer "B.Cu")
		(at 75.35672 -140.859256 180)
		(property "Reference" "R380"
			(at 0 0 0)
			(layer "B.SilkS")
			(hide yes)
			(effects
				(font
					(size 1.27 1.27)
				)
				(justify mirror)
			)
		)
		(property "Value" "4K7R2F-GP"
			(at -0.064008 -3.993896 180)
			(unlocked yes)
			(layer "B.Fab")
			(hide yes)
			(effects
				(font
					(size 1.016 1.016)
					(thickness 0.1524)
				)
				(justify mirror)
			)
		)
		(property "Device Type" "R402H16"
			(at -0.064008 -5.517896 180)
			(unlocked yes)
			(layer "B.Fab")
			(hide yes)
			(effects
				(font
					(size 1.016 1.016)
					(thickness 0.1524)
				)
				(justify mirror)
			)
		)
		(duplicate_pad_numbers_are_jumpers no)
		(fp_line
			(start 0.508 -0.9398)
			(end 0.508 0.9398)
			(stroke
				(width 0.1524)
				(type default)
			)
			(layer "B.SilkS")
		)
		(fp_line
			(start -0.508 -0.9398)
			(end 0.508 -0.9398)
			(stroke
				(width 0.1524)
				(type default)
			)
			(layer "B.SilkS")
		)
		(fp_rect
			(start 0.508 0.9398)
			(end -0.508 -0.9398)
			(stroke
				(width 0)
				(type default)
			)
			(fill no)
			(layer "B.CrtYd")
		)
		(fp_rect
			(start 0.508 0.9398)
			(end -0.508 -0.9398)
			(stroke
				(width 0)
				(type default)
			)
			(fill no)
			(layer "B.Fab")
		)
		(pad "1" smd custom
			(at 0 -0.4445)
			(size 0.1397 0.1397)
			(layers "B.Cu" "B.Mask" "B.Paste")
			(net "P3V3_STBY")
			(options
				(clearance outline)
				(anchor circle)
			)
			(primitives
				(gr_poly
					(pts
						(arc
							(start -0.1778 0.2794)
							(mid -0.249642 0.249642)
							(end -0.2794 0.1778)
						)
						(arc
							(start -0.2794 -0.1778)
							(mid -0.249642 -0.249642)
							(end -0.1778 -0.2794)
						)
						(arc
							(start 0.1778 -0.2794)
							(mid 0.249642 -0.249642)
							(end 0.2794 -0.1778)
						)
						(arc
							(start 0.2794 0.1778)
							(mid 0.249642 0.249642)
							(end 0.1778 0.2794)
						)
					)
					(width 0)
					(fill yes)
				)
			)
		)
		(pad "2" smd custom
			(at 0 0.4445)
			(size 0.1397 0.1397)
			(layers "B.Cu" "B.Mask" "B.Paste")
			(net "NCSI_TXEN")
			(options
				(clearance outline)
				(anchor circle)
			)
			(primitives
				(gr_poly
					(pts
						(arc
							(start -0.1778 0.2794)
							(mid -0.249642 0.249642)
							(end -0.2794 0.1778)
						)
						(arc
							(start -0.2794 -0.1778)
							(mid -0.249642 -0.249642)
							(end -0.1778 -0.2794)
						)
						(arc
							(start 0.1778 -0.2794)
							(mid 0.249642 -0.249642)
							(end 0.2794 -0.1778)
						)
						(arc
							(start 0.2794 0.1778)
							(mid 0.249642 0.249642)
							(end 0.1778 0.2794)
						)
					)
					(width 0)
					(fill yes)
				)
			)
		)
	)
	(footprint ""
		(layer "B.Cu")
		(at 49.75098 -161.59734 90)
		(property "Reference" "R279"
			(at 0 0 90)
			(layer "B.SilkS")
			(hide yes)
			(effects
				(font
					(size 1.27 1.27)
				)
				(justify mirror)
			)
		)
		(property "Value" "0R2J-2-GP"
			(at -0.064008 -3.993896 90)
			(unlocked yes)
			(layer "B.Fab")
			(hide yes)
			(effects
				(font
					(size 1.016 1.016)
					(thickness 0.1524)
				)
				(justify mirror)
			)
		)
		(property "Device Type" "R402H16"
			(at -0.064008 -5.517896 90)
			(unlocked yes)
			(layer "B.Fab")
			(hide yes)
			(effects
				(font
					(size 1.016 1.016)
					(thickness 0.1524)
				)
				(justify mirror)
			)
		)
		(duplicate_pad_numbers_are_jumpers no)
		(fp_line
			(start 0.508 -0.9398)
			(end 0.508 0.9398)
			(stroke
				(width 0.1524)
				(type default)
			)
			(layer "B.SilkS")
		)
		(fp_line
			(start -0.508 -0.9398)
			(end 0.508 -0.9398)
			(stroke
				(width 0.1524)
				(type default)
			)
			(layer "B.SilkS")
		)
		(fp_rect
			(start 0.508 0.9398)
			(end -0.508 -0.9398)
			(stroke
				(width 0)
				(type default)
			)
			(fill no)
			(layer "B.CrtYd")
		)
		(fp_rect
			(start 0.508 0.9398)
			(end -0.508 -0.9398)
			(stroke
				(width 0)
				(type default)
			)
			(fill no)
			(layer "B.Fab")
		)
		(pad "1" smd custom
			(at 0 -0.4445 270)
			(size 0.1397 0.1397)
			(layers "B.Cu" "B.Mask" "B.Paste")
			(net "I2C_MEZZ_OOB_SCL")
			(options
				(clearance outline)
				(anchor circle)
			)
			(primitives
				(gr_poly
					(pts
						(arc
							(start -0.1778 0.2794)
							(mid -0.249642 0.249642)
							(end -0.2794 0.1778)
						)
						(arc
							(start -0.2794 -0.1778)
							(mid -0.249642 -0.249642)
							(end -0.1778 -0.2794)
						)
						(arc
							(start 0.1778 -0.2794)
							(mid 0.249642 -0.249642)
							(end 0.2794 -0.1778)
						)
						(arc
							(start 0.2794 0.1778)
							(mid 0.249642 0.249642)
							(end 0.1778 0.2794)
						)
					)
					(width 0)
					(fill yes)
				)
			)
		)
		(pad "2" smd custom
			(at 0 0.4445 270)
			(size 0.1397 0.1397)
			(layers "B.Cu" "B.Mask" "B.Paste")
			(net "BMC_SMB5_CLK")
			(options
				(clearance outline)
				(anchor circle)
			)
			(primitives
				(gr_poly
					(pts
						(arc
							(start -0.1778 0.2794)
							(mid -0.249642 0.249642)
							(end -0.2794 0.1778)
						)
						(arc
							(start -0.2794 -0.1778)
							(mid -0.249642 -0.249642)
							(end -0.1778 -0.2794)
						)
						(arc
							(start 0.1778 -0.2794)
							(mid 0.249642 -0.249642)
							(end 0.2794 -0.1778)
						)
						(arc
							(start 0.2794 0.1778)
							(mid 0.249642 0.249642)
							(end 0.1778 0.2794)
						)
					)
					(width 0)
					(fill yes)
				)
			)
		)
	)
	(footprint ""
		(layer "B.Cu")
		(at 91.8972 -152.8318 180)
		(property "Reference" "C10"
			(at 0 0 0)
			(layer "B.SilkS")
			(hide yes)
			(effects
				(font
					(size 1.27 1.27)
				)
				(justify mirror)
			)
		)
		(property "Value" "SC1U16V2KX-7-GP"
			(at -1.7526 -1.6002 180)
			(unlocked yes)
			(layer "B.Fab")
			(hide yes)
			(effects
				(font
					(size 1.016 1.016)
					(thickness 0.1524)
				)
				(justify mirror)
			)
		)
		(property "Device Type" "C402-TO0D2H24"
			(at -1.7526 -3.1242 180)
			(unlocked yes)
			(layer "B.Fab")
			(hide yes)
			(effects
				(font
					(size 1.016 1.016)
					(thickness 0.1524)
				)
				(justify mirror)
			)
		)
		(duplicate_pad_numbers_are_jumpers no)
		(fp_rect
			(start 0.4826 0.889)
			(end -0.4826 -0.889)
			(stroke
				(width 0)
				(type default)
			)
			(fill no)
			(layer "B.CrtYd")
		)
		(fp_rect
			(start 0.4826 0.889)
			(end -0.4826 -0.889)
			(stroke
				(width 0)
				(type default)
			)
			(fill no)
			(layer "B.Fab")
		)
		(pad "1" smd custom
			(at 0 -0.4572)
			(size 0.1524 0.1524)
			(layers "B.Cu" "B.Mask" "B.Paste")
			(net "P3V3_STBY")
			(options
				(clearance outline)
				(anchor circle)
			)
			(primitives
				(gr_poly
					(pts
						(arc
							(start -0.254 -0.3048)
							(mid -0.325842 -0.275042)
							(end -0.3556 -0.2032)
						)
						(arc
							(start -0.3556 0.2032)
							(mid -0.325842 0.275042)
							(end -0.254 0.3048)
						)
						(arc
							(start 0.254 0.3048)
							(mid 0.325842 0.275042)
							(end 0.3556 0.2032)
						)
						(arc
							(start 0.3556 -0.2032)
							(mid 0.325842 -0.275042)
							(end 0.254 -0.3048)
						)
					)
					(width 0)
					(fill yes)
				)
			)
		)
		(pad "2" smd custom
			(at 0 0.4572)
			(size 0.1524 0.1524)
			(layers "B.Cu" "B.Mask" "B.Paste")
			(net "GND")
			(options
				(clearance outline)
				(anchor circle)
			)
			(primitives
				(gr_poly
					(pts
						(arc
							(start -0.254 -0.3048)
							(mid -0.325842 -0.275042)
							(end -0.3556 -0.2032)
						)
						(arc
							(start -0.3556 0.2032)
							(mid -0.325842 0.275042)
							(end -0.254 0.3048)
						)
						(arc
							(start 0.254 0.3048)
							(mid 0.325842 0.275042)
							(end 0.3556 0.2032)
						)
						(arc
							(start 0.3556 -0.2032)
							(mid 0.325842 -0.275042)
							(end 0.254 -0.3048)
						)
					)
					(width 0)
					(fill yes)
				)
			)
		)
	)
	(footprint ""
		(layer "B.Cu")
		(at 60.2488 -151.765 90)
		(property "Reference" "R393"
			(at 0 0 90)
			(layer "B.SilkS")
			(hide yes)
			(effects
				(font
					(size 1.27 1.27)
				)
				(justify mirror)
			)
		)
		(property "Value" "4K7R2F-GP"
			(at -0.064008 -3.993896 90)
			(unlocked yes)
			(layer "B.Fab")
			(hide yes)
			(effects
				(font
					(size 1.016 1.016)
					(thickness 0.1524)
				)
				(justify mirror)
			)
		)
		(property "Device Type" "R402H16"
			(at -0.064008 -5.517896 90)
			(unlocked yes)
			(layer "B.Fab")
			(hide yes)
			(effects
				(font
					(size 1.016 1.016)
					(thickness 0.1524)
				)
				(justify mirror)
			)
		)
		(duplicate_pad_numbers_are_jumpers no)
		(fp_line
			(start 0.508 -0.9398)
			(end 0.508 0.9398)
			(stroke
				(width 0.1524)
				(type default)
			)
			(layer "B.SilkS")
		)
		(fp_line
			(start -0.508 -0.9398)
			(end 0.508 -0.9398)
			(stroke
				(width 0.1524)
				(type default)
			)
			(layer "B.SilkS")
		)
		(fp_rect
			(start 0.508 0.9398)
			(end -0.508 -0.9398)
			(stroke
				(width 0)
				(type default)
			)
			(fill no)
			(layer "B.CrtYd")
		)
		(fp_rect
			(start 0.508 0.9398)
			(end -0.508 -0.9398)
			(stroke
				(width 0)
				(type default)
			)
			(fill no)
			(layer "B.Fab")
		)
		(pad "1" smd custom
			(at 0 -0.4445 270)
			(size 0.1397 0.1397)
			(layers "B.Cu" "B.Mask" "B.Paste")
			(net "P3V3_STBY")
			(options
				(clearance outline)
				(anchor circle)
			)
			(primitives
				(gr_poly
					(pts
						(arc
							(start -0.1778 0.2794)
							(mid -0.249642 0.249642)
							(end -0.2794 0.1778)
						)
						(arc
							(start -0.2794 -0.1778)
							(mid -0.249642 -0.249642)
							(end -0.1778 -0.2794)
						)
						(arc
							(start 0.1778 -0.2794)
							(mid 0.249642 -0.249642)
							(end 0.2794 -0.1778)
						)
						(arc
							(start 0.2794 0.1778)
							(mid 0.249642 0.249642)
							(end 0.1778 0.2794)
						)
					)
					(width 0)
					(fill yes)
				)
			)
		)
		(pad "2" smd custom
			(at 0 0.4445 270)
			(size 0.1397 0.1397)
			(layers "B.Cu" "B.Mask" "B.Paste")
			(net "MAC2_TXD2")
			(options
				(clearance outline)
				(anchor circle)
			)
			(primitives
				(gr_poly
					(pts
						(arc
							(start -0.1778 0.2794)
							(mid -0.249642 0.249642)
							(end -0.2794 0.1778)
						)
						(arc
							(start -0.2794 -0.1778)
							(mid -0.249642 -0.249642)
							(end -0.1778 -0.2794)
						)
						(arc
							(start 0.1778 -0.2794)
							(mid 0.249642 -0.249642)
							(end 0.2794 -0.1778)
						)
						(arc
							(start 0.2794 0.1778)
							(mid 0.249642 0.249642)
							(end 0.1778 0.2794)
						)
					)
					(width 0)
					(fill yes)
				)
			)
		)
	)
	(footprint ""
		(layer "B.Cu")
		(at 93.372686 -129.463546 -90)
		(property "Reference" "C126"
			(at 0 0 90)
			(layer "B.SilkS")
			(hide yes)
			(effects
				(font
					(size 1.27 1.27)
				)
				(justify mirror)
			)
		)
		(property "Value" "SCD1U16V2KX-3GP"
			(at -1.1811 -2.7051 270)
			(unlocked yes)
			(layer "B.Fab")
			(hide yes)
			(effects
				(font
					(size 1.016 1.016)
					(thickness 0.1524)
				)
				(justify mirror)
			)
		)
		(property "Device Type" "C402H22"
			(at -1.1811 -4.2291 270)
			(unlocked yes)
			(layer "B.Fab")
			(hide yes)
			(effects
				(font
					(size 1.016 1.016)
					(thickness 0.1524)
				)
				(justify mirror)
			)
		)
		(duplicate_pad_numbers_are_jumpers no)
		(fp_rect
			(start 0.4318 0.9525)
			(end -0.4318 -0.9525)
			(stroke
				(width 0)
				(type default)
			)
			(fill no)
			(layer "B.CrtYd")
		)
		(fp_rect
			(start 0.4318 0.9525)
			(end -0.4318 -0.9525)
			(stroke
				(width 0)
				(type default)
			)
			(fill no)
			(layer "B.Fab")
		)
		(pad "1" smd custom
			(at 0 -0.4445 90)
			(size 0.1524 0.1524)
			(layers "B.Cu" "B.Mask" "B.Paste")
			(net "P3V3_STBY")
			(options
				(clearance outline)
				(anchor circle)
			)
			(primitives
				(gr_poly
					(pts
						(arc
							(start 0.3048 0.2032)
							(mid 0.275042 0.275042)
							(end 0.2032 0.3048)
						)
						(arc
							(start -0.2032 0.3048)
							(mid -0.275042 0.275042)
							(end -0.3048 0.2032)
						)
						(arc
							(start -0.3048 -0.2032)
							(mid -0.275042 -0.275042)
							(end -0.2032 -0.3048)
						)
						(arc
							(start 0.2032 -0.3048)
							(mid 0.275042 -0.275042)
							(end 0.3048 -0.2032)
						)
					)
					(width 0)
					(fill yes)
				)
			)
		)
		(pad "2" smd custom
			(at 0 0.4445 90)
			(size 0.1524 0.1524)
			(layers "B.Cu" "B.Mask" "B.Paste")
			(net "GND")
			(options
				(clearance outline)
				(anchor circle)
			)
			(primitives
				(gr_poly
					(pts
						(arc
							(start 0.3048 0.2032)
							(mid 0.275042 0.275042)
							(end 0.2032 0.3048)
						)
						(arc
							(start -0.2032 0.3048)
							(mid -0.275042 0.275042)
							(end -0.3048 0.2032)
						)
						(arc
							(start -0.3048 -0.2032)
							(mid -0.275042 -0.275042)
							(end -0.2032 -0.3048)
						)
						(arc
							(start 0.2032 -0.3048)
							(mid 0.275042 -0.275042)
							(end 0.3048 -0.2032)
						)
					)
					(width 0)
					(fill yes)
				)
			)
		)
	)
	(footprint ""
		(layer "B.Cu")
		(at 22.225 -173.0756 90)
		(property "Reference" "C999"
			(at 0 0 90)
			(layer "B.SilkS")
			(hide yes)
			(effects
				(font
					(size 1.27 1.27)
				)
				(justify mirror)
			)
		)
		(property "Value" "SCD1U16V2KX-3GP"
			(at -1.1811 -2.7051 90)
			(unlocked yes)
			(layer "B.Fab")
			(hide yes)
			(effects
				(font
					(size 1.016 1.016)
					(thickness 0.1524)
				)
				(justify mirror)
			)
		)
		(property "Device Type" "C402H22"
			(at -1.1811 -4.2291 90)
			(unlocked yes)
			(layer "B.Fab")
			(hide yes)
			(effects
				(font
					(size 1.016 1.016)
					(thickness 0.1524)
				)
				(justify mirror)
			)
		)
		(duplicate_pad_numbers_are_jumpers no)
		(fp_rect
			(start 0.4318 0.9525)
			(end -0.4318 -0.9525)
			(stroke
				(width 0)
				(type default)
			)
			(fill no)
			(layer "B.CrtYd")
		)
		(fp_rect
			(start 0.4318 0.9525)
			(end -0.4318 -0.9525)
			(stroke
				(width 0)
				(type default)
			)
			(fill no)
			(layer "B.Fab")
		)
		(pad "1" smd custom
			(at 0 -0.4445 270)
			(size 0.1524 0.1524)
			(layers "B.Cu" "B.Mask" "B.Paste")
			(net "P1V8_STBY")
			(options
				(clearance outline)
				(anchor circle)
			)
			(primitives
				(gr_poly
					(pts
						(arc
							(start 0.3048 0.2032)
							(mid 0.275042 0.275042)
							(end 0.2032 0.3048)
						)
						(arc
							(start -0.2032 0.3048)
							(mid -0.275042 0.275042)
							(end -0.3048 0.2032)
						)
						(arc
							(start -0.3048 -0.2032)
							(mid -0.275042 -0.275042)
							(end -0.2032 -0.3048)
						)
						(arc
							(start 0.2032 -0.3048)
							(mid 0.275042 -0.275042)
							(end 0.3048 -0.2032)
						)
					)
					(width 0)
					(fill yes)
				)
			)
		)
		(pad "2" smd custom
			(at 0 0.4445 270)
			(size 0.1524 0.1524)
			(layers "B.Cu" "B.Mask" "B.Paste")
			(net "GND")
			(options
				(clearance outline)
				(anchor circle)
			)
			(primitives
				(gr_poly
					(pts
						(arc
							(start 0.3048 0.2032)
							(mid 0.275042 0.275042)
							(end 0.2032 0.3048)
						)
						(arc
							(start -0.2032 0.3048)
							(mid -0.275042 0.275042)
							(end -0.3048 0.2032)
						)
						(arc
							(start -0.3048 -0.2032)
							(mid -0.275042 -0.275042)
							(end -0.2032 -0.3048)
						)
						(arc
							(start 0.2032 -0.3048)
							(mid 0.275042 -0.275042)
							(end 0.3048 -0.2032)
						)
					)
					(width 0)
					(fill yes)
				)
			)
		)
	)
	(footprint ""
		(layer "B.Cu")
		(at 93.84792 -158.555944)
		(property "Reference" "C11"
			(at 0 0 0)
			(layer "B.SilkS")
			(hide yes)
			(effects
				(font
					(size 1.27 1.27)
				)
				(justify mirror)
			)
		)
		(property "Value" "SC1U16V2KX-7-GP"
			(at -1.7526 -1.6002 0)
			(unlocked yes)
			(layer "B.Fab")
			(hide yes)
			(effects
				(font
					(size 1.016 1.016)
					(thickness 0.1524)
				)
				(justify mirror)
			)
		)
		(property "Device Type" "C402-TO0D2H24"
			(at -1.7526 -3.1242 0)
			(unlocked yes)
			(layer "B.Fab")
			(hide yes)
			(effects
				(font
					(size 1.016 1.016)
					(thickness 0.1524)
				)
				(justify mirror)
			)
		)
		(duplicate_pad_numbers_are_jumpers no)
		(fp_rect
			(start 0.4826 0.889)
			(end -0.4826 -0.889)
			(stroke
				(width 0)
				(type default)
			)
			(fill no)
			(layer "B.CrtYd")
		)
		(fp_rect
			(start 0.4826 0.889)
			(end -0.4826 -0.889)
			(stroke
				(width 0)
				(type default)
			)
			(fill no)
			(layer "B.Fab")
		)
		(pad "1" smd custom
			(at 0 -0.4572 180)
			(size 0.1524 0.1524)
			(layers "B.Cu" "B.Mask" "B.Paste")
			(net "P3V3_STBY")
			(options
				(clearance outline)
				(anchor circle)
			)
			(primitives
				(gr_poly
					(pts
						(arc
							(start -0.254 -0.3048)
							(mid -0.325842 -0.275042)
							(end -0.3556 -0.2032)
						)
						(arc
							(start -0.3556 0.2032)
							(mid -0.325842 0.275042)
							(end -0.254 0.3048)
						)
						(arc
							(start 0.254 0.3048)
							(mid 0.325842 0.275042)
							(end 0.3556 0.2032)
						)
						(arc
							(start 0.3556 -0.2032)
							(mid 0.325842 -0.275042)
							(end 0.254 -0.3048)
						)
					)
					(width 0)
					(fill yes)
				)
			)
		)
		(pad "2" smd custom
			(at 0 0.4572 180)
			(size 0.1524 0.1524)
			(layers "B.Cu" "B.Mask" "B.Paste")
			(net "GND")
			(options
				(clearance outline)
				(anchor circle)
			)
			(primitives
				(gr_poly
					(pts
						(arc
							(start -0.254 -0.3048)
							(mid -0.325842 -0.275042)
							(end -0.3556 -0.2032)
						)
						(arc
							(start -0.3556 0.2032)
							(mid -0.325842 0.275042)
							(end -0.254 0.3048)
						)
						(arc
							(start 0.254 0.3048)
							(mid 0.325842 0.275042)
							(end 0.3556 0.2032)
						)
						(arc
							(start 0.3556 -0.2032)
							(mid 0.325842 -0.275042)
							(end 0.254 -0.3048)
						)
					)
					(width 0)
					(fill yes)
				)
			)
		)
	)
	(footprint ""
		(layer "B.Cu")
		(at 67.818 -148.463 -90)
		(property "Reference" "R334"
			(at 0 0 90)
			(layer "B.SilkS")
			(hide yes)
			(effects
				(font
					(size 1.27 1.27)
				)
				(justify mirror)
			)
		)
		(property "Value" "0R2J-2-GP"
			(at -0.064008 -3.993896 270)
			(unlocked yes)
			(layer "B.Fab")
			(hide yes)
			(effects
				(font
					(size 1.016 1.016)
					(thickness 0.1524)
				)
				(justify mirror)
			)
		)
		(property "Device Type" "R402H16"
			(at -0.064008 -5.517896 270)
			(unlocked yes)
			(layer "B.Fab")
			(hide yes)
			(effects
				(font
					(size 1.016 1.016)
					(thickness 0.1524)
				)
				(justify mirror)
			)
		)
		(duplicate_pad_numbers_are_jumpers no)
		(fp_line
			(start -0.508 -0.9398)
			(end 0.508 -0.9398)
			(stroke
				(width 0.1524)
				(type default)
			)
			(layer "B.SilkS")
		)
		(fp_line
			(start 0.508 -0.9398)
			(end 0.508 0.9398)
			(stroke
				(width 0.1524)
				(type default)
			)
			(layer "B.SilkS")
		)
		(fp_rect
			(start 0.508 0.9398)
			(end -0.508 -0.9398)
			(stroke
				(width 0)
				(type default)
			)
			(fill no)
			(layer "B.CrtYd")
		)
		(fp_rect
			(start 0.508 0.9398)
			(end -0.508 -0.9398)
			(stroke
				(width 0)
				(type default)
			)
			(fill no)
			(layer "B.Fab")
		)
		(pad "1" smd custom
			(at 0 -0.4445 90)
			(size 0.1397 0.1397)
			(layers "B.Cu" "B.Mask" "B.Paste")
			(net "NCSI_TXD0")
			(options
				(clearance outline)
				(anchor circle)
			)
			(primitives
				(gr_poly
					(pts
						(arc
							(start -0.1778 0.2794)
							(mid -0.249642 0.249642)
							(end -0.2794 0.1778)
						)
						(arc
							(start -0.2794 -0.1778)
							(mid -0.249642 -0.249642)
							(end -0.1778 -0.2794)
						)
						(arc
							(start 0.1778 -0.2794)
							(mid 0.249642 -0.249642)
							(end 0.2794 -0.1778)
						)
						(arc
							(start 0.2794 0.1778)
							(mid 0.249642 0.249642)
							(end 0.1778 0.2794)
						)
					)
					(width 0)
					(fill yes)
				)
			)
		)
		(pad "2" smd custom
			(at 0 0.4445 90)
			(size 0.1397 0.1397)
			(layers "B.Cu" "B.Mask" "B.Paste")
			(net "NCSI_TXD0_R")
			(options
				(clearance outline)
				(anchor circle)
			)
			(primitives
				(gr_poly
					(pts
						(arc
							(start -0.1778 0.2794)
							(mid -0.249642 0.249642)
							(end -0.2794 0.1778)
						)
						(arc
							(start -0.2794 -0.1778)
							(mid -0.249642 -0.249642)
							(end -0.1778 -0.2794)
						)
						(arc
							(start 0.1778 -0.2794)
							(mid 0.249642 -0.249642)
							(end 0.2794 -0.1778)
						)
						(arc
							(start 0.2794 0.1778)
							(mid 0.249642 0.249642)
							(end 0.1778 0.2794)
						)
					)
					(width 0)
					(fill yes)
				)
			)
		)
	)
	(footprint ""
		(layer "B.Cu")
		(at 49.6316 -134.239 90)
		(property "Reference" "R599"
			(at 0 0 90)
			(layer "B.SilkS")
			(hide yes)
			(effects
				(font
					(size 1.27 1.27)
				)
				(justify mirror)
			)
		)
		(property "Value" "4K7R2F-GP"
			(at -0.064008 -3.993896 90)
			(unlocked yes)
			(layer "B.Fab")
			(hide yes)
			(effects
				(font
					(size 1.016 1.016)
					(thickness 0.1524)
				)
				(justify mirror)
			)
		)
		(property "Device Type" "R402H16"
			(at -0.064008 -5.517896 90)
			(unlocked yes)
			(layer "B.Fab")
			(hide yes)
			(effects
				(font
					(size 1.016 1.016)
					(thickness 0.1524)
				)
				(justify mirror)
			)
		)
		(duplicate_pad_numbers_are_jumpers no)
		(fp_line
			(start 0.508 -0.9398)
			(end 0.508 0.9398)
			(stroke
				(width 0.1524)
				(type default)
			)
			(layer "B.SilkS")
		)
		(fp_line
			(start -0.508 -0.9398)
			(end 0.508 -0.9398)
			(stroke
				(width 0.1524)
				(type default)
			)
			(layer "B.SilkS")
		)
		(fp_rect
			(start 0.508 0.9398)
			(end -0.508 -0.9398)
			(stroke
				(width 0)
				(type default)
			)
			(fill no)
			(layer "B.CrtYd")
		)
		(fp_rect
			(start 0.508 0.9398)
			(end -0.508 -0.9398)
			(stroke
				(width 0)
				(type default)
			)
			(fill no)
			(layer "B.Fab")
		)
		(pad "1" smd custom
			(at 0 -0.4445 270)
			(size 0.1397 0.1397)
			(layers "B.Cu" "B.Mask" "B.Paste")
			(net "P3V3_STBY")
			(options
				(clearance outline)
				(anchor circle)
			)
			(primitives
				(gr_poly
					(pts
						(arc
							(start -0.1778 0.2794)
							(mid -0.249642 0.249642)
							(end -0.2794 0.1778)
						)
						(arc
							(start -0.2794 -0.1778)
							(mid -0.249642 -0.249642)
							(end -0.1778 -0.2794)
						)
						(arc
							(start 0.1778 -0.2794)
							(mid 0.249642 -0.249642)
							(end 0.2794 -0.1778)
						)
						(arc
							(start 0.2794 0.1778)
							(mid 0.249642 0.249642)
							(end 0.1778 0.2794)
						)
					)
					(width 0)
					(fill yes)
				)
			)
		)
		(pad "2" smd custom
			(at 0 0.4445 270)
			(size 0.1397 0.1397)
			(layers "B.Cu" "B.Mask" "B.Paste")
			(net "DPB_MISC_ALERT_OUT")
			(options
				(clearance outline)
				(anchor circle)
			)
			(primitives
				(gr_poly
					(pts
						(arc
							(start -0.1778 0.2794)
							(mid -0.249642 0.249642)
							(end -0.2794 0.1778)
						)
						(arc
							(start -0.2794 -0.1778)
							(mid -0.249642 -0.249642)
							(end -0.1778 -0.2794)
						)
						(arc
							(start 0.1778 -0.2794)
							(mid 0.249642 -0.249642)
							(end 0.2794 -0.1778)
						)
						(arc
							(start 0.2794 0.1778)
							(mid 0.249642 0.249642)
							(end 0.1778 0.2794)
						)
					)
					(width 0)
					(fill yes)
				)
			)
		)
	)
	(footprint ""
		(layer "B.Cu")
		(at 84.900008 -150.406862 -90)
		(property "Reference" "U15"
			(at 0 0 90)
			(layer "B.SilkS")
			(hide yes)
			(effects
				(font
					(size 1.27 1.27)
				)
				(justify mirror)
			)
		)
		(property "Value" "NX3L1G66GW-GP"
			(at 2.3368 -8.6868 270)
			(unlocked yes)
			(layer "B.Fab")
			(hide yes)
			(effects
				(font
					(size 1.016 1.016)
					(thickness 0.1524)
				)
				(justify mirror)
			)
		)
		(property "Device Type" "SC70-5H44"
			(at 2.3114 -10.414 270)
			(unlocked yes)
			(layer "B.Fab")
			(hide yes)
			(effects
				(font
					(size 1.016 1.016)
					(thickness 0.1524)
				)
				(justify mirror)
			)
		)
		(duplicate_pad_numbers_are_jumpers no)
		(fp_line
			(start -1.27 1.7018)
			(end 1.27 1.7018)
			(stroke
				(width 0.1524)
				(type default)
			)
			(layer "B.SilkS")
		)
		(fp_line
			(start 1.27 1.7018)
			(end 1.27 -1.7018)
			(stroke
				(width 0.1524)
				(type default)
			)
			(layer "B.SilkS")
		)
		(fp_line
			(start -1.27 -1.7018)
			(end -1.27 1.7018)
			(stroke
				(width 0.1524)
				(type default)
			)
			(layer "B.SilkS")
		)
		(fp_line
			(start 1.27 -1.7018)
			(end -1.27 -1.7018)
			(stroke
				(width 0.1524)
				(type default)
			)
			(layer "B.SilkS")
		)
		(fp_line
			(start -1.3843 -1.8034)
			(end -1.3843 -1.1176)
			(stroke
				(width 0.3302)
				(type default)
			)
			(layer "B.SilkS")
		)
		(fp_line
			(start -0.6604 -1.8034)
			(end -1.3843 -1.8034)
			(stroke
				(width 0.3302)
				(type default)
			)
			(layer "B.SilkS")
		)
		(fp_rect
			(start 1.524 1.9558)
			(end -1.524 -1.9558)
			(stroke
				(width 0)
				(type default)
			)
			(fill no)
			(layer "B.CrtYd")
		)
		(fp_poly
			(pts
				(xy 1.524 -1.9558) (xy -1.524 -1.9558) (xy -1.524 1.9558) (xy 1.524 1.9558)
			)
			(stroke
				(width 0)
				(type default)
			)
			(fill no)
			(layer "B.Fab")
		)
		(pad "1" smd rect
			(at -0.65024 -0.8255 90)
			(size 0.4064 1.2192)
			(layers "B.Cu" "B.Mask" "B.Paste")
			(net "I2C_BMC_COMP_SDA_R")
		)
		(pad "2" smd rect
			(at 0 -0.8255 90)
			(size 0.4064 1.2192)
			(layers "B.Cu" "B.Mask" "B.Paste")
			(net "I2C_BMC_COMP_SDA_OUT")
		)
		(pad "3" smd rect
			(at 0.65024 -0.8255 90)
			(size 0.4064 1.2192)
			(layers "B.Cu" "B.Mask" "B.Paste")
			(net "GND")
		)
		(pad "4" smd rect
			(at 0.65024 0.8255 90)
			(size 0.4064 1.2192)
			(layers "B.Cu" "B.Mask" "B.Paste")
			(net "COMP_PWR_EN")
		)
		(pad "5" smd rect
			(at -0.65024 0.8255 90)
			(size 0.4064 1.2192)
			(layers "B.Cu" "B.Mask" "B.Paste")
			(net "P3V3_STBY")
		)
	)
	(footprint ""
		(layer "B.Cu")
		(at 12.091924 -133.85673 90)
		(property "Reference" "R243"
			(at 0 0 90)
			(layer "B.SilkS")
			(hide yes)
			(effects
				(font
					(size 1.27 1.27)
				)
				(justify mirror)
			)
		)
		(property "Value" "120R2F-GP"
			(at -0.064008 -3.993896 90)
			(unlocked yes)
			(layer "B.Fab")
			(hide yes)
			(effects
				(font
					(size 1.016 1.016)
					(thickness 0.1524)
				)
				(justify mirror)
			)
		)
		(property "Device Type" "R402H16"
			(at -0.064008 -5.517896 90)
			(unlocked yes)
			(layer "B.Fab")
			(hide yes)
			(effects
				(font
					(size 1.016 1.016)
					(thickness 0.1524)
				)
				(justify mirror)
			)
		)
		(duplicate_pad_numbers_are_jumpers no)
		(fp_line
			(start 0.508 -0.9398)
			(end 0.508 0.9398)
			(stroke
				(width 0.1524)
				(type default)
			)
			(layer "B.SilkS")
		)
		(fp_line
			(start -0.508 -0.9398)
			(end 0.508 -0.9398)
			(stroke
				(width 0.1524)
				(type default)
			)
			(layer "B.SilkS")
		)
		(fp_rect
			(start 0.508 0.9398)
			(end -0.508 -0.9398)
			(stroke
				(width 0)
				(type default)
			)
			(fill no)
			(layer "B.CrtYd")
		)
		(fp_rect
			(start 0.508 0.9398)
			(end -0.508 -0.9398)
			(stroke
				(width 0)
				(type default)
			)
			(fill no)
			(layer "B.Fab")
		)
		(pad "1" smd custom
			(at 0 -0.4445 270)
			(size 0.1397 0.1397)
			(layers "B.Cu" "B.Mask" "B.Paste")
			(net "MEMA_4")
			(options
				(clearance outline)
				(anchor circle)
			)
			(primitives
				(gr_poly
					(pts
						(arc
							(start -0.1778 0.2794)
							(mid -0.249642 0.249642)
							(end -0.2794 0.1778)
						)
						(arc
							(start -0.2794 -0.1778)
							(mid -0.249642 -0.249642)
							(end -0.1778 -0.2794)
						)
						(arc
							(start 0.1778 -0.2794)
							(mid 0.249642 -0.249642)
							(end 0.2794 -0.1778)
						)
						(arc
							(start 0.2794 0.1778)
							(mid 0.249642 0.249642)
							(end 0.1778 0.2794)
						)
					)
					(width 0)
					(fill yes)
				)
			)
		)
		(pad "2" smd custom
			(at 0 0.4445 270)
			(size 0.1397 0.1397)
			(layers "B.Cu" "B.Mask" "B.Paste")
			(net "P1V2_STBY")
			(options
				(clearance outline)
				(anchor circle)
			)
			(primitives
				(gr_poly
					(pts
						(arc
							(start -0.1778 0.2794)
							(mid -0.249642 0.249642)
							(end -0.2794 0.1778)
						)
						(arc
							(start -0.2794 -0.1778)
							(mid -0.249642 -0.249642)
							(end -0.1778 -0.2794)
						)
						(arc
							(start 0.1778 -0.2794)
							(mid 0.249642 -0.249642)
							(end 0.2794 -0.1778)
						)
						(arc
							(start 0.2794 0.1778)
							(mid 0.249642 0.249642)
							(end 0.1778 0.2794)
						)
					)
					(width 0)
					(fill yes)
				)
			)
		)
	)
	(footprint ""
		(layer "B.Cu")
		(at 55.746142 -135.603742)
		(property "Reference" "R169"
			(at 0 0 0)
			(layer "B.SilkS")
			(hide yes)
			(effects
				(font
					(size 1.27 1.27)
				)
				(justify mirror)
			)
		)
		(property "Value" "0R2J-2-GP"
			(at -0.064008 -3.993896 0)
			(unlocked yes)
			(layer "B.Fab")
			(hide yes)
			(effects
				(font
					(size 1.016 1.016)
					(thickness 0.1524)
				)
				(justify mirror)
			)
		)
		(property "Device Type" "R402H16"
			(at -0.064008 -5.517896 0)
			(unlocked yes)
			(layer "B.Fab")
			(hide yes)
			(effects
				(font
					(size 1.016 1.016)
					(thickness 0.1524)
				)
				(justify mirror)
			)
		)
		(duplicate_pad_numbers_are_jumpers no)
		(fp_line
			(start -0.508 -0.9398)
			(end 0.508 -0.9398)
			(stroke
				(width 0.1524)
				(type default)
			)
			(layer "B.SilkS")
		)
		(fp_line
			(start 0.508 -0.9398)
			(end 0.508 0.9398)
			(stroke
				(width 0.1524)
				(type default)
			)
			(layer "B.SilkS")
		)
		(fp_rect
			(start 0.508 0.9398)
			(end -0.508 -0.9398)
			(stroke
				(width 0)
				(type default)
			)
			(fill no)
			(layer "B.CrtYd")
		)
		(fp_rect
			(start 0.508 0.9398)
			(end -0.508 -0.9398)
			(stroke
				(width 0)
				(type default)
			)
			(fill no)
			(layer "B.Fab")
		)
		(pad "1" smd custom
			(at 0 -0.4445 180)
			(size 0.1397 0.1397)
			(layers "B.Cu" "B.Mask" "B.Paste")
			(net "COMP_PWR_BTN_R_N")
			(options
				(clearance outline)
				(anchor circle)
			)
			(primitives
				(gr_poly
					(pts
						(arc
							(start -0.1778 0.2794)
							(mid -0.249642 0.249642)
							(end -0.2794 0.1778)
						)
						(arc
							(start -0.2794 -0.1778)
							(mid -0.249642 -0.249642)
							(end -0.1778 -0.2794)
						)
						(arc
							(start 0.1778 -0.2794)
							(mid 0.249642 -0.249642)
							(end 0.2794 -0.1778)
						)
						(arc
							(start 0.2794 0.1778)
							(mid 0.249642 0.249642)
							(end 0.1778 0.2794)
						)
					)
					(width 0)
					(fill yes)
				)
			)
		)
		(pad "2" smd custom
			(at 0 0.4445 180)
			(size 0.1397 0.1397)
			(layers "B.Cu" "B.Mask" "B.Paste")
			(net "COMP_PWR_BTN_N")
			(options
				(clearance outline)
				(anchor circle)
			)
			(primitives
				(gr_poly
					(pts
						(arc
							(start -0.1778 0.2794)
							(mid -0.249642 0.249642)
							(end -0.2794 0.1778)
						)
						(arc
							(start -0.2794 -0.1778)
							(mid -0.249642 -0.249642)
							(end -0.1778 -0.2794)
						)
						(arc
							(start 0.1778 -0.2794)
							(mid 0.249642 -0.249642)
							(end 0.2794 -0.1778)
						)
						(arc
							(start 0.2794 0.1778)
							(mid 0.249642 0.249642)
							(end 0.1778 0.2794)
						)
					)
					(width 0)
					(fill yes)
				)
			)
		)
	)
	(footprint ""
		(layer "B.Cu")
		(at 68.506086 -142.776702 180)
		(property "Reference" "R159"
			(at 0 0 0)
			(layer "B.SilkS")
			(hide yes)
			(effects
				(font
					(size 1.27 1.27)
				)
				(justify mirror)
			)
		)
		(property "Value" "0R2J-2-GP"
			(at -0.064008 -3.993896 180)
			(unlocked yes)
			(layer "B.Fab")
			(hide yes)
			(effects
				(font
					(size 1.016 1.016)
					(thickness 0.1524)
				)
				(justify mirror)
			)
		)
		(property "Device Type" "R402H16"
			(at -0.064008 -5.517896 180)
			(unlocked yes)
			(layer "B.Fab")
			(hide yes)
			(effects
				(font
					(size 1.016 1.016)
					(thickness 0.1524)
				)
				(justify mirror)
			)
		)
		(duplicate_pad_numbers_are_jumpers no)
		(fp_line
			(start 0.508 -0.9398)
			(end 0.508 0.9398)
			(stroke
				(width 0.1524)
				(type default)
			)
			(layer "B.SilkS")
		)
		(fp_line
			(start -0.508 -0.9398)
			(end 0.508 -0.9398)
			(stroke
				(width 0.1524)
				(type default)
			)
			(layer "B.SilkS")
		)
		(fp_rect
			(start 0.508 0.9398)
			(end -0.508 -0.9398)
			(stroke
				(width 0)
				(type default)
			)
			(fill no)
			(layer "B.CrtYd")
		)
		(fp_rect
			(start 0.508 0.9398)
			(end -0.508 -0.9398)
			(stroke
				(width 0)
				(type default)
			)
			(fill no)
			(layer "B.Fab")
		)
		(pad "1" smd custom
			(at 0 -0.4445)
			(size 0.1397 0.1397)
			(layers "B.Cu" "B.Mask" "B.Paste")
			(net "BMC_SMB12_CLK")
			(options
				(clearance outline)
				(anchor circle)
			)
			(primitives
				(gr_poly
					(pts
						(arc
							(start -0.1778 0.2794)
							(mid -0.249642 0.249642)
							(end -0.2794 0.1778)
						)
						(arc
							(start -0.2794 -0.1778)
							(mid -0.249642 -0.249642)
							(end -0.1778 -0.2794)
						)
						(arc
							(start 0.1778 -0.2794)
							(mid 0.249642 -0.249642)
							(end 0.2794 -0.1778)
						)
						(arc
							(start 0.2794 0.1778)
							(mid 0.249642 0.249642)
							(end 0.1778 0.2794)
						)
					)
					(width 0)
					(fill yes)
				)
			)
		)
		(pad "2" smd custom
			(at 0 0.4445)
			(size 0.1397 0.1397)
			(layers "B.Cu" "B.Mask" "B.Paste")
			(net "I2C_DEBUG_SCL_L")
			(options
				(clearance outline)
				(anchor circle)
			)
			(primitives
				(gr_poly
					(pts
						(arc
							(start -0.1778 0.2794)
							(mid -0.249642 0.249642)
							(end -0.2794 0.1778)
						)
						(arc
							(start -0.2794 -0.1778)
							(mid -0.249642 -0.249642)
							(end -0.1778 -0.2794)
						)
						(arc
							(start 0.1778 -0.2794)
							(mid 0.249642 -0.249642)
							(end 0.2794 -0.1778)
						)
						(arc
							(start 0.2794 0.1778)
							(mid 0.249642 0.249642)
							(end 0.1778 0.2794)
						)
					)
					(width 0)
					(fill yes)
				)
			)
		)
	)
	(footprint ""
		(layer "B.Cu")
		(at 43.129454 -119.168672 -90)
		(property "Reference" "R342"
			(at 0 0 90)
			(layer "B.SilkS")
			(hide yes)
			(effects
				(font
					(size 1.27 1.27)
				)
				(justify mirror)
			)
		)
		(property "Value" "0R2J-2-GP"
			(at -0.064008 -3.993896 270)
			(unlocked yes)
			(layer "B.Fab")
			(hide yes)
			(effects
				(font
					(size 1.016 1.016)
					(thickness 0.1524)
				)
				(justify mirror)
			)
		)
		(property "Device Type" "R402H16"
			(at -0.064008 -5.517896 270)
			(unlocked yes)
			(layer "B.Fab")
			(hide yes)
			(effects
				(font
					(size 1.016 1.016)
					(thickness 0.1524)
				)
				(justify mirror)
			)
		)
		(duplicate_pad_numbers_are_jumpers no)
		(fp_line
			(start -0.508 -0.9398)
			(end 0.508 -0.9398)
			(stroke
				(width 0.1524)
				(type default)
			)
			(layer "B.SilkS")
		)
		(fp_line
			(start 0.508 -0.9398)
			(end 0.508 0.9398)
			(stroke
				(width 0.1524)
				(type default)
			)
			(layer "B.SilkS")
		)
		(fp_rect
			(start 0.508 0.9398)
			(end -0.508 -0.9398)
			(stroke
				(width 0)
				(type default)
			)
			(fill no)
			(layer "B.CrtYd")
		)
		(fp_rect
			(start 0.508 0.9398)
			(end -0.508 -0.9398)
			(stroke
				(width 0)
				(type default)
			)
			(fill no)
			(layer "B.Fab")
		)
		(pad "1" smd custom
			(at 0 -0.4445 90)
			(size 0.1397 0.1397)
			(layers "B.Cu" "B.Mask" "B.Paste")
			(net "TEMP_3_SDA")
			(options
				(clearance outline)
				(anchor circle)
			)
			(primitives
				(gr_poly
					(pts
						(arc
							(start -0.1778 0.2794)
							(mid -0.249642 0.249642)
							(end -0.2794 0.1778)
						)
						(arc
							(start -0.2794 -0.1778)
							(mid -0.249642 -0.249642)
							(end -0.1778 -0.2794)
						)
						(arc
							(start 0.1778 -0.2794)
							(mid 0.249642 -0.249642)
							(end 0.2794 -0.1778)
						)
						(arc
							(start 0.2794 0.1778)
							(mid 0.249642 0.249642)
							(end 0.1778 0.2794)
						)
					)
					(width 0)
					(fill yes)
				)
			)
		)
		(pad "2" smd custom
			(at 0 0.4445 90)
			(size 0.1397 0.1397)
			(layers "B.Cu" "B.Mask" "B.Paste")
			(net "I2C_IOM_SDA")
			(options
				(clearance outline)
				(anchor circle)
			)
			(primitives
				(gr_poly
					(pts
						(arc
							(start -0.1778 0.2794)
							(mid -0.249642 0.249642)
							(end -0.2794 0.1778)
						)
						(arc
							(start -0.2794 -0.1778)
							(mid -0.249642 -0.249642)
							(end -0.1778 -0.2794)
						)
						(arc
							(start 0.1778 -0.2794)
							(mid 0.249642 -0.249642)
							(end 0.2794 -0.1778)
						)
						(arc
							(start 0.2794 0.1778)
							(mid 0.249642 0.249642)
							(end 0.1778 0.2794)
						)
					)
					(width 0)
					(fill yes)
				)
			)
		)
	)
	(footprint ""
		(layer "B.Cu")
		(at 80.345788 -153.995882 90)
		(property "Reference" "R100"
			(at 0 0 90)
			(layer "B.SilkS")
			(hide yes)
			(effects
				(font
					(size 1.27 1.27)
				)
				(justify mirror)
			)
		)
		(property "Value" "0R2J-2-GP"
			(at -0.064008 -3.993896 90)
			(unlocked yes)
			(layer "B.Fab")
			(hide yes)
			(effects
				(font
					(size 1.016 1.016)
					(thickness 0.1524)
				)
				(justify mirror)
			)
		)
		(property "Device Type" "R402H16"
			(at -0.064008 -5.517896 90)
			(unlocked yes)
			(layer "B.Fab")
			(hide yes)
			(effects
				(font
					(size 1.016 1.016)
					(thickness 0.1524)
				)
				(justify mirror)
			)
		)
		(duplicate_pad_numbers_are_jumpers no)
		(fp_line
			(start 0.508 -0.9398)
			(end 0.508 0.9398)
			(stroke
				(width 0.1524)
				(type default)
			)
			(layer "B.SilkS")
		)
		(fp_line
			(start -0.508 -0.9398)
			(end 0.508 -0.9398)
			(stroke
				(width 0.1524)
				(type default)
			)
			(layer "B.SilkS")
		)
		(fp_rect
			(start 0.508 0.9398)
			(end -0.508 -0.9398)
			(stroke
				(width 0)
				(type default)
			)
			(fill no)
			(layer "B.CrtYd")
		)
		(fp_rect
			(start 0.508 0.9398)
			(end -0.508 -0.9398)
			(stroke
				(width 0)
				(type default)
			)
			(fill no)
			(layer "B.Fab")
		)
		(pad "1" smd custom
			(at 0 -0.4445 270)
			(size 0.1397 0.1397)
			(layers "B.Cu" "B.Mask" "B.Paste")
			(net "I2C_BMC_COMP_ALERT_N_R")
			(options
				(clearance outline)
				(anchor circle)
			)
			(primitives
				(gr_poly
					(pts
						(arc
							(start -0.1778 0.2794)
							(mid -0.249642 0.249642)
							(end -0.2794 0.1778)
						)
						(arc
							(start -0.2794 -0.1778)
							(mid -0.249642 -0.249642)
							(end -0.1778 -0.2794)
						)
						(arc
							(start 0.1778 -0.2794)
							(mid 0.249642 -0.249642)
							(end 0.2794 -0.1778)
						)
						(arc
							(start 0.2794 0.1778)
							(mid 0.249642 0.249642)
							(end 0.1778 0.2794)
						)
					)
					(width 0)
					(fill yes)
				)
			)
		)
		(pad "2" smd custom
			(at 0 0.4445 270)
			(size 0.1397 0.1397)
			(layers "B.Cu" "B.Mask" "B.Paste")
			(net "I2C_BMC_COMP_ALERT_N")
			(options
				(clearance outline)
				(anchor circle)
			)
			(primitives
				(gr_poly
					(pts
						(arc
							(start -0.1778 0.2794)
							(mid -0.249642 0.249642)
							(end -0.2794 0.1778)
						)
						(arc
							(start -0.2794 -0.1778)
							(mid -0.249642 -0.249642)
							(end -0.1778 -0.2794)
						)
						(arc
							(start 0.1778 -0.2794)
							(mid 0.249642 -0.249642)
							(end 0.2794 -0.1778)
						)
						(arc
							(start 0.2794 0.1778)
							(mid 0.249642 0.249642)
							(end 0.1778 0.2794)
						)
					)
					(width 0)
					(fill yes)
				)
			)
		)
	)
	(footprint ""
		(layer "B.Cu")
		(at 48.690276 -135.719312)
		(property "Reference" "R142"
			(at 0 0 0)
			(layer "B.SilkS")
			(hide yes)
			(effects
				(font
					(size 1.27 1.27)
				)
				(justify mirror)
			)
		)
		(property "Value" "200R2F-L-GP"
			(at -0.064008 -3.993896 0)
			(unlocked yes)
			(layer "B.Fab")
			(hide yes)
			(effects
				(font
					(size 1.016 1.016)
					(thickness 0.1524)
				)
				(justify mirror)
			)
		)
		(property "Device Type" "R402H16"
			(at -0.064008 -5.517896 0)
			(unlocked yes)
			(layer "B.Fab")
			(hide yes)
			(effects
				(font
					(size 1.016 1.016)
					(thickness 0.1524)
				)
				(justify mirror)
			)
		)
		(duplicate_pad_numbers_are_jumpers no)
		(fp_line
			(start -0.508 -0.9398)
			(end 0.508 -0.9398)
			(stroke
				(width 0.1524)
				(type default)
			)
			(layer "B.SilkS")
		)
		(fp_line
			(start 0.508 -0.9398)
			(end 0.508 0.9398)
			(stroke
				(width 0.1524)
				(type default)
			)
			(layer "B.SilkS")
		)
		(fp_rect
			(start 0.508 0.9398)
			(end -0.508 -0.9398)
			(stroke
				(width 0)
				(type default)
			)
			(fill no)
			(layer "B.CrtYd")
		)
		(fp_rect
			(start 0.508 0.9398)
			(end -0.508 -0.9398)
			(stroke
				(width 0)
				(type default)
			)
			(fill no)
			(layer "B.Fab")
		)
		(pad "1" smd custom
			(at 0 -0.4445 180)
			(size 0.1397 0.1397)
			(layers "B.Cu" "B.Mask" "B.Paste")
			(net "BMC_PEREXT")
			(options
				(clearance outline)
				(anchor circle)
			)
			(primitives
				(gr_poly
					(pts
						(arc
							(start -0.1778 0.2794)
							(mid -0.249642 0.249642)
							(end -0.2794 0.1778)
						)
						(arc
							(start -0.2794 -0.1778)
							(mid -0.249642 -0.249642)
							(end -0.1778 -0.2794)
						)
						(arc
							(start 0.1778 -0.2794)
							(mid 0.249642 -0.249642)
							(end 0.2794 -0.1778)
						)
						(arc
							(start 0.2794 0.1778)
							(mid 0.249642 0.249642)
							(end 0.1778 0.2794)
						)
					)
					(width 0)
					(fill yes)
				)
			)
		)
		(pad "2" smd custom
			(at 0 0.4445 180)
			(size 0.1397 0.1397)
			(layers "B.Cu" "B.Mask" "B.Paste")
			(net "GND")
			(options
				(clearance outline)
				(anchor circle)
			)
			(primitives
				(gr_poly
					(pts
						(arc
							(start -0.1778 0.2794)
							(mid -0.249642 0.249642)
							(end -0.2794 0.1778)
						)
						(arc
							(start -0.2794 -0.1778)
							(mid -0.249642 -0.249642)
							(end -0.1778 -0.2794)
						)
						(arc
							(start 0.1778 -0.2794)
							(mid 0.249642 -0.249642)
							(end 0.2794 -0.1778)
						)
						(arc
							(start 0.2794 0.1778)
							(mid 0.249642 0.249642)
							(end 0.1778 0.2794)
						)
					)
					(width 0)
					(fill yes)
				)
			)
		)
	)
	(footprint ""
		(layer "B.Cu")
		(at 218.823794 -91.481402)
		(property "Reference" "R837"
			(at 0 0 0)
			(layer "B.SilkS")
			(hide yes)
			(effects
				(font
					(size 1.27 1.27)
				)
				(justify mirror)
			)
		)
		(property "Value" "2D7R3-GP"
			(at 0.0254 -2.5146 0)
			(unlocked yes)
			(layer "B.Fab")
			(hide yes)
			(effects
				(font
					(size 1.016 1.016)
					(thickness 0.1524)
				)
				(justify mirror)
			)
		)
		(property "Device Type" "R603H22"
			(at 0.0254 -4.0386 0)
			(unlocked yes)
			(layer "B.Fab")
			(hide yes)
			(effects
				(font
					(size 1.016 1.016)
					(thickness 0.1524)
				)
				(justify mirror)
			)
		)
		(duplicate_pad_numbers_are_jumpers no)
		(fp_line
			(start -0.2032 0)
			(end -0.4826 0)
			(stroke
				(width 0.2032)
				(type default)
			)
			(layer "B.SilkS")
		)
		(fp_line
			(start 0.4826 0)
			(end 0.2032 0)
			(stroke
				(width 0.2032)
				(type default)
			)
			(layer "B.SilkS")
		)
		(fp_rect
			(start 0.5842 1.3335)
			(end -0.5842 -1.3335)
			(stroke
				(width 0)
				(type default)
			)
			(fill no)
			(layer "B.CrtYd")
		)
		(fp_rect
			(start 0.5842 1.3335)
			(end -0.5842 -1.3335)
			(stroke
				(width 0)
				(type default)
			)
			(fill no)
			(layer "B.Fab")
		)
		(pad "1" smd custom
			(at 0 -0.762 180)
			(size 0.2159 0.2159)
			(layers "B.Cu" "B.Mask" "B.Paste")
			(net "P3V3_M2_VBST")
			(options
				(clearance outline)
				(anchor circle)
			)
			(primitives
				(gr_poly
					(pts
						(arc
							(start -0.3302 0.4318)
							(mid -0.402042 0.402042)
							(end -0.4318 0.3302)
						)
						(arc
							(start -0.4318 -0.3302)
							(mid -0.402042 -0.402042)
							(end -0.3302 -0.4318)
						)
						(arc
							(start 0.3302 -0.4318)
							(mid 0.402042 -0.402042)
							(end 0.4318 -0.3302)
						)
						(arc
							(start 0.4318 0.3302)
							(mid 0.402042 0.402042)
							(end 0.3302 0.4318)
						)
					)
					(width 0)
					(fill yes)
				)
			)
		)
		(pad "2" smd custom
			(at 0 0.762 180)
			(size 0.2159 0.2159)
			(layers "B.Cu" "B.Mask" "B.Paste")
			(net "P3V3_M2_VBST_RC")
			(options
				(clearance outline)
				(anchor circle)
			)
			(primitives
				(gr_poly
					(pts
						(arc
							(start -0.3302 0.4318)
							(mid -0.402042 0.402042)
							(end -0.4318 0.3302)
						)
						(arc
							(start -0.4318 -0.3302)
							(mid -0.402042 -0.402042)
							(end -0.3302 -0.4318)
						)
						(arc
							(start 0.3302 -0.4318)
							(mid 0.402042 -0.402042)
							(end 0.4318 -0.3302)
						)
						(arc
							(start 0.4318 0.3302)
							(mid 0.402042 0.402042)
							(end 0.3302 0.4318)
						)
					)
					(width 0)
					(fill yes)
				)
			)
		)
	)
	(footprint ""
		(layer "B.Cu")
		(at 224.989644 -72.07123 90)
		(property "Reference" "C655"
			(at 0 0 90)
			(layer "B.SilkS")
			(hide yes)
			(effects
				(font
					(size 1.27 1.27)
				)
				(justify mirror)
			)
		)
		(property "Value" "SC10U6D3V5KX-4GP"
			(at 0.0762 -6.1214 90)
			(unlocked yes)
			(layer "B.Fab")
			(hide yes)
			(effects
				(font
					(size 1.016 1.016)
					(thickness 0.1524)
				)
				(justify mirror)
			)
		)
		(property "Device Type" "C805H58"
			(at 0.0762 -8.1534 90)
			(unlocked yes)
			(layer "B.Fab")
			(hide yes)
			(effects
				(font
					(size 1.016 1.016)
					(thickness 0.1524)
				)
				(justify mirror)
			)
		)
		(duplicate_pad_numbers_are_jumpers no)
		(fp_line
			(start -0.635 0)
			(end 0.635 0)
			(stroke
				(width 0.508)
				(type default)
			)
			(layer "B.SilkS")
		)
		(fp_rect
			(start 0.9652 1.778)
			(end -0.9652 -1.778)
			(stroke
				(width 0)
				(type default)
			)
			(fill no)
			(layer "B.CrtYd")
		)
		(fp_poly
			(pts
				(xy 0.9652 -1.778) (xy -0.9652 -1.778) (xy -0.9652 1.778) (xy 0.9652 1.778)
			)
			(stroke
				(width 0)
				(type default)
			)
			(fill no)
			(layer "B.Fab")
		)
		(pad "1" smd rect
			(at 0 -0.9652 270)
			(size 1.397 1.143)
			(layers "B.Cu" "B.Mask" "B.Paste")
			(net "P3V3_M2")
		)
		(pad "2" smd rect
			(at 0 0.9652 270)
			(size 1.397 1.143)
			(layers "B.Cu" "B.Mask" "B.Paste")
			(net "GND")
		)
	)
	(footprint ""
		(layer "B.Cu")
		(at 175.294036 -130.732784 180)
		(property "Reference" "C616"
			(at 0 0 0)
			(layer "B.SilkS")
			(hide yes)
			(effects
				(font
					(size 1.27 1.27)
				)
				(justify mirror)
			)
		)
		(property "Value" "SCD1U16V2KX-3GP"
			(at -1.1811 -2.7051 180)
			(unlocked yes)
			(layer "B.Fab")
			(hide yes)
			(effects
				(font
					(size 1.016 1.016)
					(thickness 0.1524)
				)
				(justify mirror)
			)
		)
		(property "Device Type" "C402H22"
			(at -1.1811 -4.2291 180)
			(unlocked yes)
			(layer "B.Fab")
			(hide yes)
			(effects
				(font
					(size 1.016 1.016)
					(thickness 0.1524)
				)
				(justify mirror)
			)
		)
		(duplicate_pad_numbers_are_jumpers no)
		(fp_rect
			(start 0.4318 0.9525)
			(end -0.4318 -0.9525)
			(stroke
				(width 0)
				(type default)
			)
			(fill no)
			(layer "B.CrtYd")
		)
		(fp_rect
			(start 0.4318 0.9525)
			(end -0.4318 -0.9525)
			(stroke
				(width 0)
				(type default)
			)
			(fill no)
			(layer "B.Fab")
		)
		(pad "1" smd custom
			(at 0 -0.4445)
			(size 0.1524 0.1524)
			(layers "B.Cu" "B.Mask" "B.Paste")
			(net "P3V3_M2")
			(options
				(clearance outline)
				(anchor circle)
			)
			(primitives
				(gr_poly
					(pts
						(arc
							(start 0.3048 0.2032)
							(mid 0.275042 0.275042)
							(end 0.2032 0.3048)
						)
						(arc
							(start -0.2032 0.3048)
							(mid -0.275042 0.275042)
							(end -0.3048 0.2032)
						)
						(arc
							(start -0.3048 -0.2032)
							(mid -0.275042 -0.275042)
							(end -0.2032 -0.3048)
						)
						(arc
							(start 0.2032 -0.3048)
							(mid 0.275042 -0.275042)
							(end 0.3048 -0.2032)
						)
					)
					(width 0)
					(fill yes)
				)
			)
		)
		(pad "2" smd custom
			(at 0 0.4445)
			(size 0.1524 0.1524)
			(layers "B.Cu" "B.Mask" "B.Paste")
			(net "GND")
			(options
				(clearance outline)
				(anchor circle)
			)
			(primitives
				(gr_poly
					(pts
						(arc
							(start 0.3048 0.2032)
							(mid 0.275042 0.275042)
							(end 0.2032 0.3048)
						)
						(arc
							(start -0.2032 0.3048)
							(mid -0.275042 0.275042)
							(end -0.3048 0.2032)
						)
						(arc
							(start -0.3048 -0.2032)
							(mid -0.275042 -0.275042)
							(end -0.2032 -0.3048)
						)
						(arc
							(start 0.2032 -0.3048)
							(mid 0.275042 -0.275042)
							(end 0.3048 -0.2032)
						)
					)
					(width 0)
					(fill yes)
				)
			)
		)
	)
	(footprint ""
		(layer "B.Cu")
		(at 61.7474 -138.0998 -90)
		(property "Reference" "R185"
			(at 0 0 90)
			(layer "B.SilkS")
			(hide yes)
			(effects
				(font
					(size 1.27 1.27)
				)
				(justify mirror)
			)
		)
		(property "Value" "2K2R2F-GP"
			(at -0.064008 -3.993896 270)
			(unlocked yes)
			(layer "B.Fab")
			(hide yes)
			(effects
				(font
					(size 1.016 1.016)
					(thickness 0.1524)
				)
				(justify mirror)
			)
		)
		(property "Device Type" "R402H16"
			(at -0.064008 -5.517896 270)
			(unlocked yes)
			(layer "B.Fab")
			(hide yes)
			(effects
				(font
					(size 1.016 1.016)
					(thickness 0.1524)
				)
				(justify mirror)
			)
		)
		(duplicate_pad_numbers_are_jumpers no)
		(fp_line
			(start -0.508 -0.9398)
			(end 0.508 -0.9398)
			(stroke
				(width 0.1524)
				(type default)
			)
			(layer "B.SilkS")
		)
		(fp_line
			(start 0.508 -0.9398)
			(end 0.508 0.9398)
			(stroke
				(width 0.1524)
				(type default)
			)
			(layer "B.SilkS")
		)
		(fp_rect
			(start 0.508 0.9398)
			(end -0.508 -0.9398)
			(stroke
				(width 0)
				(type default)
			)
			(fill no)
			(layer "B.CrtYd")
		)
		(fp_rect
			(start 0.508 0.9398)
			(end -0.508 -0.9398)
			(stroke
				(width 0)
				(type default)
			)
			(fill no)
			(layer "B.Fab")
		)
		(pad "1" smd custom
			(at 0 -0.4445 90)
			(size 0.1397 0.1397)
			(layers "B.Cu" "B.Mask" "B.Paste")
			(net "I2C_M2_2_SCL")
			(options
				(clearance outline)
				(anchor circle)
			)
			(primitives
				(gr_poly
					(pts
						(arc
							(start -0.1778 0.2794)
							(mid -0.249642 0.249642)
							(end -0.2794 0.1778)
						)
						(arc
							(start -0.2794 -0.1778)
							(mid -0.249642 -0.249642)
							(end -0.1778 -0.2794)
						)
						(arc
							(start 0.1778 -0.2794)
							(mid 0.249642 -0.249642)
							(end 0.2794 -0.1778)
						)
						(arc
							(start 0.2794 0.1778)
							(mid 0.249642 0.249642)
							(end 0.1778 0.2794)
						)
					)
					(width 0)
					(fill yes)
				)
			)
		)
		(pad "2" smd custom
			(at 0 0.4445 90)
			(size 0.1397 0.1397)
			(layers "B.Cu" "B.Mask" "B.Paste")
			(net "P3V3_STBY")
			(options
				(clearance outline)
				(anchor circle)
			)
			(primitives
				(gr_poly
					(pts
						(arc
							(start -0.1778 0.2794)
							(mid -0.249642 0.249642)
							(end -0.2794 0.1778)
						)
						(arc
							(start -0.2794 -0.1778)
							(mid -0.249642 -0.249642)
							(end -0.1778 -0.2794)
						)
						(arc
							(start 0.1778 -0.2794)
							(mid 0.249642 -0.249642)
							(end 0.2794 -0.1778)
						)
						(arc
							(start 0.2794 0.1778)
							(mid 0.249642 0.249642)
							(end 0.1778 0.2794)
						)
					)
					(width 0)
					(fill yes)
				)
			)
		)
	)
	(footprint ""
		(layer "B.Cu")
		(at 38.419278 -143.058642)
		(property "Reference" "C58"
			(at 0 0 0)
			(layer "B.SilkS")
			(hide yes)
			(effects
				(font
					(size 1.27 1.27)
				)
				(justify mirror)
			)
		)
		(property "Value" "SC1U16V3KX-5GP"
			(at 0 -2.8194 0)
			(unlocked yes)
			(layer "B.Fab")
			(hide yes)
			(effects
				(font
					(size 1.016 1.016)
					(thickness 0.1524)
				)
				(justify mirror)
			)
		)
		(property "Device Type" "C603H36"
			(at 0 -4.3434 0)
			(unlocked yes)
			(layer "B.Fab")
			(hide yes)
			(effects
				(font
					(size 1.016 1.016)
					(thickness 0.1524)
				)
				(justify mirror)
			)
		)
		(duplicate_pad_numbers_are_jumpers no)
		(fp_line
			(start -0.508 0)
			(end 0.508 0)
			(stroke
				(width 0.2032)
				(type default)
			)
			(layer "B.SilkS")
		)
		(fp_rect
			(start 0.5842 1.3335)
			(end -0.5842 -1.3335)
			(stroke
				(width 0)
				(type default)
			)
			(fill no)
			(layer "B.CrtYd")
		)
		(fp_rect
			(start 0.5842 1.3335)
			(end -0.5842 -1.3335)
			(stroke
				(width 0)
				(type default)
			)
			(fill no)
			(layer "B.Fab")
		)
		(pad "1" smd custom
			(at 0 -0.762 180)
			(size 0.2159 0.2159)
			(layers "B.Cu" "B.Mask" "B.Paste")
			(net "P1V2_STBY")
			(options
				(clearance outline)
				(anchor circle)
			)
			(primitives
				(gr_poly
					(pts
						(arc
							(start -0.3302 0.4318)
							(mid -0.402042 0.402042)
							(end -0.4318 0.3302)
						)
						(arc
							(start -0.4318 -0.3302)
							(mid -0.402042 -0.402042)
							(end -0.3302 -0.4318)
						)
						(arc
							(start 0.3302 -0.4318)
							(mid 0.402042 -0.402042)
							(end 0.4318 -0.3302)
						)
						(arc
							(start 0.4318 0.3302)
							(mid 0.402042 0.402042)
							(end 0.3302 0.4318)
						)
					)
					(width 0)
					(fill yes)
				)
			)
		)
		(pad "2" smd custom
			(at 0 0.762 180)
			(size 0.2159 0.2159)
			(layers "B.Cu" "B.Mask" "B.Paste")
			(net "GND")
			(options
				(clearance outline)
				(anchor circle)
			)
			(primitives
				(gr_poly
					(pts
						(arc
							(start -0.3302 0.4318)
							(mid -0.402042 0.402042)
							(end -0.4318 0.3302)
						)
						(arc
							(start -0.4318 -0.3302)
							(mid -0.402042 -0.402042)
							(end -0.3302 -0.4318)
						)
						(arc
							(start 0.3302 -0.4318)
							(mid 0.402042 -0.402042)
							(end 0.4318 -0.3302)
						)
						(arc
							(start 0.4318 0.3302)
							(mid 0.402042 0.402042)
							(end 0.3302 0.4318)
						)
					)
					(width 0)
					(fill yes)
				)
			)
		)
	)
	(footprint ""
		(layer "B.Cu")
		(at 120.123966 -6.5532 90)
		(property "Reference" "C132"
			(at 0 0 90)
			(layer "B.SilkS")
			(hide yes)
			(effects
				(font
					(size 1.27 1.27)
				)
				(justify mirror)
			)
		)
		(property "Value" "SC22UF16V6KX-GP"
			(at 0 -6.8072 90)
			(unlocked yes)
			(layer "B.Fab")
			(hide yes)
			(effects
				(font
					(size 1.016 1.016)
					(thickness 0.1524)
				)
				(justify mirror)
			)
		)
		(property "Device Type" "C1206H75"
			(at 0 -8.7122 90)
			(unlocked yes)
			(layer "B.Fab")
			(hide yes)
			(effects
				(font
					(size 1.016 1.016)
					(thickness 0.1524)
				)
				(justify mirror)
			)
		)
		(duplicate_pad_numbers_are_jumpers no)
		(fp_line
			(start 1.016 -2.2352)
			(end 1.016 -0.8382)
			(stroke
				(width 0.1524)
				(type default)
			)
			(layer "B.SilkS")
		)
		(fp_line
			(start -1.016 -2.2352)
			(end 1.016 -2.2352)
			(stroke
				(width 0.1524)
				(type default)
			)
			(layer "B.SilkS")
		)
		(fp_line
			(start -1.016 -2.2352)
			(end -1.016 -0.8382)
			(stroke
				(width 0.1524)
				(type default)
			)
			(layer "B.SilkS")
		)
		(fp_line
			(start -1.016 0.8382)
			(end -1.016 2.2352)
			(stroke
				(width 0.1524)
				(type default)
			)
			(layer "B.SilkS")
		)
		(fp_line
			(start 1.016 2.2352)
			(end 1.016 0.8128)
			(stroke
				(width 0.1524)
				(type default)
			)
			(layer "B.SilkS")
		)
		(fp_line
			(start -1.016 2.2352)
			(end 1.016 2.2352)
			(stroke
				(width 0.1524)
				(type default)
			)
			(layer "B.SilkS")
		)
		(fp_rect
			(start 1.0922 2.3114)
			(end -1.0922 -2.3114)
			(stroke
				(width 0)
				(type default)
			)
			(fill no)
			(layer "B.CrtYd")
		)
		(fp_poly
			(pts
				(xy 1.0922 -2.3114) (xy -1.0922 -2.3114) (xy -1.0922 2.3114) (xy 1.0922 2.3114)
			)
			(stroke
				(width 0)
				(type default)
			)
			(fill no)
			(layer "B.Fab")
		)
		(pad "1" smd rect
			(at 0 -1.397 270)
			(size 1.651 1.27)
			(layers "B.Cu" "B.Mask" "B.Paste")
			(net "MB0_HS_ENABLE")
		)
		(pad "2" smd rect
			(at 0 1.397 270)
			(size 1.651 1.27)
			(layers "B.Cu" "B.Mask" "B.Paste")
			(net "GND")
		)
	)
	(footprint ""
		(layer "B.Cu")
		(at 57.3278 -145.2626 -90)
		(property "Reference" "R361"
			(at 0 0 90)
			(layer "B.SilkS")
			(hide yes)
			(effects
				(font
					(size 1.27 1.27)
				)
				(justify mirror)
			)
		)
		(property "Value" "10KR2F-2-GP"
			(at -0.064008 -3.993896 270)
			(unlocked yes)
			(layer "B.Fab")
			(hide yes)
			(effects
				(font
					(size 1.016 1.016)
					(thickness 0.1524)
				)
				(justify mirror)
			)
		)
		(property "Device Type" "R402H16"
			(at -0.064008 -5.517896 270)
			(unlocked yes)
			(layer "B.Fab")
			(hide yes)
			(effects
				(font
					(size 1.016 1.016)
					(thickness 0.1524)
				)
				(justify mirror)
			)
		)
		(duplicate_pad_numbers_are_jumpers no)
		(fp_line
			(start -0.508 -0.9398)
			(end 0.508 -0.9398)
			(stroke
				(width 0.1524)
				(type default)
			)
			(layer "B.SilkS")
		)
		(fp_line
			(start 0.508 -0.9398)
			(end 0.508 0.9398)
			(stroke
				(width 0.1524)
				(type default)
			)
			(layer "B.SilkS")
		)
		(fp_rect
			(start 0.508 0.9398)
			(end -0.508 -0.9398)
			(stroke
				(width 0)
				(type default)
			)
			(fill no)
			(layer "B.CrtYd")
		)
		(fp_rect
			(start 0.508 0.9398)
			(end -0.508 -0.9398)
			(stroke
				(width 0)
				(type default)
			)
			(fill no)
			(layer "B.Fab")
		)
		(pad "1" smd custom
			(at 0 -0.4445 90)
			(size 0.1397 0.1397)
			(layers "B.Cu" "B.Mask" "B.Paste")
			(net "P3V3_STBY")
			(options
				(clearance outline)
				(anchor circle)
			)
			(primitives
				(gr_poly
					(pts
						(arc
							(start -0.1778 0.2794)
							(mid -0.249642 0.249642)
							(end -0.2794 0.1778)
						)
						(arc
							(start -0.2794 -0.1778)
							(mid -0.249642 -0.249642)
							(end -0.1778 -0.2794)
						)
						(arc
							(start 0.1778 -0.2794)
							(mid 0.249642 -0.249642)
							(end 0.2794 -0.1778)
						)
						(arc
							(start 0.2794 0.1778)
							(mid 0.249642 0.249642)
							(end 0.1778 0.2794)
						)
					)
					(width 0)
					(fill yes)
				)
			)
		)
		(pad "2" smd custom
			(at 0 0.4445 90)
			(size 0.1397 0.1397)
			(layers "B.Cu" "B.Mask" "B.Paste")
			(net "JTAG_BMC_TDO")
			(options
				(clearance outline)
				(anchor circle)
			)
			(primitives
				(gr_poly
					(pts
						(arc
							(start -0.1778 0.2794)
							(mid -0.249642 0.249642)
							(end -0.2794 0.1778)
						)
						(arc
							(start -0.2794 -0.1778)
							(mid -0.249642 -0.249642)
							(end -0.1778 -0.2794)
						)
						(arc
							(start 0.1778 -0.2794)
							(mid 0.249642 -0.249642)
							(end 0.2794 -0.1778)
						)
						(arc
							(start 0.2794 0.1778)
							(mid 0.249642 0.249642)
							(end 0.1778 0.2794)
						)
					)
					(width 0)
					(fill yes)
				)
			)
		)
	)
	(footprint ""
		(layer "B.Cu")
		(at 53.877972 -119.200422 180)
		(property "Reference" "R282"
			(at 0 0 0)
			(layer "B.SilkS")
			(hide yes)
			(effects
				(font
					(size 1.27 1.27)
				)
				(justify mirror)
			)
		)
		(property "Value" "4K7R2F-GP"
			(at -0.064008 -3.993896 180)
			(unlocked yes)
			(layer "B.Fab")
			(hide yes)
			(effects
				(font
					(size 1.016 1.016)
					(thickness 0.1524)
				)
				(justify mirror)
			)
		)
		(property "Device Type" "R402H16"
			(at -0.064008 -5.517896 180)
			(unlocked yes)
			(layer "B.Fab")
			(hide yes)
			(effects
				(font
					(size 1.016 1.016)
					(thickness 0.1524)
				)
				(justify mirror)
			)
		)
		(duplicate_pad_numbers_are_jumpers no)
		(fp_line
			(start 0.508 -0.9398)
			(end 0.508 0.9398)
			(stroke
				(width 0.1524)
				(type default)
			)
			(layer "B.SilkS")
		)
		(fp_line
			(start -0.508 -0.9398)
			(end 0.508 -0.9398)
			(stroke
				(width 0.1524)
				(type default)
			)
			(layer "B.SilkS")
		)
		(fp_rect
			(start 0.508 0.9398)
			(end -0.508 -0.9398)
			(stroke
				(width 0)
				(type default)
			)
			(fill no)
			(layer "B.CrtYd")
		)
		(fp_rect
			(start 0.508 0.9398)
			(end -0.508 -0.9398)
			(stroke
				(width 0)
				(type default)
			)
			(fill no)
			(layer "B.Fab")
		)
		(pad "1" smd custom
			(at 0 -0.4445)
			(size 0.1397 0.1397)
			(layers "B.Cu" "B.Mask" "B.Paste")
			(net "P3V3_STBY")
			(options
				(clearance outline)
				(anchor circle)
			)
			(primitives
				(gr_poly
					(pts
						(arc
							(start -0.1778 0.2794)
							(mid -0.249642 0.249642)
							(end -0.2794 0.1778)
						)
						(arc
							(start -0.2794 -0.1778)
							(mid -0.249642 -0.249642)
							(end -0.1778 -0.2794)
						)
						(arc
							(start 0.1778 -0.2794)
							(mid 0.249642 -0.249642)
							(end 0.2794 -0.1778)
						)
						(arc
							(start 0.2794 0.1778)
							(mid 0.249642 0.249642)
							(end 0.1778 0.2794)
						)
					)
					(width 0)
					(fill yes)
				)
			)
		)
		(pad "2" smd custom
			(at 0 0.4445)
			(size 0.1397 0.1397)
			(layers "B.Cu" "B.Mask" "B.Paste")
			(net "TEMP_3_A0")
			(options
				(clearance outline)
				(anchor circle)
			)
			(primitives
				(gr_poly
					(pts
						(arc
							(start -0.1778 0.2794)
							(mid -0.249642 0.249642)
							(end -0.2794 0.1778)
						)
						(arc
							(start -0.2794 -0.1778)
							(mid -0.249642 -0.249642)
							(end -0.1778 -0.2794)
						)
						(arc
							(start 0.1778 -0.2794)
							(mid 0.249642 -0.249642)
							(end 0.2794 -0.1778)
						)
						(arc
							(start 0.2794 0.1778)
							(mid 0.249642 0.249642)
							(end 0.1778 0.2794)
						)
					)
					(width 0)
					(fill yes)
				)
			)
		)
	)
	(footprint ""
		(layer "B.Cu")
		(at 35.862006 -152.028398 180)
		(property "Reference" "C54"
			(at 0 0 0)
			(layer "B.SilkS")
			(hide yes)
			(effects
				(font
					(size 1.27 1.27)
				)
				(justify mirror)
			)
		)
		(property "Value" "SC1U16V3KX-5GP"
			(at 0 -2.8194 180)
			(unlocked yes)
			(layer "B.Fab")
			(hide yes)
			(effects
				(font
					(size 1.016 1.016)
					(thickness 0.1524)
				)
				(justify mirror)
			)
		)
		(property "Device Type" "C603H36"
			(at 0 -4.3434 180)
			(unlocked yes)
			(layer "B.Fab")
			(hide yes)
			(effects
				(font
					(size 1.016 1.016)
					(thickness 0.1524)
				)
				(justify mirror)
			)
		)
		(duplicate_pad_numbers_are_jumpers no)
		(fp_line
			(start -0.508 0)
			(end 0.508 0)
			(stroke
				(width 0.2032)
				(type default)
			)
			(layer "B.SilkS")
		)
		(fp_rect
			(start 0.5842 1.3335)
			(end -0.5842 -1.3335)
			(stroke
				(width 0)
				(type default)
			)
			(fill no)
			(layer "B.CrtYd")
		)
		(fp_rect
			(start 0.5842 1.3335)
			(end -0.5842 -1.3335)
			(stroke
				(width 0)
				(type default)
			)
			(fill no)
			(layer "B.Fab")
		)
		(pad "1" smd custom
			(at 0 -0.762)
			(size 0.2159 0.2159)
			(layers "B.Cu" "B.Mask" "B.Paste")
			(net "DDR_VREF")
			(options
				(clearance outline)
				(anchor circle)
			)
			(primitives
				(gr_poly
					(pts
						(arc
							(start -0.3302 0.4318)
							(mid -0.402042 0.402042)
							(end -0.4318 0.3302)
						)
						(arc
							(start -0.4318 -0.3302)
							(mid -0.402042 -0.402042)
							(end -0.3302 -0.4318)
						)
						(arc
							(start 0.3302 -0.4318)
							(mid 0.402042 -0.402042)
							(end 0.4318 -0.3302)
						)
						(arc
							(start 0.4318 0.3302)
							(mid 0.402042 0.402042)
							(end 0.3302 0.4318)
						)
					)
					(width 0)
					(fill yes)
				)
			)
		)
		(pad "2" smd custom
			(at 0 0.762)
			(size 0.2159 0.2159)
			(layers "B.Cu" "B.Mask" "B.Paste")
			(net "GND")
			(options
				(clearance outline)
				(anchor circle)
			)
			(primitives
				(gr_poly
					(pts
						(arc
							(start -0.3302 0.4318)
							(mid -0.402042 0.402042)
							(end -0.4318 0.3302)
						)
						(arc
							(start -0.4318 -0.3302)
							(mid -0.402042 -0.402042)
							(end -0.3302 -0.4318)
						)
						(arc
							(start 0.3302 -0.4318)
							(mid 0.402042 -0.402042)
							(end 0.4318 -0.3302)
						)
						(arc
							(start 0.4318 0.3302)
							(mid 0.402042 0.402042)
							(end 0.3302 0.4318)
						)
					)
					(width 0)
					(fill yes)
				)
			)
		)
	)
	(footprint ""
		(layer "B.Cu")
		(at 38.231064 -144.85747 -90)
		(property "Reference" "C71"
			(at 0 0 90)
			(layer "B.SilkS")
			(hide yes)
			(effects
				(font
					(size 1.27 1.27)
				)
				(justify mirror)
			)
		)
		(property "Value" "SCD1U16V2KX-3GP"
			(at -1.1811 -2.7051 270)
			(unlocked yes)
			(layer "B.Fab")
			(hide yes)
			(effects
				(font
					(size 1.016 1.016)
					(thickness 0.1524)
				)
				(justify mirror)
			)
		)
		(property "Device Type" "C402H22"
			(at -1.1811 -4.2291 270)
			(unlocked yes)
			(layer "B.Fab")
			(hide yes)
			(effects
				(font
					(size 1.016 1.016)
					(thickness 0.1524)
				)
				(justify mirror)
			)
		)
		(duplicate_pad_numbers_are_jumpers no)
		(fp_rect
			(start 0.4318 0.9525)
			(end -0.4318 -0.9525)
			(stroke
				(width 0)
				(type default)
			)
			(fill no)
			(layer "B.CrtYd")
		)
		(fp_rect
			(start 0.4318 0.9525)
			(end -0.4318 -0.9525)
			(stroke
				(width 0)
				(type default)
			)
			(fill no)
			(layer "B.Fab")
		)
		(pad "1" smd custom
			(at 0 -0.4445 90)
			(size 0.1524 0.1524)
			(layers "B.Cu" "B.Mask" "B.Paste")
			(net "GND")
			(options
				(clearance outline)
				(anchor circle)
			)
			(primitives
				(gr_poly
					(pts
						(arc
							(start 0.3048 0.2032)
							(mid 0.275042 0.275042)
							(end 0.2032 0.3048)
						)
						(arc
							(start -0.2032 0.3048)
							(mid -0.275042 0.275042)
							(end -0.3048 0.2032)
						)
						(arc
							(start -0.3048 -0.2032)
							(mid -0.275042 -0.275042)
							(end -0.2032 -0.3048)
						)
						(arc
							(start 0.2032 -0.3048)
							(mid 0.275042 -0.275042)
							(end 0.3048 -0.2032)
						)
					)
					(width 0)
					(fill yes)
				)
			)
		)
		(pad "2" smd custom
			(at 0 0.4445 90)
			(size 0.1524 0.1524)
			(layers "B.Cu" "B.Mask" "B.Paste")
			(net "P1V2_STBY")
			(options
				(clearance outline)
				(anchor circle)
			)
			(primitives
				(gr_poly
					(pts
						(arc
							(start 0.3048 0.2032)
							(mid 0.275042 0.275042)
							(end 0.2032 0.3048)
						)
						(arc
							(start -0.2032 0.3048)
							(mid -0.275042 0.275042)
							(end -0.3048 0.2032)
						)
						(arc
							(start -0.3048 -0.2032)
							(mid -0.275042 -0.275042)
							(end -0.2032 -0.3048)
						)
						(arc
							(start 0.2032 -0.3048)
							(mid 0.275042 -0.275042)
							(end 0.3048 -0.2032)
						)
					)
					(width 0)
					(fill yes)
				)
			)
		)
	)
	(footprint ""
		(layer "B.Cu")
		(at 195.197476 -137.218674 90)
		(property "Reference" "R809"
			(at 0 0 90)
			(layer "B.SilkS")
			(hide yes)
			(effects
				(font
					(size 1.27 1.27)
				)
				(justify mirror)
			)
		)
		(property "Value" "0R2J-2-GP"
			(at -0.064008 -3.993896 90)
			(unlocked yes)
			(layer "B.Fab")
			(hide yes)
			(effects
				(font
					(size 1.016 1.016)
					(thickness 0.1524)
				)
				(justify mirror)
			)
		)
		(property "Device Type" "R402H16"
			(at -0.064008 -5.517896 90)
			(unlocked yes)
			(layer "B.Fab")
			(hide yes)
			(effects
				(font
					(size 1.016 1.016)
					(thickness 0.1524)
				)
				(justify mirror)
			)
		)
		(duplicate_pad_numbers_are_jumpers no)
		(fp_line
			(start 0.508 -0.9398)
			(end 0.508 0.9398)
			(stroke
				(width 0.1524)
				(type default)
			)
			(layer "B.SilkS")
		)
		(fp_line
			(start -0.508 -0.9398)
			(end 0.508 -0.9398)
			(stroke
				(width 0.1524)
				(type default)
			)
			(layer "B.SilkS")
		)
		(fp_rect
			(start 0.508 0.9398)
			(end -0.508 -0.9398)
			(stroke
				(width 0)
				(type default)
			)
			(fill no)
			(layer "B.CrtYd")
		)
		(fp_rect
			(start 0.508 0.9398)
			(end -0.508 -0.9398)
			(stroke
				(width 0)
				(type default)
			)
			(fill no)
			(layer "B.Fab")
		)
		(pad "1" smd custom
			(at 0 -0.4445 270)
			(size 0.1397 0.1397)
			(layers "B.Cu" "B.Mask" "B.Paste")
			(net "M2_1_PRESENT_N_R")
			(options
				(clearance outline)
				(anchor circle)
			)
			(primitives
				(gr_poly
					(pts
						(arc
							(start -0.1778 0.2794)
							(mid -0.249642 0.249642)
							(end -0.2794 0.1778)
						)
						(arc
							(start -0.2794 -0.1778)
							(mid -0.249642 -0.249642)
							(end -0.1778 -0.2794)
						)
						(arc
							(start 0.1778 -0.2794)
							(mid 0.249642 -0.249642)
							(end 0.2794 -0.1778)
						)
						(arc
							(start 0.2794 0.1778)
							(mid 0.249642 0.249642)
							(end 0.1778 0.2794)
						)
					)
					(width 0)
					(fill yes)
				)
			)
		)
		(pad "2" smd custom
			(at 0 0.4445 270)
			(size 0.1397 0.1397)
			(layers "B.Cu" "B.Mask" "B.Paste")
			(net "GND")
			(options
				(clearance outline)
				(anchor circle)
			)
			(primitives
				(gr_poly
					(pts
						(arc
							(start -0.1778 0.2794)
							(mid -0.249642 0.249642)
							(end -0.2794 0.1778)
						)
						(arc
							(start -0.2794 -0.1778)
							(mid -0.249642 -0.249642)
							(end -0.1778 -0.2794)
						)
						(arc
							(start 0.1778 -0.2794)
							(mid 0.249642 -0.249642)
							(end 0.2794 -0.1778)
						)
						(arc
							(start 0.2794 0.1778)
							(mid 0.249642 0.249642)
							(end 0.1778 0.2794)
						)
					)
					(width 0)
					(fill yes)
				)
			)
		)
	)
	(footprint ""
		(layer "B.Cu")
		(at 63.373 -157.5562 180)
		(property "Reference" "C81"
			(at 0 0 0)
			(layer "B.SilkS")
			(hide yes)
			(effects
				(font
					(size 1.27 1.27)
				)
				(justify mirror)
			)
		)
		(property "Value" "SC4D7U25V5KX-1-GP"
			(at 0.0762 -6.1214 180)
			(unlocked yes)
			(layer "B.Fab")
			(hide yes)
			(effects
				(font
					(size 1.016 1.016)
					(thickness 0.1524)
				)
				(justify mirror)
			)
		)
		(property "Device Type" "C805H58"
			(at 0.0762 -8.1534 180)
			(unlocked yes)
			(layer "B.Fab")
			(hide yes)
			(effects
				(font
					(size 1.016 1.016)
					(thickness 0.1524)
				)
				(justify mirror)
			)
		)
		(duplicate_pad_numbers_are_jumpers no)
		(fp_line
			(start -0.635 0)
			(end 0.635 0)
			(stroke
				(width 0.508)
				(type default)
			)
			(layer "B.SilkS")
		)
		(fp_rect
			(start 0.9652 1.778)
			(end -0.9652 -1.778)
			(stroke
				(width 0)
				(type default)
			)
			(fill no)
			(layer "B.CrtYd")
		)
		(fp_poly
			(pts
				(xy 0.9652 -1.778) (xy -0.9652 -1.778) (xy -0.9652 1.778) (xy 0.9652 1.778)
			)
			(stroke
				(width 0)
				(type default)
			)
			(fill no)
			(layer "B.Fab")
		)
		(pad "1" smd rect
			(at 0 -0.9652)
			(size 1.397 1.143)
			(layers "B.Cu" "B.Mask" "B.Paste")
			(net "P3V3_STBY")
		)
		(pad "2" smd rect
			(at 0 0.9652)
			(size 1.397 1.143)
			(layers "B.Cu" "B.Mask" "B.Paste")
			(net "GND")
		)
	)
	(footprint ""
		(layer "B.Cu")
		(at 55.348632 -122.25909)
		(property "Reference" "R339"
			(at 0 0 0)
			(layer "B.SilkS")
			(hide yes)
			(effects
				(font
					(size 1.27 1.27)
				)
				(justify mirror)
			)
		)
		(property "Value" "4K7R2F-GP"
			(at -0.064008 -3.993896 0)
			(unlocked yes)
			(layer "B.Fab")
			(hide yes)
			(effects
				(font
					(size 1.016 1.016)
					(thickness 0.1524)
				)
				(justify mirror)
			)
		)
		(property "Device Type" "R402H16"
			(at -0.064008 -5.517896 0)
			(unlocked yes)
			(layer "B.Fab")
			(hide yes)
			(effects
				(font
					(size 1.016 1.016)
					(thickness 0.1524)
				)
				(justify mirror)
			)
		)
		(duplicate_pad_numbers_are_jumpers no)
		(fp_line
			(start -0.508 -0.9398)
			(end 0.508 -0.9398)
			(stroke
				(width 0.1524)
				(type default)
			)
			(layer "B.SilkS")
		)
		(fp_line
			(start 0.508 -0.9398)
			(end 0.508 0.9398)
			(stroke
				(width 0.1524)
				(type default)
			)
			(layer "B.SilkS")
		)
		(fp_rect
			(start 0.508 0.9398)
			(end -0.508 -0.9398)
			(stroke
				(width 0)
				(type default)
			)
			(fill no)
			(layer "B.CrtYd")
		)
		(fp_rect
			(start 0.508 0.9398)
			(end -0.508 -0.9398)
			(stroke
				(width 0)
				(type default)
			)
			(fill no)
			(layer "B.Fab")
		)
		(pad "1" smd custom
			(at 0 -0.4445 180)
			(size 0.1397 0.1397)
			(layers "B.Cu" "B.Mask" "B.Paste")
			(net "P3V3_STBY")
			(options
				(clearance outline)
				(anchor circle)
			)
			(primitives
				(gr_poly
					(pts
						(arc
							(start -0.1778 0.2794)
							(mid -0.249642 0.249642)
							(end -0.2794 0.1778)
						)
						(arc
							(start -0.2794 -0.1778)
							(mid -0.249642 -0.249642)
							(end -0.1778 -0.2794)
						)
						(arc
							(start 0.1778 -0.2794)
							(mid 0.249642 -0.249642)
							(end 0.2794 -0.1778)
						)
						(arc
							(start 0.2794 0.1778)
							(mid 0.249642 0.249642)
							(end 0.1778 0.2794)
						)
					)
					(width 0)
					(fill yes)
				)
			)
		)
		(pad "2" smd custom
			(at 0 0.4445 180)
			(size 0.1397 0.1397)
			(layers "B.Cu" "B.Mask" "B.Paste")
			(net "TEMP_3_A1")
			(options
				(clearance outline)
				(anchor circle)
			)
			(primitives
				(gr_poly
					(pts
						(arc
							(start -0.1778 0.2794)
							(mid -0.249642 0.249642)
							(end -0.2794 0.1778)
						)
						(arc
							(start -0.2794 -0.1778)
							(mid -0.249642 -0.249642)
							(end -0.1778 -0.2794)
						)
						(arc
							(start 0.1778 -0.2794)
							(mid 0.249642 -0.249642)
							(end 0.2794 -0.1778)
						)
						(arc
							(start 0.2794 0.1778)
							(mid 0.249642 0.249642)
							(end 0.1778 0.2794)
						)
					)
					(width 0)
					(fill yes)
				)
			)
		)
	)
	(footprint ""
		(layer "B.Cu")
		(at 79.018638 -57.02681 180)
		(property "Reference" "C188"
			(at 0 0 0)
			(layer "B.SilkS")
			(hide yes)
			(effects
				(font
					(size 1.27 1.27)
				)
				(justify mirror)
			)
		)
		(property "Value" "SC10U6D3V5KX-4GP"
			(at 0.0762 -6.1214 180)
			(unlocked yes)
			(layer "B.Fab")
			(hide yes)
			(effects
				(font
					(size 1.016 1.016)
					(thickness 0.1524)
				)
				(justify mirror)
			)
		)
		(property "Device Type" "C805H58"
			(at 0.0762 -8.153146 180)
			(unlocked yes)
			(layer "B.Fab")
			(hide yes)
			(effects
				(font
					(size 1.016 1.016)
					(thickness 0.1524)
				)
				(justify mirror)
			)
		)
		(duplicate_pad_numbers_are_jumpers no)
		(fp_line
			(start -0.635254 0)
			(end 0.635 0)
			(stroke
				(width 0.508)
				(type default)
			)
			(layer "B.SilkS")
		)
		(fp_rect
			(start 0.9652 1.778254)
			(end -0.9652 -1.777746)
			(stroke
				(width 0)
				(type default)
			)
			(fill no)
			(layer "B.CrtYd")
		)
		(fp_poly
			(pts
				(xy 0.9652 -1.778) (xy -0.9652 -1.778) (xy -0.9652 1.778254) (xy 0.9652 1.778254)
			)
			(stroke
				(width 0)
				(type default)
			)
			(fill no)
			(layer "B.Fab")
		)
		(pad "1" smd rect
			(at 0 -0.9652)
			(size 1.397 1.143)
			(layers "B.Cu" "B.Mask" "B.Paste")
			(net "P3V3")
		)
		(pad "2" smd rect
			(at 0 0.9652)
			(size 1.397 1.143)
			(layers "B.Cu" "B.Mask" "B.Paste")
			(net "GND")
		)
	)
	(footprint ""
		(layer "B.Cu")
		(at 56.843168 -163.069524 -90)
		(property "Reference" "R413"
			(at 0 0 90)
			(layer "B.SilkS")
			(hide yes)
			(effects
				(font
					(size 1.27 1.27)
				)
				(justify mirror)
			)
		)
		(property "Value" "2K7R2F-GP"
			(at -0.064008 -3.993896 270)
			(unlocked yes)
			(layer "B.Fab")
			(hide yes)
			(effects
				(font
					(size 1.016 1.016)
					(thickness 0.1524)
				)
				(justify mirror)
			)
		)
		(property "Device Type" "R402H16"
			(at -0.064008 -5.517896 270)
			(unlocked yes)
			(layer "B.Fab")
			(hide yes)
			(effects
				(font
					(size 1.016 1.016)
					(thickness 0.1524)
				)
				(justify mirror)
			)
		)
		(duplicate_pad_numbers_are_jumpers no)
		(fp_line
			(start -0.508 -0.9398)
			(end 0.508 -0.9398)
			(stroke
				(width 0.1524)
				(type default)
			)
			(layer "B.SilkS")
		)
		(fp_line
			(start 0.508 -0.9398)
			(end 0.508 0.9398)
			(stroke
				(width 0.1524)
				(type default)
			)
			(layer "B.SilkS")
		)
		(fp_rect
			(start 0.508 0.9398)
			(end -0.508 -0.9398)
			(stroke
				(width 0)
				(type default)
			)
			(fill no)
			(layer "B.CrtYd")
		)
		(fp_rect
			(start 0.508 0.9398)
			(end -0.508 -0.9398)
			(stroke
				(width 0)
				(type default)
			)
			(fill no)
			(layer "B.Fab")
		)
		(pad "1" smd custom
			(at 0 -0.4445 90)
			(size 0.1397 0.1397)
			(layers "B.Cu" "B.Mask" "B.Paste")
			(net "P5V_STBY")
			(options
				(clearance outline)
				(anchor circle)
			)
			(primitives
				(gr_poly
					(pts
						(arc
							(start -0.1778 0.2794)
							(mid -0.249642 0.249642)
							(end -0.2794 0.1778)
						)
						(arc
							(start -0.2794 -0.1778)
							(mid -0.249642 -0.249642)
							(end -0.1778 -0.2794)
						)
						(arc
							(start 0.1778 -0.2794)
							(mid 0.249642 -0.249642)
							(end 0.2794 -0.1778)
						)
						(arc
							(start 0.2794 0.1778)
							(mid 0.249642 0.249642)
							(end 0.1778 0.2794)
						)
					)
					(width 0)
					(fill yes)
				)
			)
		)
		(pad "2" smd custom
			(at 0 0.4445 90)
			(size 0.1397 0.1397)
			(layers "B.Cu" "B.Mask" "B.Paste")
			(net "ADC_P5V_STBY")
			(options
				(clearance outline)
				(anchor circle)
			)
			(primitives
				(gr_poly
					(pts
						(arc
							(start -0.1778 0.2794)
							(mid -0.249642 0.249642)
							(end -0.2794 0.1778)
						)
						(arc
							(start -0.2794 -0.1778)
							(mid -0.249642 -0.249642)
							(end -0.1778 -0.2794)
						)
						(arc
							(start 0.1778 -0.2794)
							(mid 0.249642 -0.249642)
							(end 0.2794 -0.1778)
						)
						(arc
							(start 0.2794 0.1778)
							(mid 0.249642 0.249642)
							(end 0.1778 0.2794)
						)
					)
					(width 0)
					(fill yes)
				)
			)
		)
	)
	(footprint ""
		(layer "B.Cu")
		(at 224.989644 -78.16723 90)
		(property "Reference" "C643"
			(at 0 0 90)
			(layer "B.SilkS")
			(hide yes)
			(effects
				(font
					(size 1.27 1.27)
				)
				(justify mirror)
			)
		)
		(property "Value" "SC10U6D3V5KX-4GP"
			(at 0.0762 -6.1214 90)
			(unlocked yes)
			(layer "B.Fab")
			(hide yes)
			(effects
				(font
					(size 1.016 1.016)
					(thickness 0.1524)
				)
				(justify mirror)
			)
		)
		(property "Device Type" "C805H58"
			(at 0.0762 -8.1534 90)
			(unlocked yes)
			(layer "B.Fab")
			(hide yes)
			(effects
				(font
					(size 1.016 1.016)
					(thickness 0.1524)
				)
				(justify mirror)
			)
		)
		(duplicate_pad_numbers_are_jumpers no)
		(fp_line
			(start -0.635 0)
			(end 0.635 0)
			(stroke
				(width 0.508)
				(type default)
			)
			(layer "B.SilkS")
		)
		(fp_rect
			(start 0.9652 1.778)
			(end -0.9652 -1.778)
			(stroke
				(width 0)
				(type default)
			)
			(fill no)
			(layer "B.CrtYd")
		)
		(fp_poly
			(pts
				(xy 0.9652 -1.778) (xy -0.9652 -1.778) (xy -0.9652 1.778) (xy 0.9652 1.778)
			)
			(stroke
				(width 0)
				(type default)
			)
			(fill no)
			(layer "B.Fab")
		)
		(pad "1" smd rect
			(at 0 -0.9652 270)
			(size 1.397 1.143)
			(layers "B.Cu" "B.Mask" "B.Paste")
			(net "P3V3_M2")
		)
		(pad "2" smd rect
			(at 0 0.9652 270)
			(size 1.397 1.143)
			(layers "B.Cu" "B.Mask" "B.Paste")
			(net "GND")
		)
	)
	(footprint ""
		(layer "B.Cu")
		(at 42.351198 -127.978916)
		(property "Reference" "R325"
			(at 0 0 0)
			(layer "B.SilkS")
			(hide yes)
			(effects
				(font
					(size 1.27 1.27)
				)
				(justify mirror)
			)
		)
		(property "Value" "0R2J-2-GP"
			(at -0.064008 -3.993896 0)
			(unlocked yes)
			(layer "B.Fab")
			(hide yes)
			(effects
				(font
					(size 1.016 1.016)
					(thickness 0.1524)
				)
				(justify mirror)
			)
		)
		(property "Device Type" "R402H16"
			(at -0.064008 -5.517896 0)
			(unlocked yes)
			(layer "B.Fab")
			(hide yes)
			(effects
				(font
					(size 1.016 1.016)
					(thickness 0.1524)
				)
				(justify mirror)
			)
		)
		(duplicate_pad_numbers_are_jumpers no)
		(fp_line
			(start -0.508 -0.9398)
			(end 0.508 -0.9398)
			(stroke
				(width 0.1524)
				(type default)
			)
			(layer "B.SilkS")
		)
		(fp_line
			(start 0.508 -0.9398)
			(end 0.508 0.9398)
			(stroke
				(width 0.1524)
				(type default)
			)
			(layer "B.SilkS")
		)
		(fp_rect
			(start 0.508 0.9398)
			(end -0.508 -0.9398)
			(stroke
				(width 0)
				(type default)
			)
			(fill no)
			(layer "B.CrtYd")
		)
		(fp_rect
			(start 0.508 0.9398)
			(end -0.508 -0.9398)
			(stroke
				(width 0)
				(type default)
			)
			(fill no)
			(layer "B.Fab")
		)
		(pad "1" smd custom
			(at 0 -0.4445 180)
			(size 0.1397 0.1397)
			(layers "B.Cu" "B.Mask" "B.Paste")
			(net "BMC0_SRST_N")
			(options
				(clearance outline)
				(anchor circle)
			)
			(primitives
				(gr_poly
					(pts
						(arc
							(start -0.1778 0.2794)
							(mid -0.249642 0.249642)
							(end -0.2794 0.1778)
						)
						(arc
							(start -0.2794 -0.1778)
							(mid -0.249642 -0.249642)
							(end -0.1778 -0.2794)
						)
						(arc
							(start 0.1778 -0.2794)
							(mid 0.249642 -0.249642)
							(end 0.2794 -0.1778)
						)
						(arc
							(start 0.2794 0.1778)
							(mid 0.249642 0.249642)
							(end 0.1778 0.2794)
						)
					)
					(width 0)
					(fill yes)
				)
			)
		)
		(pad "2" smd custom
			(at 0 0.4445 180)
			(size 0.1397 0.1397)
			(layers "B.Cu" "B.Mask" "B.Paste")
			(net "FM_BMC_RESET_N")
			(options
				(clearance outline)
				(anchor circle)
			)
			(primitives
				(gr_poly
					(pts
						(arc
							(start -0.1778 0.2794)
							(mid -0.249642 0.249642)
							(end -0.2794 0.1778)
						)
						(arc
							(start -0.2794 -0.1778)
							(mid -0.249642 -0.249642)
							(end -0.1778 -0.2794)
						)
						(arc
							(start 0.1778 -0.2794)
							(mid 0.249642 -0.249642)
							(end 0.2794 -0.1778)
						)
						(arc
							(start 0.2794 0.1778)
							(mid 0.249642 0.249642)
							(end 0.1778 0.2794)
						)
					)
					(width 0)
					(fill yes)
				)
			)
		)
	)
	(footprint ""
		(layer "B.Cu")
		(at 11.345672 -144.098264 -90)
		(property "Reference" "C65"
			(at 0 0 90)
			(layer "B.SilkS")
			(hide yes)
			(effects
				(font
					(size 1.27 1.27)
				)
				(justify mirror)
			)
		)
		(property "Value" "SC1U16V3KX-5GP"
			(at 0 -2.8194 270)
			(unlocked yes)
			(layer "B.Fab")
			(hide yes)
			(effects
				(font
					(size 1.016 1.016)
					(thickness 0.1524)
				)
				(justify mirror)
			)
		)
		(property "Device Type" "C603H36"
			(at 0 -4.3434 270)
			(unlocked yes)
			(layer "B.Fab")
			(hide yes)
			(effects
				(font
					(size 1.016 1.016)
					(thickness 0.1524)
				)
				(justify mirror)
			)
		)
		(duplicate_pad_numbers_are_jumpers no)
		(fp_line
			(start -0.508 0)
			(end 0.508 0)
			(stroke
				(width 0.2032)
				(type default)
			)
			(layer "B.SilkS")
		)
		(fp_rect
			(start 0.5842 1.3335)
			(end -0.5842 -1.3335)
			(stroke
				(width 0)
				(type default)
			)
			(fill no)
			(layer "B.CrtYd")
		)
		(fp_rect
			(start 0.5842 1.3335)
			(end -0.5842 -1.3335)
			(stroke
				(width 0)
				(type default)
			)
			(fill no)
			(layer "B.Fab")
		)
		(pad "1" smd custom
			(at 0 -0.762 90)
			(size 0.2159 0.2159)
			(layers "B.Cu" "B.Mask" "B.Paste")
			(net "P2V5_STBY")
			(options
				(clearance outline)
				(anchor circle)
			)
			(primitives
				(gr_poly
					(pts
						(arc
							(start -0.3302 0.4318)
							(mid -0.402042 0.402042)
							(end -0.4318 0.3302)
						)
						(arc
							(start -0.4318 -0.3302)
							(mid -0.402042 -0.402042)
							(end -0.3302 -0.4318)
						)
						(arc
							(start 0.3302 -0.4318)
							(mid 0.402042 -0.402042)
							(end 0.4318 -0.3302)
						)
						(arc
							(start 0.4318 0.3302)
							(mid 0.402042 0.402042)
							(end 0.3302 0.4318)
						)
					)
					(width 0)
					(fill yes)
				)
			)
		)
		(pad "2" smd custom
			(at 0 0.762 90)
			(size 0.2159 0.2159)
			(layers "B.Cu" "B.Mask" "B.Paste")
			(net "GND")
			(options
				(clearance outline)
				(anchor circle)
			)
			(primitives
				(gr_poly
					(pts
						(arc
							(start -0.3302 0.4318)
							(mid -0.402042 0.402042)
							(end -0.4318 0.3302)
						)
						(arc
							(start -0.4318 -0.3302)
							(mid -0.402042 -0.402042)
							(end -0.3302 -0.4318)
						)
						(arc
							(start 0.3302 -0.4318)
							(mid 0.402042 -0.402042)
							(end 0.4318 -0.3302)
						)
						(arc
							(start 0.4318 0.3302)
							(mid 0.402042 0.402042)
							(end 0.3302 0.4318)
						)
					)
					(width 0)
					(fill yes)
				)
			)
		)
	)
	(footprint ""
		(layer "B.Cu")
		(at 32.5374 -162.306 90)
		(property "Reference" "R703"
			(at 0 0 90)
			(layer "B.SilkS")
			(hide yes)
			(effects
				(font
					(size 1.27 1.27)
				)
				(justify mirror)
			)
		)
		(property "Value" "4K7R2F-GP"
			(at -0.064008 -3.993896 90)
			(unlocked yes)
			(layer "B.Fab")
			(hide yes)
			(effects
				(font
					(size 1.016 1.016)
					(thickness 0.1524)
				)
				(justify mirror)
			)
		)
		(property "Device Type" "R402H16"
			(at -0.064008 -5.517896 90)
			(unlocked yes)
			(layer "B.Fab")
			(hide yes)
			(effects
				(font
					(size 1.016 1.016)
					(thickness 0.1524)
				)
				(justify mirror)
			)
		)
		(duplicate_pad_numbers_are_jumpers no)
		(fp_line
			(start 0.508 -0.9398)
			(end 0.508 0.9398)
			(stroke
				(width 0.1524)
				(type default)
			)
			(layer "B.SilkS")
		)
		(fp_line
			(start -0.508 -0.9398)
			(end 0.508 -0.9398)
			(stroke
				(width 0.1524)
				(type default)
			)
			(layer "B.SilkS")
		)
		(fp_rect
			(start 0.508 0.9398)
			(end -0.508 -0.9398)
			(stroke
				(width 0)
				(type default)
			)
			(fill no)
			(layer "B.CrtYd")
		)
		(fp_rect
			(start 0.508 0.9398)
			(end -0.508 -0.9398)
			(stroke
				(width 0)
				(type default)
			)
			(fill no)
			(layer "B.Fab")
		)
		(pad "1" smd custom
			(at 0 -0.4445 270)
			(size 0.1397 0.1397)
			(layers "B.Cu" "B.Mask" "B.Paste")
			(net "GND")
			(options
				(clearance outline)
				(anchor circle)
			)
			(primitives
				(gr_poly
					(pts
						(arc
							(start -0.1778 0.2794)
							(mid -0.249642 0.249642)
							(end -0.2794 0.1778)
						)
						(arc
							(start -0.2794 -0.1778)
							(mid -0.249642 -0.249642)
							(end -0.1778 -0.2794)
						)
						(arc
							(start 0.1778 -0.2794)
							(mid 0.249642 -0.249642)
							(end 0.2794 -0.1778)
						)
						(arc
							(start 0.2794 0.1778)
							(mid 0.249642 0.249642)
							(end 0.1778 0.2794)
						)
					)
					(width 0)
					(fill yes)
				)
			)
		)
		(pad "2" smd custom
			(at 0 0.4445 270)
			(size 0.1397 0.1397)
			(layers "B.Cu" "B.Mask" "B.Paste")
			(net "IOM_TYPE1")
			(options
				(clearance outline)
				(anchor circle)
			)
			(primitives
				(gr_poly
					(pts
						(arc
							(start -0.1778 0.2794)
							(mid -0.249642 0.249642)
							(end -0.2794 0.1778)
						)
						(arc
							(start -0.2794 -0.1778)
							(mid -0.249642 -0.249642)
							(end -0.1778 -0.2794)
						)
						(arc
							(start 0.1778 -0.2794)
							(mid 0.249642 -0.249642)
							(end 0.2794 -0.1778)
						)
						(arc
							(start 0.2794 0.1778)
							(mid 0.249642 0.249642)
							(end 0.1778 0.2794)
						)
					)
					(width 0)
					(fill yes)
				)
			)
		)
	)
	(footprint ""
		(layer "B.Cu")
		(at 60.8838 -141.2494 -90)
		(property "Reference" "R176"
			(at 0 0 90)
			(layer "B.SilkS")
			(hide yes)
			(effects
				(font
					(size 1.27 1.27)
				)
				(justify mirror)
			)
		)
		(property "Value" "0R2J-2-GP"
			(at -0.064008 -3.993896 270)
			(unlocked yes)
			(layer "B.Fab")
			(hide yes)
			(effects
				(font
					(size 1.016 1.016)
					(thickness 0.1524)
				)
				(justify mirror)
			)
		)
		(property "Device Type" "R402H16"
			(at -0.064008 -5.517896 270)
			(unlocked yes)
			(layer "B.Fab")
			(hide yes)
			(effects
				(font
					(size 1.016 1.016)
					(thickness 0.1524)
				)
				(justify mirror)
			)
		)
		(duplicate_pad_numbers_are_jumpers no)
		(fp_line
			(start -0.508 -0.9398)
			(end 0.508 -0.9398)
			(stroke
				(width 0.1524)
				(type default)
			)
			(layer "B.SilkS")
		)
		(fp_line
			(start 0.508 -0.9398)
			(end 0.508 0.9398)
			(stroke
				(width 0.1524)
				(type default)
			)
			(layer "B.SilkS")
		)
		(fp_rect
			(start 0.508 0.9398)
			(end -0.508 -0.9398)
			(stroke
				(width 0)
				(type default)
			)
			(fill no)
			(layer "B.CrtYd")
		)
		(fp_rect
			(start 0.508 0.9398)
			(end -0.508 -0.9398)
			(stroke
				(width 0)
				(type default)
			)
			(fill no)
			(layer "B.Fab")
		)
		(pad "1" smd custom
			(at 0 -0.4445 90)
			(size 0.1397 0.1397)
			(layers "B.Cu" "B.Mask" "B.Paste")
			(net "I2C_M2_2_SDA")
			(options
				(clearance outline)
				(anchor circle)
			)
			(primitives
				(gr_poly
					(pts
						(arc
							(start -0.1778 0.2794)
							(mid -0.249642 0.249642)
							(end -0.2794 0.1778)
						)
						(arc
							(start -0.2794 -0.1778)
							(mid -0.249642 -0.249642)
							(end -0.1778 -0.2794)
						)
						(arc
							(start 0.1778 -0.2794)
							(mid 0.249642 -0.249642)
							(end 0.2794 -0.1778)
						)
						(arc
							(start 0.2794 0.1778)
							(mid 0.249642 0.249642)
							(end 0.1778 0.2794)
						)
					)
					(width 0)
					(fill yes)
				)
			)
		)
		(pad "2" smd custom
			(at 0 0.4445 90)
			(size 0.1397 0.1397)
			(layers "B.Cu" "B.Mask" "B.Paste")
			(net "BMC_SMB9_DAT")
			(options
				(clearance outline)
				(anchor circle)
			)
			(primitives
				(gr_poly
					(pts
						(arc
							(start -0.1778 0.2794)
							(mid -0.249642 0.249642)
							(end -0.2794 0.1778)
						)
						(arc
							(start -0.2794 -0.1778)
							(mid -0.249642 -0.249642)
							(end -0.1778 -0.2794)
						)
						(arc
							(start 0.1778 -0.2794)
							(mid 0.249642 -0.249642)
							(end 0.2794 -0.1778)
						)
						(arc
							(start 0.2794 0.1778)
							(mid 0.249642 0.249642)
							(end 0.1778 0.2794)
						)
					)
					(width 0)
					(fill yes)
				)
			)
		)
	)
	(footprint ""
		(layer "B.Cu")
		(at 55.372 -119.6594 90)
		(property "Reference" "R337"
			(at 0 0 90)
			(layer "B.SilkS")
			(hide yes)
			(effects
				(font
					(size 1.27 1.27)
				)
				(justify mirror)
			)
		)
		(property "Value" "4K7R2F-GP"
			(at -0.064008 -3.993896 90)
			(unlocked yes)
			(layer "B.Fab")
			(hide yes)
			(effects
				(font
					(size 1.016 1.016)
					(thickness 0.1524)
				)
				(justify mirror)
			)
		)
		(property "Device Type" "R402H16"
			(at -0.064008 -5.517896 90)
			(unlocked yes)
			(layer "B.Fab")
			(hide yes)
			(effects
				(font
					(size 1.016 1.016)
					(thickness 0.1524)
				)
				(justify mirror)
			)
		)
		(duplicate_pad_numbers_are_jumpers no)
		(fp_line
			(start 0.508 -0.9398)
			(end 0.508 0.9398)
			(stroke
				(width 0.1524)
				(type default)
			)
			(layer "B.SilkS")
		)
		(fp_line
			(start -0.508 -0.9398)
			(end 0.508 -0.9398)
			(stroke
				(width 0.1524)
				(type default)
			)
			(layer "B.SilkS")
		)
		(fp_rect
			(start 0.508 0.9398)
			(end -0.508 -0.9398)
			(stroke
				(width 0)
				(type default)
			)
			(fill no)
			(layer "B.CrtYd")
		)
		(fp_rect
			(start 0.508 0.9398)
			(end -0.508 -0.9398)
			(stroke
				(width 0)
				(type default)
			)
			(fill no)
			(layer "B.Fab")
		)
		(pad "1" smd custom
			(at 0 -0.4445 270)
			(size 0.1397 0.1397)
			(layers "B.Cu" "B.Mask" "B.Paste")
			(net "TEMP_3_A0")
			(options
				(clearance outline)
				(anchor circle)
			)
			(primitives
				(gr_poly
					(pts
						(arc
							(start -0.1778 0.2794)
							(mid -0.249642 0.249642)
							(end -0.2794 0.1778)
						)
						(arc
							(start -0.2794 -0.1778)
							(mid -0.249642 -0.249642)
							(end -0.1778 -0.2794)
						)
						(arc
							(start 0.1778 -0.2794)
							(mid 0.249642 -0.249642)
							(end 0.2794 -0.1778)
						)
						(arc
							(start 0.2794 0.1778)
							(mid 0.249642 0.249642)
							(end 0.1778 0.2794)
						)
					)
					(width 0)
					(fill yes)
				)
			)
		)
		(pad "2" smd custom
			(at 0 0.4445 270)
			(size 0.1397 0.1397)
			(layers "B.Cu" "B.Mask" "B.Paste")
			(net "GND")
			(options
				(clearance outline)
				(anchor circle)
			)
			(primitives
				(gr_poly
					(pts
						(arc
							(start -0.1778 0.2794)
							(mid -0.249642 0.249642)
							(end -0.2794 0.1778)
						)
						(arc
							(start -0.2794 -0.1778)
							(mid -0.249642 -0.249642)
							(end -0.1778 -0.2794)
						)
						(arc
							(start 0.1778 -0.2794)
							(mid 0.249642 -0.249642)
							(end 0.2794 -0.1778)
						)
						(arc
							(start 0.2794 0.1778)
							(mid 0.249642 0.249642)
							(end 0.1778 0.2794)
						)
					)
					(width 0)
					(fill yes)
				)
			)
		)
	)
	(footprint ""
		(layer "B.Cu")
		(at 55.8038 -143.0274)
		(property "Reference" "TP54"
			(at 0 0 0)
			(layer "B.SilkS")
			(hide yes)
			(effects
				(font
					(size 1.27 1.27)
				)
				(justify mirror)
			)
		)
		(property "Value" "TPAD28-2-GP"
			(at 0.0127 -1.6637 0)
			(unlocked yes)
			(layer "B.Fab")
			(hide yes)
			(effects
				(font
					(size 1.016 1.016)
					(thickness 0.1524)
				)
				(justify mirror)
			)
		)
		(property "Device Type" "TPAD28"
			(at 0.0127 -3.1877 0)
			(unlocked yes)
			(layer "B.Fab")
			(hide yes)
			(effects
				(font
					(size 1.016 1.016)
					(thickness 0.1524)
				)
				(justify mirror)
			)
		)
		(duplicate_pad_numbers_are_jumpers no)
		(fp_poly
			(pts
				(arc
					(start 0.3556 0)
					(mid -0.3556 0)
					(end 0.3556 0)
				)
			)
			(stroke
				(width 0)
				(type default)
			)
			(fill no)
			(layer "B.CrtYd")
		)
		(fp_poly
			(pts
				(arc
					(start 0.6096 0)
					(mid -0.6096 0)
					(end 0.6096 0)
				)
			)
			(stroke
				(width 0)
				(type default)
			)
			(fill no)
			(layer "B.Fab")
		)
		(pad "1" smd circle
			(at 0 0 180)
			(size 0.7112 0.7112)
			(layers "B.Cu" "B.Mask" "B.Paste")
			(net "TP_BMC_GPIOA6")
		)
	)
	(footprint ""
		(layer "B.Cu")
		(at 51.40452 -144.26438)
		(property "Reference" "TP78"
			(at 0 0 0)
			(layer "B.SilkS")
			(hide yes)
			(effects
				(font
					(size 1.27 1.27)
				)
				(justify mirror)
			)
		)
		(property "Value" "TPAD28-2-GP"
			(at 0.0127 -1.6637 0)
			(unlocked yes)
			(layer "B.Fab")
			(hide yes)
			(effects
				(font
					(size 1.016 1.016)
					(thickness 0.1524)
				)
				(justify mirror)
			)
		)
		(property "Device Type" "TPAD28"
			(at 0.0127 -3.1877 0)
			(unlocked yes)
			(layer "B.Fab")
			(hide yes)
			(effects
				(font
					(size 1.016 1.016)
					(thickness 0.1524)
				)
				(justify mirror)
			)
		)
		(duplicate_pad_numbers_are_jumpers no)
		(fp_poly
			(pts
				(arc
					(start 0.3556 0)
					(mid -0.3556 0)
					(end 0.3556 0)
				)
			)
			(stroke
				(width 0)
				(type default)
			)
			(fill no)
			(layer "B.CrtYd")
		)
		(fp_poly
			(pts
				(arc
					(start 0.6096 0)
					(mid -0.6096 0)
					(end 0.6096 0)
				)
			)
			(stroke
				(width 0)
				(type default)
			)
			(fill no)
			(layer "B.Fab")
		)
		(pad "1" smd circle
			(at 0 0 180)
			(size 0.7112 0.7112)
			(layers "B.Cu" "B.Mask" "B.Paste")
			(net "JTAG_BMC_TRST_N")
		)
	)
	(footprint ""
		(layer "B.Cu")
		(at 210.0072 -107.343448 -90)
		(property "Reference" "R814"
			(at 0 0 90)
			(layer "B.SilkS")
			(hide yes)
			(effects
				(font
					(size 1.27 1.27)
				)
				(justify mirror)
			)
		)
		(property "Value" "1KR2F-3-GP"
			(at -0.064008 -3.993896 270)
			(unlocked yes)
			(layer "B.Fab")
			(hide yes)
			(effects
				(font
					(size 1.016 1.016)
					(thickness 0.1524)
				)
				(justify mirror)
			)
		)
		(property "Device Type" "R402H16"
			(at -0.064008 -5.517896 270)
			(unlocked yes)
			(layer "B.Fab")
			(hide yes)
			(effects
				(font
					(size 1.016 1.016)
					(thickness 0.1524)
				)
				(justify mirror)
			)
		)
		(duplicate_pad_numbers_are_jumpers no)
		(fp_line
			(start -0.508 -0.9398)
			(end 0.508 -0.9398)
			(stroke
				(width 0.1524)
				(type default)
			)
			(layer "B.SilkS")
		)
		(fp_line
			(start 0.508 -0.9398)
			(end 0.508 0.9398)
			(stroke
				(width 0.1524)
				(type default)
			)
			(layer "B.SilkS")
		)
		(fp_rect
			(start 0.508 0.9398)
			(end -0.508 -0.9398)
			(stroke
				(width 0)
				(type default)
			)
			(fill no)
			(layer "B.CrtYd")
		)
		(fp_rect
			(start 0.508 0.9398)
			(end -0.508 -0.9398)
			(stroke
				(width 0)
				(type default)
			)
			(fill no)
			(layer "B.Fab")
		)
		(pad "1" smd custom
			(at 0 -0.4445 90)
			(size 0.1397 0.1397)
			(layers "B.Cu" "B.Mask" "B.Paste")
			(net "P1V8_STBY")
			(options
				(clearance outline)
				(anchor circle)
			)
			(primitives
				(gr_poly
					(pts
						(arc
							(start -0.1778 0.2794)
							(mid -0.249642 0.249642)
							(end -0.2794 0.1778)
						)
						(arc
							(start -0.2794 -0.1778)
							(mid -0.249642 -0.249642)
							(end -0.1778 -0.2794)
						)
						(arc
							(start 0.1778 -0.2794)
							(mid 0.249642 -0.249642)
							(end 0.2794 -0.1778)
						)
						(arc
							(start 0.2794 0.1778)
							(mid 0.249642 0.249642)
							(end 0.1778 0.2794)
						)
					)
					(width 0)
					(fill yes)
				)
			)
		)
		(pad "2" smd custom
			(at 0 0.4445 90)
			(size 0.1397 0.1397)
			(layers "B.Cu" "B.Mask" "B.Paste")
			(net "I2C_M2_1_1V8_SDA")
			(options
				(clearance outline)
				(anchor circle)
			)
			(primitives
				(gr_poly
					(pts
						(arc
							(start -0.1778 0.2794)
							(mid -0.249642 0.249642)
							(end -0.2794 0.1778)
						)
						(arc
							(start -0.2794 -0.1778)
							(mid -0.249642 -0.249642)
							(end -0.1778 -0.2794)
						)
						(arc
							(start 0.1778 -0.2794)
							(mid 0.249642 -0.249642)
							(end 0.2794 -0.1778)
						)
						(arc
							(start 0.2794 0.1778)
							(mid 0.249642 0.249642)
							(end 0.1778 0.2794)
						)
					)
					(width 0)
					(fill yes)
				)
			)
		)
	)
	(footprint ""
		(layer "B.Cu")
		(at 168.617138 -9.171178)
		(property "Reference" "C215"
			(at 0 0 0)
			(layer "B.SilkS")
			(hide yes)
			(effects
				(font
					(size 1.27 1.27)
				)
				(justify mirror)
			)
		)
		(property "Value" "SC10U6D3V5KX-4GP"
			(at 0.0762 -6.1214 0)
			(unlocked yes)
			(layer "B.Fab")
			(hide yes)
			(effects
				(font
					(size 1.016 1.016)
					(thickness 0.1524)
				)
				(justify mirror)
			)
		)
		(property "Device Type" "C805H58"
			(at 0.0762 -8.1534 0)
			(unlocked yes)
			(layer "B.Fab")
			(hide yes)
			(effects
				(font
					(size 1.016 1.016)
					(thickness 0.1524)
				)
				(justify mirror)
			)
		)
		(duplicate_pad_numbers_are_jumpers no)
		(fp_line
			(start -0.635 0)
			(end 0.635 0)
			(stroke
				(width 0.508)
				(type default)
			)
			(layer "B.SilkS")
		)
		(fp_rect
			(start 0.9652 1.778)
			(end -0.9652 -1.778)
			(stroke
				(width 0)
				(type default)
			)
			(fill no)
			(layer "B.CrtYd")
		)
		(fp_poly
			(pts
				(xy 0.9652 -1.778) (xy -0.9652 -1.778) (xy -0.9652 1.778) (xy 0.9652 1.778)
			)
			(stroke
				(width 0)
				(type default)
			)
			(fill no)
			(layer "B.Fab")
		)
		(pad "1" smd rect
			(at 0 -0.9652 180)
			(size 1.397 1.143)
			(layers "B.Cu" "B.Mask" "B.Paste")
			(net "P1V8_STBY")
		)
		(pad "2" smd rect
			(at 0 0.9652 180)
			(size 1.397 1.143)
			(layers "B.Cu" "B.Mask" "B.Paste")
			(net "GND")
		)
	)
	(footprint ""
		(layer "B.Cu")
		(at 58.3438 -144.018 -90)
		(property "Reference" "R358"
			(at 0 0 90)
			(layer "B.SilkS")
			(hide yes)
			(effects
				(font
					(size 1.27 1.27)
				)
				(justify mirror)
			)
		)
		(property "Value" "10KR2F-2-GP"
			(at -0.064008 -3.993896 270)
			(unlocked yes)
			(layer "B.Fab")
			(hide yes)
			(effects
				(font
					(size 1.016 1.016)
					(thickness 0.1524)
				)
				(justify mirror)
			)
		)
		(property "Device Type" "R402H16"
			(at -0.064008 -5.517896 270)
			(unlocked yes)
			(layer "B.Fab")
			(hide yes)
			(effects
				(font
					(size 1.016 1.016)
					(thickness 0.1524)
				)
				(justify mirror)
			)
		)
		(duplicate_pad_numbers_are_jumpers no)
		(fp_line
			(start -0.508 -0.9398)
			(end 0.508 -0.9398)
			(stroke
				(width 0.1524)
				(type default)
			)
			(layer "B.SilkS")
		)
		(fp_line
			(start 0.508 -0.9398)
			(end 0.508 0.9398)
			(stroke
				(width 0.1524)
				(type default)
			)
			(layer "B.SilkS")
		)
		(fp_rect
			(start 0.508 0.9398)
			(end -0.508 -0.9398)
			(stroke
				(width 0)
				(type default)
			)
			(fill no)
			(layer "B.CrtYd")
		)
		(fp_rect
			(start 0.508 0.9398)
			(end -0.508 -0.9398)
			(stroke
				(width 0)
				(type default)
			)
			(fill no)
			(layer "B.Fab")
		)
		(pad "1" smd custom
			(at 0 -0.4445 90)
			(size 0.1397 0.1397)
			(layers "B.Cu" "B.Mask" "B.Paste")
			(net "P3V3_STBY")
			(options
				(clearance outline)
				(anchor circle)
			)
			(primitives
				(gr_poly
					(pts
						(arc
							(start -0.1778 0.2794)
							(mid -0.249642 0.249642)
							(end -0.2794 0.1778)
						)
						(arc
							(start -0.2794 -0.1778)
							(mid -0.249642 -0.249642)
							(end -0.1778 -0.2794)
						)
						(arc
							(start 0.1778 -0.2794)
							(mid 0.249642 -0.249642)
							(end 0.2794 -0.1778)
						)
						(arc
							(start 0.2794 0.1778)
							(mid 0.249642 0.249642)
							(end 0.1778 0.2794)
						)
					)
					(width 0)
					(fill yes)
				)
			)
		)
		(pad "2" smd custom
			(at 0 0.4445 90)
			(size 0.1397 0.1397)
			(layers "B.Cu" "B.Mask" "B.Paste")
			(net "JTAG_BMC_TDI")
			(options
				(clearance outline)
				(anchor circle)
			)
			(primitives
				(gr_poly
					(pts
						(arc
							(start -0.1778 0.2794)
							(mid -0.249642 0.249642)
							(end -0.2794 0.1778)
						)
						(arc
							(start -0.2794 -0.1778)
							(mid -0.249642 -0.249642)
							(end -0.1778 -0.2794)
						)
						(arc
							(start 0.1778 -0.2794)
							(mid 0.249642 -0.249642)
							(end 0.2794 -0.1778)
						)
						(arc
							(start 0.2794 0.1778)
							(mid 0.249642 0.249642)
							(end 0.1778 0.2794)
						)
					)
					(width 0)
					(fill yes)
				)
			)
		)
	)
	(footprint ""
		(layer "B.Cu")
		(at 88.6968 -161.2646 180)
		(property "Reference" "C15"
			(at 0 0 0)
			(layer "B.SilkS")
			(hide yes)
			(effects
				(font
					(size 1.27 1.27)
				)
				(justify mirror)
			)
		)
		(property "Value" "SC1U16V3KX-5GP"
			(at 0 -2.8194 180)
			(unlocked yes)
			(layer "B.Fab")
			(hide yes)
			(effects
				(font
					(size 1.016 1.016)
					(thickness 0.1524)
				)
				(justify mirror)
			)
		)
		(property "Device Type" "C603H36"
			(at 0 -4.3434 180)
			(unlocked yes)
			(layer "B.Fab")
			(hide yes)
			(effects
				(font
					(size 1.016 1.016)
					(thickness 0.1524)
				)
				(justify mirror)
			)
		)
		(duplicate_pad_numbers_are_jumpers no)
		(fp_line
			(start -0.508 0)
			(end 0.508 0)
			(stroke
				(width 0.2032)
				(type default)
			)
			(layer "B.SilkS")
		)
		(fp_rect
			(start 0.5842 1.3335)
			(end -0.5842 -1.3335)
			(stroke
				(width 0)
				(type default)
			)
			(fill no)
			(layer "B.CrtYd")
		)
		(fp_rect
			(start 0.5842 1.3335)
			(end -0.5842 -1.3335)
			(stroke
				(width 0)
				(type default)
			)
			(fill no)
			(layer "B.Fab")
		)
		(pad "1" smd custom
			(at 0 -0.762)
			(size 0.2159 0.2159)
			(layers "B.Cu" "B.Mask" "B.Paste")
			(net "P3V3_STBY")
			(options
				(clearance outline)
				(anchor circle)
			)
			(primitives
				(gr_poly
					(pts
						(arc
							(start -0.3302 0.4318)
							(mid -0.402042 0.402042)
							(end -0.4318 0.3302)
						)
						(arc
							(start -0.4318 -0.3302)
							(mid -0.402042 -0.402042)
							(end -0.3302 -0.4318)
						)
						(arc
							(start 0.3302 -0.4318)
							(mid 0.402042 -0.402042)
							(end 0.4318 -0.3302)
						)
						(arc
							(start 0.4318 0.3302)
							(mid 0.402042 0.402042)
							(end 0.3302 0.4318)
						)
					)
					(width 0)
					(fill yes)
				)
			)
		)
		(pad "2" smd custom
			(at 0 0.762)
			(size 0.2159 0.2159)
			(layers "B.Cu" "B.Mask" "B.Paste")
			(net "GND")
			(options
				(clearance outline)
				(anchor circle)
			)
			(primitives
				(gr_poly
					(pts
						(arc
							(start -0.3302 0.4318)
							(mid -0.402042 0.402042)
							(end -0.4318 0.3302)
						)
						(arc
							(start -0.4318 -0.3302)
							(mid -0.402042 -0.402042)
							(end -0.3302 -0.4318)
						)
						(arc
							(start 0.3302 -0.4318)
							(mid 0.402042 -0.402042)
							(end 0.4318 -0.3302)
						)
						(arc
							(start 0.4318 0.3302)
							(mid 0.402042 0.402042)
							(end 0.3302 0.4318)
						)
					)
					(width 0)
					(fill yes)
				)
			)
		)
	)
	(footprint ""
		(layer "B.Cu")
		(at 81.1784 -130.2766 -90)
		(property "Reference" "U103"
			(at 0 0 90)
			(layer "B.SilkS")
			(hide yes)
			(effects
				(font
					(size 1.27 1.27)
				)
				(justify mirror)
			)
		)
		(property "Value" "SNLVC1G126DCKR-GP"
			(at 2.3368 -8.6868 270)
			(unlocked yes)
			(layer "B.Fab")
			(hide yes)
			(effects
				(font
					(size 1.016 1.016)
					(thickness 0.1524)
				)
				(justify mirror)
			)
		)
		(property "Device Type" "SC70-5H44"
			(at 2.3114 -10.414 270)
			(unlocked yes)
			(layer "B.Fab")
			(hide yes)
			(effects
				(font
					(size 1.016 1.016)
					(thickness 0.1524)
				)
				(justify mirror)
			)
		)
		(duplicate_pad_numbers_are_jumpers no)
		(fp_line
			(start -1.27 1.7018)
			(end 1.27 1.7018)
			(stroke
				(width 0.1524)
				(type default)
			)
			(layer "B.SilkS")
		)
		(fp_line
			(start 1.27 1.7018)
			(end 1.27 -1.7018)
			(stroke
				(width 0.1524)
				(type default)
			)
			(layer "B.SilkS")
		)
		(fp_line
			(start -1.27 -1.7018)
			(end -1.27 1.7018)
			(stroke
				(width 0.1524)
				(type default)
			)
			(layer "B.SilkS")
		)
		(fp_line
			(start 1.27 -1.7018)
			(end -1.27 -1.7018)
			(stroke
				(width 0.1524)
				(type default)
			)
			(layer "B.SilkS")
		)
		(fp_line
			(start -1.3843 -1.8034)
			(end -1.3843 -1.1176)
			(stroke
				(width 0.3302)
				(type default)
			)
			(layer "B.SilkS")
		)
		(fp_line
			(start -0.6604 -1.8034)
			(end -1.3843 -1.8034)
			(stroke
				(width 0.3302)
				(type default)
			)
			(layer "B.SilkS")
		)
		(fp_rect
			(start 1.524 1.9558)
			(end -1.524 -1.9558)
			(stroke
				(width 0)
				(type default)
			)
			(fill no)
			(layer "B.CrtYd")
		)
		(fp_poly
			(pts
				(xy 1.524 -1.9558) (xy -1.524 -1.9558) (xy -1.524 1.9558) (xy 1.524 1.9558)
			)
			(stroke
				(width 0)
				(type default)
			)
			(fill no)
			(layer "B.Fab")
		)
		(pad "1" smd rect
			(at -0.65024 -0.8255 90)
			(size 0.4064 1.2192)
			(layers "B.Cu" "B.Mask" "B.Paste")
			(net "PWRGD_P3V3_STBY")
		)
		(pad "2" smd rect
			(at 0 -0.8255 90)
			(size 0.4064 1.2192)
			(layers "B.Cu" "B.Mask" "B.Paste")
			(net "BMC_TO_EXP_RESET_OUT_R")
		)
		(pad "3" smd rect
			(at 0.65024 -0.8255 90)
			(size 0.4064 1.2192)
			(layers "B.Cu" "B.Mask" "B.Paste")
			(net "GND")
		)
		(pad "4" smd rect
			(at 0.65024 0.8255 90)
			(size 0.4064 1.2192)
			(layers "B.Cu" "B.Mask" "B.Paste")
			(net "BMC_TO_EXP_RESET_N")
		)
		(pad "5" smd rect
			(at -0.65024 0.8255 90)
			(size 0.4064 1.2192)
			(layers "B.Cu" "B.Mask" "B.Paste")
			(net "P3V3_STBY")
		)
	)
	(footprint ""
		(layer "B.Cu")
		(at 92.456 -146.0246 90)
		(property "Reference" "R425"
			(at 0 0 90)
			(layer "B.SilkS")
			(hide yes)
			(effects
				(font
					(size 1.27 1.27)
				)
				(justify mirror)
			)
		)
		(property "Value" "4K7R2F-GP"
			(at -0.064008 -3.993896 90)
			(unlocked yes)
			(layer "B.Fab")
			(hide yes)
			(effects
				(font
					(size 1.016 1.016)
					(thickness 0.1524)
				)
				(justify mirror)
			)
		)
		(property "Device Type" "R402H16"
			(at -0.064008 -5.517896 90)
			(unlocked yes)
			(layer "B.Fab")
			(hide yes)
			(effects
				(font
					(size 1.016 1.016)
					(thickness 0.1524)
				)
				(justify mirror)
			)
		)
		(duplicate_pad_numbers_are_jumpers no)
		(fp_line
			(start 0.508 -0.9398)
			(end 0.508 0.9398)
			(stroke
				(width 0.1524)
				(type default)
			)
			(layer "B.SilkS")
		)
		(fp_line
			(start -0.508 -0.9398)
			(end 0.508 -0.9398)
			(stroke
				(width 0.1524)
				(type default)
			)
			(layer "B.SilkS")
		)
		(fp_rect
			(start 0.508 0.9398)
			(end -0.508 -0.9398)
			(stroke
				(width 0)
				(type default)
			)
			(fill no)
			(layer "B.CrtYd")
		)
		(fp_rect
			(start 0.508 0.9398)
			(end -0.508 -0.9398)
			(stroke
				(width 0)
				(type default)
			)
			(fill no)
			(layer "B.Fab")
		)
		(pad "1" smd custom
			(at 0 -0.4445 270)
			(size 0.1397 0.1397)
			(layers "B.Cu" "B.Mask" "B.Paste")
			(net "P3V3_STBY")
			(options
				(clearance outline)
				(anchor circle)
			)
			(primitives
				(gr_poly
					(pts
						(arc
							(start -0.1778 0.2794)
							(mid -0.249642 0.249642)
							(end -0.2794 0.1778)
						)
						(arc
							(start -0.2794 -0.1778)
							(mid -0.249642 -0.249642)
							(end -0.1778 -0.2794)
						)
						(arc
							(start 0.1778 -0.2794)
							(mid 0.249642 -0.249642)
							(end 0.2794 -0.1778)
						)
						(arc
							(start 0.2794 0.1778)
							(mid 0.249642 0.249642)
							(end 0.1778 0.2794)
						)
					)
					(width 0)
					(fill yes)
				)
			)
		)
		(pad "2" smd custom
			(at 0 0.4445 270)
			(size 0.1397 0.1397)
			(layers "B.Cu" "B.Mask" "B.Paste")
			(net "TCA9555_A2")
			(options
				(clearance outline)
				(anchor circle)
			)
			(primitives
				(gr_poly
					(pts
						(arc
							(start -0.1778 0.2794)
							(mid -0.249642 0.249642)
							(end -0.2794 0.1778)
						)
						(arc
							(start -0.2794 -0.1778)
							(mid -0.249642 -0.249642)
							(end -0.1778 -0.2794)
						)
						(arc
							(start 0.1778 -0.2794)
							(mid 0.249642 -0.249642)
							(end 0.2794 -0.1778)
						)
						(arc
							(start 0.2794 0.1778)
							(mid 0.249642 0.249642)
							(end 0.1778 0.2794)
						)
					)
					(width 0)
					(fill yes)
				)
			)
		)
	)
	(footprint ""
		(layer "B.Cu")
		(at 89.662 -155.6004 90)
		(property "Reference" "C12"
			(at 0 0 90)
			(layer "B.SilkS")
			(hide yes)
			(effects
				(font
					(size 1.27 1.27)
				)
				(justify mirror)
			)
		)
		(property "Value" "SC1U16V2KX-7-GP"
			(at -1.7526 -1.6002 90)
			(unlocked yes)
			(layer "B.Fab")
			(hide yes)
			(effects
				(font
					(size 1.016 1.016)
					(thickness 0.1524)
				)
				(justify mirror)
			)
		)
		(property "Device Type" "C402-TO0D2H24"
			(at -1.7526 -3.1242 90)
			(unlocked yes)
			(layer "B.Fab")
			(hide yes)
			(effects
				(font
					(size 1.016 1.016)
					(thickness 0.1524)
				)
				(justify mirror)
			)
		)
		(duplicate_pad_numbers_are_jumpers no)
		(fp_rect
			(start 0.4826 0.889)
			(end -0.4826 -0.889)
			(stroke
				(width 0)
				(type default)
			)
			(fill no)
			(layer "B.CrtYd")
		)
		(fp_rect
			(start 0.4826 0.889)
			(end -0.4826 -0.889)
			(stroke
				(width 0)
				(type default)
			)
			(fill no)
			(layer "B.Fab")
		)
		(pad "1" smd custom
			(at 0 -0.4572 270)
			(size 0.1524 0.1524)
			(layers "B.Cu" "B.Mask" "B.Paste")
			(net "P3V3_STBY")
			(options
				(clearance outline)
				(anchor circle)
			)
			(primitives
				(gr_poly
					(pts
						(arc
							(start -0.254 -0.3048)
							(mid -0.325842 -0.275042)
							(end -0.3556 -0.2032)
						)
						(arc
							(start -0.3556 0.2032)
							(mid -0.325842 0.275042)
							(end -0.254 0.3048)
						)
						(arc
							(start 0.254 0.3048)
							(mid 0.325842 0.275042)
							(end 0.3556 0.2032)
						)
						(arc
							(start 0.3556 -0.2032)
							(mid 0.325842 -0.275042)
							(end 0.254 -0.3048)
						)
					)
					(width 0)
					(fill yes)
				)
			)
		)
		(pad "2" smd custom
			(at 0 0.4572 270)
			(size 0.1524 0.1524)
			(layers "B.Cu" "B.Mask" "B.Paste")
			(net "GND")
			(options
				(clearance outline)
				(anchor circle)
			)
			(primitives
				(gr_poly
					(pts
						(arc
							(start -0.254 -0.3048)
							(mid -0.325842 -0.275042)
							(end -0.3556 -0.2032)
						)
						(arc
							(start -0.3556 0.2032)
							(mid -0.325842 0.275042)
							(end -0.254 0.3048)
						)
						(arc
							(start 0.254 0.3048)
							(mid 0.325842 0.275042)
							(end 0.3556 0.2032)
						)
						(arc
							(start 0.3556 -0.2032)
							(mid 0.325842 -0.275042)
							(end 0.254 -0.3048)
						)
					)
					(width 0)
					(fill yes)
				)
			)
		)
	)
	(footprint ""
		(layer "B.Cu")
		(at 116.82984 -6.60146 90)
		(property "Reference" "R436"
			(at 0 0 90)
			(layer "B.SilkS")
			(hide yes)
			(effects
				(font
					(size 1.27 1.27)
				)
				(justify mirror)
			)
		)
		(property "Value" "0R2J-2-GP"
			(at -0.064008 -3.993896 90)
			(unlocked yes)
			(layer "B.Fab")
			(hide yes)
			(effects
				(font
					(size 1.016 1.016)
					(thickness 0.1524)
				)
				(justify mirror)
			)
		)
		(property "Device Type" "R402H16"
			(at -0.064008 -5.517896 90)
			(unlocked yes)
			(layer "B.Fab")
			(hide yes)
			(effects
				(font
					(size 1.016 1.016)
					(thickness 0.1524)
				)
				(justify mirror)
			)
		)
		(duplicate_pad_numbers_are_jumpers no)
		(fp_line
			(start 0.508 -0.9398)
			(end 0.508 0.9398)
			(stroke
				(width 0.1524)
				(type default)
			)
			(layer "B.SilkS")
		)
		(fp_line
			(start -0.508 -0.9398)
			(end 0.508 -0.9398)
			(stroke
				(width 0.1524)
				(type default)
			)
			(layer "B.SilkS")
		)
		(fp_rect
			(start 0.508 0.9398)
			(end -0.508 -0.9398)
			(stroke
				(width 0)
				(type default)
			)
			(fill no)
			(layer "B.CrtYd")
		)
		(fp_rect
			(start 0.508 0.9398)
			(end -0.508 -0.9398)
			(stroke
				(width 0)
				(type default)
			)
			(fill no)
			(layer "B.Fab")
		)
		(pad "1" smd custom
			(at 0 -0.4445 270)
			(size 0.1397 0.1397)
			(layers "B.Cu" "B.Mask" "B.Paste")
			(net "P12V_A_PGOOD")
			(options
				(clearance outline)
				(anchor circle)
			)
			(primitives
				(gr_poly
					(pts
						(arc
							(start -0.1778 0.2794)
							(mid -0.249642 0.249642)
							(end -0.2794 0.1778)
						)
						(arc
							(start -0.2794 -0.1778)
							(mid -0.249642 -0.249642)
							(end -0.1778 -0.2794)
						)
						(arc
							(start 0.1778 -0.2794)
							(mid 0.249642 -0.249642)
							(end 0.2794 -0.1778)
						)
						(arc
							(start 0.2794 0.1778)
							(mid 0.249642 0.249642)
							(end 0.1778 0.2794)
						)
					)
					(width 0)
					(fill yes)
				)
			)
		)
		(pad "2" smd custom
			(at 0 0.4445 270)
			(size 0.1397 0.1397)
			(layers "B.Cu" "B.Mask" "B.Paste")
			(net "MB0_HS_ENABLE")
			(options
				(clearance outline)
				(anchor circle)
			)
			(primitives
				(gr_poly
					(pts
						(arc
							(start -0.1778 0.2794)
							(mid -0.249642 0.249642)
							(end -0.2794 0.1778)
						)
						(arc
							(start -0.2794 -0.1778)
							(mid -0.249642 -0.249642)
							(end -0.1778 -0.2794)
						)
						(arc
							(start 0.1778 -0.2794)
							(mid 0.249642 -0.249642)
							(end 0.2794 -0.1778)
						)
						(arc
							(start 0.2794 0.1778)
							(mid 0.249642 0.249642)
							(end 0.1778 0.2794)
						)
					)
					(width 0)
					(fill yes)
				)
			)
		)
	)
	(footprint ""
		(layer "B.Cu")
		(at 32.4866 -159.0802 -90)
		(property "Reference" "R699"
			(at 0 0 90)
			(layer "B.SilkS")
			(hide yes)
			(effects
				(font
					(size 1.27 1.27)
				)
				(justify mirror)
			)
		)
		(property "Value" "4K7R2F-GP"
			(at -0.064008 -3.993896 270)
			(unlocked yes)
			(layer "B.Fab")
			(hide yes)
			(effects
				(font
					(size 1.016 1.016)
					(thickness 0.1524)
				)
				(justify mirror)
			)
		)
		(property "Device Type" "R402H16"
			(at -0.064008 -5.517896 270)
			(unlocked yes)
			(layer "B.Fab")
			(hide yes)
			(effects
				(font
					(size 1.016 1.016)
					(thickness 0.1524)
				)
				(justify mirror)
			)
		)
		(duplicate_pad_numbers_are_jumpers no)
		(fp_line
			(start -0.508 -0.9398)
			(end 0.508 -0.9398)
			(stroke
				(width 0.1524)
				(type default)
			)
			(layer "B.SilkS")
		)
		(fp_line
			(start 0.508 -0.9398)
			(end 0.508 0.9398)
			(stroke
				(width 0.1524)
				(type default)
			)
			(layer "B.SilkS")
		)
		(fp_rect
			(start 0.508 0.9398)
			(end -0.508 -0.9398)
			(stroke
				(width 0)
				(type default)
			)
			(fill no)
			(layer "B.CrtYd")
		)
		(fp_rect
			(start 0.508 0.9398)
			(end -0.508 -0.9398)
			(stroke
				(width 0)
				(type default)
			)
			(fill no)
			(layer "B.Fab")
		)
		(pad "1" smd custom
			(at 0 -0.4445 90)
			(size 0.1397 0.1397)
			(layers "B.Cu" "B.Mask" "B.Paste")
			(net "IOM_TYPE2")
			(options
				(clearance outline)
				(anchor circle)
			)
			(primitives
				(gr_poly
					(pts
						(arc
							(start -0.1778 0.2794)
							(mid -0.249642 0.249642)
							(end -0.2794 0.1778)
						)
						(arc
							(start -0.2794 -0.1778)
							(mid -0.249642 -0.249642)
							(end -0.1778 -0.2794)
						)
						(arc
							(start 0.1778 -0.2794)
							(mid 0.249642 -0.249642)
							(end 0.2794 -0.1778)
						)
						(arc
							(start 0.2794 0.1778)
							(mid 0.249642 0.249642)
							(end 0.1778 0.2794)
						)
					)
					(width 0)
					(fill yes)
				)
			)
		)
		(pad "2" smd custom
			(at 0 0.4445 90)
			(size 0.1397 0.1397)
			(layers "B.Cu" "B.Mask" "B.Paste")
			(net "GND")
			(options
				(clearance outline)
				(anchor circle)
			)
			(primitives
				(gr_poly
					(pts
						(arc
							(start -0.1778 0.2794)
							(mid -0.249642 0.249642)
							(end -0.2794 0.1778)
						)
						(arc
							(start -0.2794 -0.1778)
							(mid -0.249642 -0.249642)
							(end -0.1778 -0.2794)
						)
						(arc
							(start 0.1778 -0.2794)
							(mid 0.249642 -0.249642)
							(end 0.2794 -0.1778)
						)
						(arc
							(start 0.2794 0.1778)
							(mid 0.249642 0.249642)
							(end 0.1778 0.2794)
						)
					)
					(width 0)
					(fill yes)
				)
			)
		)
	)
	(footprint ""
		(layer "B.Cu")
		(at 16.3449 -147.2438 180)
		(property "Reference" "C61"
			(at 0 0 0)
			(layer "B.SilkS")
			(hide yes)
			(effects
				(font
					(size 1.27 1.27)
				)
				(justify mirror)
			)
		)
		(property "Value" "SC1U16V3KX-5GP"
			(at 0 -2.8194 180)
			(unlocked yes)
			(layer "B.Fab")
			(hide yes)
			(effects
				(font
					(size 1.016 1.016)
					(thickness 0.1524)
				)
				(justify mirror)
			)
		)
		(property "Device Type" "C603H36"
			(at 0 -4.3434 180)
			(unlocked yes)
			(layer "B.Fab")
			(hide yes)
			(effects
				(font
					(size 1.016 1.016)
					(thickness 0.1524)
				)
				(justify mirror)
			)
		)
		(duplicate_pad_numbers_are_jumpers no)
		(fp_line
			(start -0.508 0)
			(end 0.508 0)
			(stroke
				(width 0.2032)
				(type default)
			)
			(layer "B.SilkS")
		)
		(fp_rect
			(start 0.5842 1.3335)
			(end -0.5842 -1.3335)
			(stroke
				(width 0)
				(type default)
			)
			(fill no)
			(layer "B.CrtYd")
		)
		(fp_rect
			(start 0.5842 1.3335)
			(end -0.5842 -1.3335)
			(stroke
				(width 0)
				(type default)
			)
			(fill no)
			(layer "B.Fab")
		)
		(pad "1" smd custom
			(at 0 -0.762)
			(size 0.2159 0.2159)
			(layers "B.Cu" "B.Mask" "B.Paste")
			(net "P1V2_STBY")
			(options
				(clearance outline)
				(anchor circle)
			)
			(primitives
				(gr_poly
					(pts
						(arc
							(start -0.3302 0.4318)
							(mid -0.402042 0.402042)
							(end -0.4318 0.3302)
						)
						(arc
							(start -0.4318 -0.3302)
							(mid -0.402042 -0.402042)
							(end -0.3302 -0.4318)
						)
						(arc
							(start 0.3302 -0.4318)
							(mid 0.402042 -0.402042)
							(end 0.4318 -0.3302)
						)
						(arc
							(start 0.4318 0.3302)
							(mid 0.402042 0.402042)
							(end 0.3302 0.4318)
						)
					)
					(width 0)
					(fill yes)
				)
			)
		)
		(pad "2" smd custom
			(at 0 0.762)
			(size 0.2159 0.2159)
			(layers "B.Cu" "B.Mask" "B.Paste")
			(net "GND")
			(options
				(clearance outline)
				(anchor circle)
			)
			(primitives
				(gr_poly
					(pts
						(arc
							(start -0.3302 0.4318)
							(mid -0.402042 0.402042)
							(end -0.4318 0.3302)
						)
						(arc
							(start -0.4318 -0.3302)
							(mid -0.402042 -0.402042)
							(end -0.3302 -0.4318)
						)
						(arc
							(start 0.3302 -0.4318)
							(mid 0.402042 -0.402042)
							(end 0.4318 -0.3302)
						)
						(arc
							(start 0.4318 0.3302)
							(mid 0.402042 0.402042)
							(end 0.3302 0.4318)
						)
					)
					(width 0)
					(fill yes)
				)
			)
		)
	)
	(footprint ""
		(layer "B.Cu")
		(at 90.96248 -138.659616 180)
		(property "Reference" "R721"
			(at 0 0 0)
			(layer "B.SilkS")
			(hide yes)
			(effects
				(font
					(size 1.27 1.27)
				)
				(justify mirror)
			)
		)
		(property "Value" "4K7R2F-GP"
			(at -0.064008 -3.993896 180)
			(unlocked yes)
			(layer "B.Fab")
			(hide yes)
			(effects
				(font
					(size 1.016 1.016)
					(thickness 0.1524)
				)
				(justify mirror)
			)
		)
		(property "Device Type" "R402H16"
			(at -0.064008 -5.517896 180)
			(unlocked yes)
			(layer "B.Fab")
			(hide yes)
			(effects
				(font
					(size 1.016 1.016)
					(thickness 0.1524)
				)
				(justify mirror)
			)
		)
		(duplicate_pad_numbers_are_jumpers no)
		(fp_line
			(start 0.508 -0.9398)
			(end 0.508 0.9398)
			(stroke
				(width 0.1524)
				(type default)
			)
			(layer "B.SilkS")
		)
		(fp_line
			(start -0.508 -0.9398)
			(end 0.508 -0.9398)
			(stroke
				(width 0.1524)
				(type default)
			)
			(layer "B.SilkS")
		)
		(fp_rect
			(start 0.508 0.9398)
			(end -0.508 -0.9398)
			(stroke
				(width 0)
				(type default)
			)
			(fill no)
			(layer "B.CrtYd")
		)
		(fp_rect
			(start 0.508 0.9398)
			(end -0.508 -0.9398)
			(stroke
				(width 0)
				(type default)
			)
			(fill no)
			(layer "B.Fab")
		)
		(pad "1" smd custom
			(at 0 -0.4445)
			(size 0.1397 0.1397)
			(layers "B.Cu" "B.Mask" "B.Paste")
			(net "P3V3_STBY")
			(options
				(clearance outline)
				(anchor circle)
			)
			(primitives
				(gr_poly
					(pts
						(arc
							(start -0.1778 0.2794)
							(mid -0.249642 0.249642)
							(end -0.2794 0.1778)
						)
						(arc
							(start -0.2794 -0.1778)
							(mid -0.249642 -0.249642)
							(end -0.1778 -0.2794)
						)
						(arc
							(start 0.1778 -0.2794)
							(mid 0.249642 -0.249642)
							(end 0.2794 -0.1778)
						)
						(arc
							(start 0.2794 0.1778)
							(mid 0.249642 0.249642)
							(end 0.1778 0.2794)
						)
					)
					(width 0)
					(fill yes)
				)
			)
		)
		(pad "2" smd custom
			(at 0 0.4445)
			(size 0.1397 0.1397)
			(layers "B.Cu" "B.Mask" "B.Paste")
			(net "DEBUG_HDR_UART_SEL")
			(options
				(clearance outline)
				(anchor circle)
			)
			(primitives
				(gr_poly
					(pts
						(arc
							(start -0.1778 0.2794)
							(mid -0.249642 0.249642)
							(end -0.2794 0.1778)
						)
						(arc
							(start -0.2794 -0.1778)
							(mid -0.249642 -0.249642)
							(end -0.1778 -0.2794)
						)
						(arc
							(start 0.1778 -0.2794)
							(mid 0.249642 -0.249642)
							(end 0.2794 -0.1778)
						)
						(arc
							(start 0.2794 0.1778)
							(mid 0.249642 0.249642)
							(end 0.1778 0.2794)
						)
					)
					(width 0)
					(fill yes)
				)
			)
		)
	)
	(footprint ""
		(layer "B.Cu")
		(at 203.273914 -130.370072 180)
		(property "Reference" "C606"
			(at 0 0 0)
			(layer "B.SilkS")
			(hide yes)
			(effects
				(font
					(size 1.27 1.27)
				)
				(justify mirror)
			)
		)
		(property "Value" "SC10U6D3V5KX-4GP"
			(at 0.0762 -6.1214 180)
			(unlocked yes)
			(layer "B.Fab")
			(hide yes)
			(effects
				(font
					(size 1.016 1.016)
					(thickness 0.1524)
				)
				(justify mirror)
			)
		)
		(property "Device Type" "C805H58"
			(at 0.0762 -8.1534 180)
			(unlocked yes)
			(layer "B.Fab")
			(hide yes)
			(effects
				(font
					(size 1.016 1.016)
					(thickness 0.1524)
				)
				(justify mirror)
			)
		)
		(duplicate_pad_numbers_are_jumpers no)
		(fp_line
			(start -0.635 0)
			(end 0.635 0)
			(stroke
				(width 0.508)
				(type default)
			)
			(layer "B.SilkS")
		)
		(fp_rect
			(start 0.9652 1.778)
			(end -0.9652 -1.778)
			(stroke
				(width 0)
				(type default)
			)
			(fill no)
			(layer "B.CrtYd")
		)
		(fp_poly
			(pts
				(xy 0.9652 -1.778) (xy -0.9652 -1.778) (xy -0.9652 1.778) (xy 0.9652 1.778)
			)
			(stroke
				(width 0)
				(type default)
			)
			(fill no)
			(layer "B.Fab")
		)
		(pad "1" smd rect
			(at 0 -0.9652)
			(size 1.397 1.143)
			(layers "B.Cu" "B.Mask" "B.Paste")
			(net "P3V3_M2")
		)
		(pad "2" smd rect
			(at 0 0.9652)
			(size 1.397 1.143)
			(layers "B.Cu" "B.Mask" "B.Paste")
			(net "GND")
		)
	)
	(footprint ""
		(layer "B.Cu")
		(at 47.861474 -155.356052)
		(property "Reference" "R310"
			(at 0 0 0)
			(layer "B.SilkS")
			(hide yes)
			(effects
				(font
					(size 1.27 1.27)
				)
				(justify mirror)
			)
		)
		(property "Value" "4K7R2F-GP"
			(at -0.064008 -3.993896 0)
			(unlocked yes)
			(layer "B.Fab")
			(hide yes)
			(effects
				(font
					(size 1.016 1.016)
					(thickness 0.1524)
				)
				(justify mirror)
			)
		)
		(property "Device Type" "R402H16"
			(at -0.064008 -5.517896 0)
			(unlocked yes)
			(layer "B.Fab")
			(hide yes)
			(effects
				(font
					(size 1.016 1.016)
					(thickness 0.1524)
				)
				(justify mirror)
			)
		)
		(duplicate_pad_numbers_are_jumpers no)
		(fp_line
			(start -0.508 -0.9398)
			(end 0.508 -0.9398)
			(stroke
				(width 0.1524)
				(type default)
			)
			(layer "B.SilkS")
		)
		(fp_line
			(start 0.508 -0.9398)
			(end 0.508 0.9398)
			(stroke
				(width 0.1524)
				(type default)
			)
			(layer "B.SilkS")
		)
		(fp_rect
			(start 0.508 0.9398)
			(end -0.508 -0.9398)
			(stroke
				(width 0)
				(type default)
			)
			(fill no)
			(layer "B.CrtYd")
		)
		(fp_rect
			(start 0.508 0.9398)
			(end -0.508 -0.9398)
			(stroke
				(width 0)
				(type default)
			)
			(fill no)
			(layer "B.Fab")
		)
		(pad "1" smd custom
			(at 0 -0.4445 180)
			(size 0.1397 0.1397)
			(layers "B.Cu" "B.Mask" "B.Paste")
			(net "P3V3_STBY")
			(options
				(clearance outline)
				(anchor circle)
			)
			(primitives
				(gr_poly
					(pts
						(arc
							(start -0.1778 0.2794)
							(mid -0.249642 0.249642)
							(end -0.2794 0.1778)
						)
						(arc
							(start -0.2794 -0.1778)
							(mid -0.249642 -0.249642)
							(end -0.1778 -0.2794)
						)
						(arc
							(start 0.1778 -0.2794)
							(mid 0.249642 -0.249642)
							(end 0.2794 -0.1778)
						)
						(arc
							(start 0.2794 0.1778)
							(mid 0.249642 0.249642)
							(end 0.1778 0.2794)
						)
					)
					(width 0)
					(fill yes)
				)
			)
		)
		(pad "2" smd custom
			(at 0 0.4445 180)
			(size 0.1397 0.1397)
			(layers "B.Cu" "B.Mask" "B.Paste")
			(net "BOARD_REV_1")
			(options
				(clearance outline)
				(anchor circle)
			)
			(primitives
				(gr_poly
					(pts
						(arc
							(start -0.1778 0.2794)
							(mid -0.249642 0.249642)
							(end -0.2794 0.1778)
						)
						(arc
							(start -0.2794 -0.1778)
							(mid -0.249642 -0.249642)
							(end -0.1778 -0.2794)
						)
						(arc
							(start 0.1778 -0.2794)
							(mid 0.249642 -0.249642)
							(end 0.2794 -0.1778)
						)
						(arc
							(start 0.2794 0.1778)
							(mid 0.249642 0.249642)
							(end 0.1778 0.2794)
						)
					)
					(width 0)
					(fill yes)
				)
			)
		)
	)
	(footprint ""
		(layer "B.Cu")
		(at 93.9292 -146.3802 180)
		(property "Reference" "R430"
			(at 0 0 0)
			(layer "B.SilkS")
			(hide yes)
			(effects
				(font
					(size 1.27 1.27)
				)
				(justify mirror)
			)
		)
		(property "Value" "4K7R2F-GP"
			(at -0.064008 -3.993896 180)
			(unlocked yes)
			(layer "B.Fab")
			(hide yes)
			(effects
				(font
					(size 1.016 1.016)
					(thickness 0.1524)
				)
				(justify mirror)
			)
		)
		(property "Device Type" "R402H16"
			(at -0.064008 -5.517896 180)
			(unlocked yes)
			(layer "B.Fab")
			(hide yes)
			(effects
				(font
					(size 1.016 1.016)
					(thickness 0.1524)
				)
				(justify mirror)
			)
		)
		(duplicate_pad_numbers_are_jumpers no)
		(fp_line
			(start 0.508 -0.9398)
			(end 0.508 0.9398)
			(stroke
				(width 0.1524)
				(type default)
			)
			(layer "B.SilkS")
		)
		(fp_line
			(start -0.508 -0.9398)
			(end 0.508 -0.9398)
			(stroke
				(width 0.1524)
				(type default)
			)
			(layer "B.SilkS")
		)
		(fp_rect
			(start 0.508 0.9398)
			(end -0.508 -0.9398)
			(stroke
				(width 0)
				(type default)
			)
			(fill no)
			(layer "B.CrtYd")
		)
		(fp_rect
			(start 0.508 0.9398)
			(end -0.508 -0.9398)
			(stroke
				(width 0)
				(type default)
			)
			(fill no)
			(layer "B.Fab")
		)
		(pad "1" smd custom
			(at 0 -0.4445)
			(size 0.1397 0.1397)
			(layers "B.Cu" "B.Mask" "B.Paste")
			(net "TCA9555_A2")
			(options
				(clearance outline)
				(anchor circle)
			)
			(primitives
				(gr_poly
					(pts
						(arc
							(start -0.1778 0.2794)
							(mid -0.249642 0.249642)
							(end -0.2794 0.1778)
						)
						(arc
							(start -0.2794 -0.1778)
							(mid -0.249642 -0.249642)
							(end -0.1778 -0.2794)
						)
						(arc
							(start 0.1778 -0.2794)
							(mid 0.249642 -0.249642)
							(end 0.2794 -0.1778)
						)
						(arc
							(start 0.2794 0.1778)
							(mid 0.249642 0.249642)
							(end 0.1778 0.2794)
						)
					)
					(width 0)
					(fill yes)
				)
			)
		)
		(pad "2" smd custom
			(at 0 0.4445)
			(size 0.1397 0.1397)
			(layers "B.Cu" "B.Mask" "B.Paste")
			(net "GND")
			(options
				(clearance outline)
				(anchor circle)
			)
			(primitives
				(gr_poly
					(pts
						(arc
							(start -0.1778 0.2794)
							(mid -0.249642 0.249642)
							(end -0.2794 0.1778)
						)
						(arc
							(start -0.2794 -0.1778)
							(mid -0.249642 -0.249642)
							(end -0.1778 -0.2794)
						)
						(arc
							(start 0.1778 -0.2794)
							(mid 0.249642 -0.249642)
							(end 0.2794 -0.1778)
						)
						(arc
							(start 0.2794 0.1778)
							(mid 0.249642 0.249642)
							(end 0.1778 0.2794)
						)
					)
					(width 0)
					(fill yes)
				)
			)
		)
	)
	(footprint ""
		(layer "B.Cu")
		(at 177.5587 -118.690644 180)
		(property "Reference" "U83"
			(at 0 0 0)
			(layer "B.SilkS")
			(hide yes)
			(effects
				(font
					(size 1.27 1.27)
				)
				(justify mirror)
			)
		)
		(property "Value" "PCA9306DCTT-GP"
			(at 0 -11.6332 180)
			(unlocked yes)
			(layer "B.Fab")
			(hide yes)
			(effects
				(font
					(size 1.016 1.016)
					(thickness 0.1524)
				)
				(justify mirror)
			)
		)
		(property "Device Type" "SSOIC8H52"
			(at 0 -13.1572 180)
			(unlocked yes)
			(layer "B.Fab")
			(hide yes)
			(effects
				(font
					(size 1.016 1.016)
					(thickness 0.1524)
				)
				(justify mirror)
			)
		)
		(duplicate_pad_numbers_are_jumpers no)
		(fp_line
			(start 1.7018 -0.5842)
			(end 1.7018 2.286)
			(stroke
				(width 0.1524)
				(type default)
			)
			(layer "B.SilkS")
		)
		(fp_line
			(start 1.7018 -0.5842)
			(end -1.0668 -0.5842)
			(stroke
				(width 0.1524)
				(type default)
			)
			(layer "B.SilkS")
		)
		(fp_line
			(start 1.524 0.5842)
			(end 1.524 2.286)
			(stroke
				(width 0.508)
				(type default)
			)
			(layer "B.SilkS")
		)
		(fp_line
			(start 1.397 0)
			(end 1.7018 0.3048)
			(stroke
				(width 0.1524)
				(type default)
			)
			(layer "B.SilkS")
		)
		(fp_line
			(start 1.397 0)
			(end 1.7018 -0.3048)
			(stroke
				(width 0.1524)
				(type default)
			)
			(layer "B.SilkS")
		)
		(fp_line
			(start -1.0668 0.5842)
			(end 1.524 0.5842)
			(stroke
				(width 0.1524)
				(type default)
			)
			(layer "B.SilkS")
		)
		(fp_line
			(start -1.0668 -0.5842)
			(end -1.0668 0.5842)
			(stroke
				(width 0.1524)
				(type default)
			)
			(layer "B.SilkS")
		)
		(fp_poly
			(pts
				(xy 1.1684 -0.5842) (xy -1.0668 -0.5842) (xy -1.0668 0.5842) (xy 1.1684 0.5842)
			)
			(stroke
				(width 0)
				(type default)
			)
			(fill yes)
			(layer "B.SilkS")
		)
		(fp_poly
			(pts
				(xy 1.778 2.54) (xy -1.778 2.54) (xy -1.778 -2.54) (xy 1.778 -2.54)
			)
			(stroke
				(width 0)
				(type default)
			)
			(fill no)
			(layer "B.CrtYd")
		)
		(fp_poly
			(pts
				(xy 1.778 -2.54) (xy -1.778 -2.54) (xy -1.778 2.54) (xy 1.778 2.54)
			)
			(stroke
				(width 0)
				(type default)
			)
			(fill no)
			(layer "B.Fab")
		)
		(pad "1" smd rect
			(at 0.97536 1.6256)
			(size 0.3556 1.524)
			(layers "B.Cu" "B.Mask" "B.Paste")
			(net "GND")
		)
		(pad "2" smd rect
			(at 0.32512 1.6256)
			(size 0.3556 1.524)
			(layers "B.Cu" "B.Mask" "B.Paste")
			(net "P1V8_STBY")
		)
		(pad "3" smd rect
			(at -0.32512 1.6256)
			(size 0.3556 1.524)
			(layers "B.Cu" "B.Mask" "B.Paste")
			(net "I2C_M2_2_1V8_SCL")
		)
		(pad "4" smd rect
			(at -0.97536 1.6256)
			(size 0.3556 1.524)
			(layers "B.Cu" "B.Mask" "B.Paste")
			(net "I2C_M2_2_1V8_SDA")
		)
		(pad "5" smd rect
			(at -0.97536 -1.6256)
			(size 0.3556 1.524)
			(layers "B.Cu" "B.Mask" "B.Paste")
			(net "I2C_M2_2_SDA")
		)
		(pad "6" smd rect
			(at -0.32512 -1.6256)
			(size 0.3556 1.524)
			(layers "B.Cu" "B.Mask" "B.Paste")
			(net "I2C_M2_2_SCL")
		)
		(pad "7" smd rect
			(at 0.32512 -1.6256)
			(size 0.3556 1.524)
			(layers "B.Cu" "B.Mask" "B.Paste")
			(net "U83_VREF2")
		)
		(pad "8" smd rect
			(at 0.97536 -1.6256)
			(size 0.3556 1.524)
			(layers "B.Cu" "B.Mask" "B.Paste")
			(net "U83_VREF2")
		)
	)
	(footprint ""
		(layer "B.Cu")
		(at 221.94266 -56.533542 -90)
		(property "Reference" "R464"
			(at 0 0 90)
			(layer "B.SilkS")
			(hide yes)
			(effects
				(font
					(size 1.27 1.27)
				)
				(justify mirror)
			)
		)
		(property "Value" "2D2R3-1-U-GP"
			(at 0.0254 -2.5146 270)
			(unlocked yes)
			(layer "B.Fab")
			(hide yes)
			(effects
				(font
					(size 1.016 1.016)
					(thickness 0.1524)
				)
				(justify mirror)
			)
		)
		(property "Device Type" "R603H22"
			(at 0.0254 -4.0386 270)
			(unlocked yes)
			(layer "B.Fab")
			(hide yes)
			(effects
				(font
					(size 1.016 1.016)
					(thickness 0.1524)
				)
				(justify mirror)
			)
		)
		(duplicate_pad_numbers_are_jumpers no)
		(fp_line
			(start -0.2032 0)
			(end -0.4826 0)
			(stroke
				(width 0.2032)
				(type default)
			)
			(layer "B.SilkS")
		)
		(fp_line
			(start 0.4826 0)
			(end 0.2032 0)
			(stroke
				(width 0.2032)
				(type default)
			)
			(layer "B.SilkS")
		)
		(fp_rect
			(start 0.5842 1.3335)
			(end -0.5842 -1.3335)
			(stroke
				(width 0)
				(type default)
			)
			(fill no)
			(layer "B.CrtYd")
		)
		(fp_rect
			(start 0.5842 1.3335)
			(end -0.5842 -1.3335)
			(stroke
				(width 0)
				(type default)
			)
			(fill no)
			(layer "B.Fab")
		)
		(pad "1" smd custom
			(at 0 -0.762 90)
			(size 0.2159 0.2159)
			(layers "B.Cu" "B.Mask" "B.Paste")
			(net "P12V_STBY")
			(options
				(clearance outline)
				(anchor circle)
			)
			(primitives
				(gr_poly
					(pts
						(arc
							(start -0.3302 0.4318)
							(mid -0.402042 0.402042)
							(end -0.4318 0.3302)
						)
						(arc
							(start -0.4318 -0.3302)
							(mid -0.402042 -0.402042)
							(end -0.3302 -0.4318)
						)
						(arc
							(start 0.3302 -0.4318)
							(mid 0.402042 -0.402042)
							(end 0.4318 -0.3302)
						)
						(arc
							(start 0.4318 0.3302)
							(mid 0.402042 0.402042)
							(end 0.3302 0.4318)
						)
					)
					(width 0)
					(fill yes)
				)
			)
		)
		(pad "2" smd custom
			(at 0 0.762 90)
			(size 0.2159 0.2159)
			(layers "B.Cu" "B.Mask" "B.Paste")
			(net "P5V_VDD")
			(options
				(clearance outline)
				(anchor circle)
			)
			(primitives
				(gr_poly
					(pts
						(arc
							(start -0.3302 0.4318)
							(mid -0.402042 0.402042)
							(end -0.4318 0.3302)
						)
						(arc
							(start -0.4318 -0.3302)
							(mid -0.402042 -0.402042)
							(end -0.3302 -0.4318)
						)
						(arc
							(start 0.3302 -0.4318)
							(mid 0.402042 -0.402042)
							(end 0.4318 -0.3302)
						)
						(arc
							(start 0.4318 0.3302)
							(mid 0.402042 0.402042)
							(end 0.3302 0.4318)
						)
					)
					(width 0)
					(fill yes)
				)
			)
		)
	)
	(footprint ""
		(layer "B.Cu")
		(at 13.2207 -147.3835 -90)
		(property "Reference" "C62"
			(at 0 0 90)
			(layer "B.SilkS")
			(hide yes)
			(effects
				(font
					(size 1.27 1.27)
				)
				(justify mirror)
			)
		)
		(property "Value" "SC1U16V3KX-5GP"
			(at 0 -2.8194 270)
			(unlocked yes)
			(layer "B.Fab")
			(hide yes)
			(effects
				(font
					(size 1.016 1.016)
					(thickness 0.1524)
				)
				(justify mirror)
			)
		)
		(property "Device Type" "C603H36"
			(at 0 -4.3434 270)
			(unlocked yes)
			(layer "B.Fab")
			(hide yes)
			(effects
				(font
					(size 1.016 1.016)
					(thickness 0.1524)
				)
				(justify mirror)
			)
		)
		(duplicate_pad_numbers_are_jumpers no)
		(fp_line
			(start -0.508 0)
			(end 0.508 0)
			(stroke
				(width 0.2032)
				(type default)
			)
			(layer "B.SilkS")
		)
		(fp_rect
			(start 0.5842 1.3335)
			(end -0.5842 -1.3335)
			(stroke
				(width 0)
				(type default)
			)
			(fill no)
			(layer "B.CrtYd")
		)
		(fp_rect
			(start 0.5842 1.3335)
			(end -0.5842 -1.3335)
			(stroke
				(width 0)
				(type default)
			)
			(fill no)
			(layer "B.Fab")
		)
		(pad "1" smd custom
			(at 0 -0.762 90)
			(size 0.2159 0.2159)
			(layers "B.Cu" "B.Mask" "B.Paste")
			(net "P1V2_STBY")
			(options
				(clearance outline)
				(anchor circle)
			)
			(primitives
				(gr_poly
					(pts
						(arc
							(start -0.3302 0.4318)
							(mid -0.402042 0.402042)
							(end -0.4318 0.3302)
						)
						(arc
							(start -0.4318 -0.3302)
							(mid -0.402042 -0.402042)
							(end -0.3302 -0.4318)
						)
						(arc
							(start 0.3302 -0.4318)
							(mid 0.402042 -0.402042)
							(end 0.4318 -0.3302)
						)
						(arc
							(start 0.4318 0.3302)
							(mid 0.402042 0.402042)
							(end 0.3302 0.4318)
						)
					)
					(width 0)
					(fill yes)
				)
			)
		)
		(pad "2" smd custom
			(at 0 0.762 90)
			(size 0.2159 0.2159)
			(layers "B.Cu" "B.Mask" "B.Paste")
			(net "GND")
			(options
				(clearance outline)
				(anchor circle)
			)
			(primitives
				(gr_poly
					(pts
						(arc
							(start -0.3302 0.4318)
							(mid -0.402042 0.402042)
							(end -0.4318 0.3302)
						)
						(arc
							(start -0.4318 -0.3302)
							(mid -0.402042 -0.402042)
							(end -0.3302 -0.4318)
						)
						(arc
							(start 0.3302 -0.4318)
							(mid 0.402042 -0.402042)
							(end 0.4318 -0.3302)
						)
						(arc
							(start 0.4318 0.3302)
							(mid 0.402042 0.402042)
							(end 0.3302 0.4318)
						)
					)
					(width 0)
					(fill yes)
				)
			)
		)
	)
	(footprint ""
		(layer "B.Cu")
		(at 44.5008 -140.97)
		(property "Reference" "TP28"
			(at 0 0 0)
			(layer "B.SilkS")
			(hide yes)
			(effects
				(font
					(size 1.27 1.27)
				)
				(justify mirror)
			)
		)
		(property "Value" "TPAD28-2-GP"
			(at 0.0127 -1.6637 0)
			(unlocked yes)
			(layer "B.Fab")
			(hide yes)
			(effects
				(font
					(size 1.016 1.016)
					(thickness 0.1524)
				)
				(justify mirror)
			)
		)
		(property "Device Type" "TPAD28"
			(at 0.0127 -3.1877 0)
			(unlocked yes)
			(layer "B.Fab")
			(hide yes)
			(effects
				(font
					(size 1.016 1.016)
					(thickness 0.1524)
				)
				(justify mirror)
			)
		)
		(duplicate_pad_numbers_are_jumpers no)
		(fp_poly
			(pts
				(arc
					(start 0.3556 0)
					(mid -0.3556 0)
					(end 0.3556 0)
				)
			)
			(stroke
				(width 0)
				(type default)
			)
			(fill no)
			(layer "B.CrtYd")
		)
		(fp_poly
			(pts
				(arc
					(start 0.6096 0)
					(mid -0.6096 0)
					(end 0.6096 0)
				)
			)
			(stroke
				(width 0)
				(type default)
			)
			(fill no)
			(layer "B.Fab")
		)
		(pad "1" smd circle
			(at 0 0 180)
			(size 0.7112 0.7112)
			(layers "B.Cu" "B.Mask" "B.Paste")
			(net "TP_BMC_GPIOR2")
		)
	)
	(footprint ""
		(layer "B.Cu")
		(at 204.93355 -107.29341)
		(property "Reference" "C631"
			(at 0 0 0)
			(layer "B.SilkS")
			(hide yes)
			(effects
				(font
					(size 1.27 1.27)
				)
				(justify mirror)
			)
		)
		(property "Value" "SCD1U16V2KX-3GP"
			(at -1.1811 -2.7051 0)
			(unlocked yes)
			(layer "B.Fab")
			(hide yes)
			(effects
				(font
					(size 1.016 1.016)
					(thickness 0.1524)
				)
				(justify mirror)
			)
		)
		(property "Device Type" "C402H22"
			(at -1.1811 -4.2291 0)
			(unlocked yes)
			(layer "B.Fab")
			(hide yes)
			(effects
				(font
					(size 1.016 1.016)
					(thickness 0.1524)
				)
				(justify mirror)
			)
		)
		(duplicate_pad_numbers_are_jumpers no)
		(fp_rect
			(start 0.4318 0.9525)
			(end -0.4318 -0.9525)
			(stroke
				(width 0)
				(type default)
			)
			(fill no)
			(layer "B.CrtYd")
		)
		(fp_rect
			(start 0.4318 0.9525)
			(end -0.4318 -0.9525)
			(stroke
				(width 0)
				(type default)
			)
			(fill no)
			(layer "B.Fab")
		)
		(pad "1" smd custom
			(at 0 -0.4445 180)
			(size 0.1524 0.1524)
			(layers "B.Cu" "B.Mask" "B.Paste")
			(net "P1V8_STBY")
			(options
				(clearance outline)
				(anchor circle)
			)
			(primitives
				(gr_poly
					(pts
						(arc
							(start 0.3048 0.2032)
							(mid 0.275042 0.275042)
							(end 0.2032 0.3048)
						)
						(arc
							(start -0.2032 0.3048)
							(mid -0.275042 0.275042)
							(end -0.3048 0.2032)
						)
						(arc
							(start -0.3048 -0.2032)
							(mid -0.275042 -0.275042)
							(end -0.2032 -0.3048)
						)
						(arc
							(start 0.2032 -0.3048)
							(mid 0.275042 -0.275042)
							(end 0.3048 -0.2032)
						)
					)
					(width 0)
					(fill yes)
				)
			)
		)
		(pad "2" smd custom
			(at 0 0.4445 180)
			(size 0.1524 0.1524)
			(layers "B.Cu" "B.Mask" "B.Paste")
			(net "GND")
			(options
				(clearance outline)
				(anchor circle)
			)
			(primitives
				(gr_poly
					(pts
						(arc
							(start 0.3048 0.2032)
							(mid 0.275042 0.275042)
							(end 0.2032 0.3048)
						)
						(arc
							(start -0.2032 0.3048)
							(mid -0.275042 0.275042)
							(end -0.3048 0.2032)
						)
						(arc
							(start -0.3048 -0.2032)
							(mid -0.275042 -0.275042)
							(end -0.2032 -0.3048)
						)
						(arc
							(start 0.2032 -0.3048)
							(mid 0.275042 -0.275042)
							(end 0.3048 -0.2032)
						)
					)
					(width 0)
					(fill yes)
				)
			)
		)
	)
	(footprint ""
		(layer "B.Cu")
		(at 41.3258 -125.476 180)
		(property "Reference" "R362"
			(at 0 0 0)
			(layer "B.SilkS")
			(hide yes)
			(effects
				(font
					(size 1.27 1.27)
				)
				(justify mirror)
			)
		)
		(property "Value" "4K7R2F-GP"
			(at -0.064008 -3.993896 180)
			(unlocked yes)
			(layer "B.Fab")
			(hide yes)
			(effects
				(font
					(size 1.016 1.016)
					(thickness 0.1524)
				)
				(justify mirror)
			)
		)
		(property "Device Type" "R402H16"
			(at -0.064008 -5.517896 180)
			(unlocked yes)
			(layer "B.Fab")
			(hide yes)
			(effects
				(font
					(size 1.016 1.016)
					(thickness 0.1524)
				)
				(justify mirror)
			)
		)
		(duplicate_pad_numbers_are_jumpers no)
		(fp_line
			(start 0.508 -0.9398)
			(end 0.508 0.9398)
			(stroke
				(width 0.1524)
				(type default)
			)
			(layer "B.SilkS")
		)
		(fp_line
			(start -0.508 -0.9398)
			(end 0.508 -0.9398)
			(stroke
				(width 0.1524)
				(type default)
			)
			(layer "B.SilkS")
		)
		(fp_rect
			(start 0.508 0.9398)
			(end -0.508 -0.9398)
			(stroke
				(width 0)
				(type default)
			)
			(fill no)
			(layer "B.CrtYd")
		)
		(fp_rect
			(start 0.508 0.9398)
			(end -0.508 -0.9398)
			(stroke
				(width 0)
				(type default)
			)
			(fill no)
			(layer "B.Fab")
		)
		(pad "1" smd custom
			(at 0 -0.4445)
			(size 0.1397 0.1397)
			(layers "B.Cu" "B.Mask" "B.Paste")
			(net "P3V3_STBY")
			(options
				(clearance outline)
				(anchor circle)
			)
			(primitives
				(gr_poly
					(pts
						(arc
							(start -0.1778 0.2794)
							(mid -0.249642 0.249642)
							(end -0.2794 0.1778)
						)
						(arc
							(start -0.2794 -0.1778)
							(mid -0.249642 -0.249642)
							(end -0.1778 -0.2794)
						)
						(arc
							(start 0.1778 -0.2794)
							(mid 0.249642 -0.249642)
							(end 0.2794 -0.1778)
						)
						(arc
							(start 0.2794 0.1778)
							(mid 0.249642 0.249642)
							(end 0.1778 0.2794)
						)
					)
					(width 0)
					(fill yes)
				)
			)
		)
		(pad "2" smd custom
			(at 0 0.4445)
			(size 0.1397 0.1397)
			(layers "B.Cu" "B.Mask" "B.Paste")
			(net "FM_BMC_RESET_N")
			(options
				(clearance outline)
				(anchor circle)
			)
			(primitives
				(gr_poly
					(pts
						(arc
							(start -0.1778 0.2794)
							(mid -0.249642 0.249642)
							(end -0.2794 0.1778)
						)
						(arc
							(start -0.2794 -0.1778)
							(mid -0.249642 -0.249642)
							(end -0.1778 -0.2794)
						)
						(arc
							(start 0.1778 -0.2794)
							(mid 0.249642 -0.249642)
							(end 0.2794 -0.1778)
						)
						(arc
							(start 0.2794 0.1778)
							(mid 0.249642 0.249642)
							(end 0.1778 0.2794)
						)
					)
					(width 0)
					(fill yes)
				)
			)
		)
	)
	(footprint ""
		(layer "B.Cu")
		(at 90.853006 -137.207752 -90)
		(property "Reference" "C504"
			(at 0 0 90)
			(layer "B.SilkS")
			(hide yes)
			(effects
				(font
					(size 1.27 1.27)
				)
				(justify mirror)
			)
		)
		(property "Value" "SCD1U16V2KX-3GP"
			(at -1.1811 -2.7051 270)
			(unlocked yes)
			(layer "B.Fab")
			(hide yes)
			(effects
				(font
					(size 1.016 1.016)
					(thickness 0.1524)
				)
				(justify mirror)
			)
		)
		(property "Device Type" "C402H22"
			(at -1.1811 -4.2291 270)
			(unlocked yes)
			(layer "B.Fab")
			(hide yes)
			(effects
				(font
					(size 1.016 1.016)
					(thickness 0.1524)
				)
				(justify mirror)
			)
		)
		(duplicate_pad_numbers_are_jumpers no)
		(fp_rect
			(start 0.4318 0.9525)
			(end -0.4318 -0.9525)
			(stroke
				(width 0)
				(type default)
			)
			(fill no)
			(layer "B.CrtYd")
		)
		(fp_rect
			(start 0.4318 0.9525)
			(end -0.4318 -0.9525)
			(stroke
				(width 0)
				(type default)
			)
			(fill no)
			(layer "B.Fab")
		)
		(pad "1" smd custom
			(at 0 -0.4445 90)
			(size 0.1524 0.1524)
			(layers "B.Cu" "B.Mask" "B.Paste")
			(net "P3V3_STBY")
			(options
				(clearance outline)
				(anchor circle)
			)
			(primitives
				(gr_poly
					(pts
						(arc
							(start 0.3048 0.2032)
							(mid 0.275042 0.275042)
							(end 0.2032 0.3048)
						)
						(arc
							(start -0.2032 0.3048)
							(mid -0.275042 0.275042)
							(end -0.3048 0.2032)
						)
						(arc
							(start -0.3048 -0.2032)
							(mid -0.275042 -0.275042)
							(end -0.2032 -0.3048)
						)
						(arc
							(start 0.2032 -0.3048)
							(mid 0.275042 -0.275042)
							(end 0.3048 -0.2032)
						)
					)
					(width 0)
					(fill yes)
				)
			)
		)
		(pad "2" smd custom
			(at 0 0.4445 90)
			(size 0.1524 0.1524)
			(layers "B.Cu" "B.Mask" "B.Paste")
			(net "GND")
			(options
				(clearance outline)
				(anchor circle)
			)
			(primitives
				(gr_poly
					(pts
						(arc
							(start 0.3048 0.2032)
							(mid 0.275042 0.275042)
							(end 0.2032 0.3048)
						)
						(arc
							(start -0.2032 0.3048)
							(mid -0.275042 0.275042)
							(end -0.3048 0.2032)
						)
						(arc
							(start -0.3048 -0.2032)
							(mid -0.275042 -0.275042)
							(end -0.2032 -0.3048)
						)
						(arc
							(start 0.2032 -0.3048)
							(mid 0.275042 -0.275042)
							(end 0.3048 -0.2032)
						)
					)
					(width 0)
					(fill yes)
				)
			)
		)
	)
	(footprint ""
		(layer "B.Cu")
		(at 30.897322 -156.547058 180)
		(property "Reference" "R782"
			(at 0 0 0)
			(layer "B.SilkS")
			(hide yes)
			(effects
				(font
					(size 1.27 1.27)
				)
				(justify mirror)
			)
		)
		(property "Value" "4K7R2F-GP"
			(at -0.064008 -3.993896 180)
			(unlocked yes)
			(layer "B.Fab")
			(hide yes)
			(effects
				(font
					(size 1.016 1.016)
					(thickness 0.1524)
				)
				(justify mirror)
			)
		)
		(property "Device Type" "R402H16"
			(at -0.064008 -5.517896 180)
			(unlocked yes)
			(layer "B.Fab")
			(hide yes)
			(effects
				(font
					(size 1.016 1.016)
					(thickness 0.1524)
				)
				(justify mirror)
			)
		)
		(duplicate_pad_numbers_are_jumpers no)
		(fp_line
			(start 0.508 -0.9398)
			(end 0.508 0.9398)
			(stroke
				(width 0.1524)
				(type default)
			)
			(layer "B.SilkS")
		)
		(fp_line
			(start -0.508 -0.9398)
			(end 0.508 -0.9398)
			(stroke
				(width 0.1524)
				(type default)
			)
			(layer "B.SilkS")
		)
		(fp_rect
			(start 0.508 0.9398)
			(end -0.508 -0.9398)
			(stroke
				(width 0)
				(type default)
			)
			(fill no)
			(layer "B.CrtYd")
		)
		(fp_rect
			(start 0.508 0.9398)
			(end -0.508 -0.9398)
			(stroke
				(width 0)
				(type default)
			)
			(fill no)
			(layer "B.Fab")
		)
		(pad "1" smd custom
			(at 0 -0.4445)
			(size 0.1397 0.1397)
			(layers "B.Cu" "B.Mask" "B.Paste")
			(net "COMP_FAST_THROTTLE_N")
			(options
				(clearance outline)
				(anchor circle)
			)
			(primitives
				(gr_poly
					(pts
						(arc
							(start -0.1778 0.2794)
							(mid -0.249642 0.249642)
							(end -0.2794 0.1778)
						)
						(arc
							(start -0.2794 -0.1778)
							(mid -0.249642 -0.249642)
							(end -0.1778 -0.2794)
						)
						(arc
							(start 0.1778 -0.2794)
							(mid 0.249642 -0.249642)
							(end 0.2794 -0.1778)
						)
						(arc
							(start 0.2794 0.1778)
							(mid 0.249642 0.249642)
							(end 0.1778 0.2794)
						)
					)
					(width 0)
					(fill yes)
				)
			)
		)
		(pad "2" smd custom
			(at 0 0.4445)
			(size 0.1397 0.1397)
			(layers "B.Cu" "B.Mask" "B.Paste")
			(net "GND")
			(options
				(clearance outline)
				(anchor circle)
			)
			(primitives
				(gr_poly
					(pts
						(arc
							(start -0.1778 0.2794)
							(mid -0.249642 0.249642)
							(end -0.2794 0.1778)
						)
						(arc
							(start -0.2794 -0.1778)
							(mid -0.249642 -0.249642)
							(end -0.1778 -0.2794)
						)
						(arc
							(start 0.1778 -0.2794)
							(mid 0.249642 -0.249642)
							(end 0.2794 -0.1778)
						)
						(arc
							(start 0.2794 0.1778)
							(mid 0.249642 0.249642)
							(end 0.1778 0.2794)
						)
					)
					(width 0)
					(fill yes)
				)
			)
		)
	)
	(footprint ""
		(layer "B.Cu")
		(at 172.071538 -120.580658)
		(property "Reference" "C617"
			(at 0 0 0)
			(layer "B.SilkS")
			(hide yes)
			(effects
				(font
					(size 1.27 1.27)
				)
				(justify mirror)
			)
		)
		(property "Value" "SC10U6D3V5KX-4GP"
			(at 0.0762 -6.1214 0)
			(unlocked yes)
			(layer "B.Fab")
			(hide yes)
			(effects
				(font
					(size 1.016 1.016)
					(thickness 0.1524)
				)
				(justify mirror)
			)
		)
		(property "Device Type" "C805H58"
			(at 0.0762 -8.1534 0)
			(unlocked yes)
			(layer "B.Fab")
			(hide yes)
			(effects
				(font
					(size 1.016 1.016)
					(thickness 0.1524)
				)
				(justify mirror)
			)
		)
		(duplicate_pad_numbers_are_jumpers no)
		(fp_line
			(start -0.635 0)
			(end 0.635 0)
			(stroke
				(width 0.508)
				(type default)
			)
			(layer "B.SilkS")
		)
		(fp_rect
			(start 0.9652 1.778)
			(end -0.9652 -1.778)
			(stroke
				(width 0)
				(type default)
			)
			(fill no)
			(layer "B.CrtYd")
		)
		(fp_poly
			(pts
				(xy 0.9652 -1.778) (xy -0.9652 -1.778) (xy -0.9652 1.778) (xy 0.9652 1.778)
			)
			(stroke
				(width 0)
				(type default)
			)
			(fill no)
			(layer "B.Fab")
		)
		(pad "1" smd rect
			(at 0 -0.9652 180)
			(size 1.397 1.143)
			(layers "B.Cu" "B.Mask" "B.Paste")
			(net "P3V3_M2")
		)
		(pad "2" smd rect
			(at 0 0.9652 180)
			(size 1.397 1.143)
			(layers "B.Cu" "B.Mask" "B.Paste")
			(net "GND")
		)
	)
	(footprint ""
		(layer "B.Cu")
		(at 50.938684 -127.383286 -90)
		(property "Reference" "R294"
			(at 0 0 90)
			(layer "B.SilkS")
			(hide yes)
			(effects
				(font
					(size 1.27 1.27)
				)
				(justify mirror)
			)
		)
		(property "Value" "0R2J-2-GP"
			(at -0.064008 -3.993896 270)
			(unlocked yes)
			(layer "B.Fab")
			(hide yes)
			(effects
				(font
					(size 1.016 1.016)
					(thickness 0.1524)
				)
				(justify mirror)
			)
		)
		(property "Device Type" "R402H16"
			(at -0.064008 -5.517896 270)
			(unlocked yes)
			(layer "B.Fab")
			(hide yes)
			(effects
				(font
					(size 1.016 1.016)
					(thickness 0.1524)
				)
				(justify mirror)
			)
		)
		(duplicate_pad_numbers_are_jumpers no)
		(fp_line
			(start -0.508 -0.9398)
			(end 0.508 -0.9398)
			(stroke
				(width 0.1524)
				(type default)
			)
			(layer "B.SilkS")
		)
		(fp_line
			(start 0.508 -0.9398)
			(end 0.508 0.9398)
			(stroke
				(width 0.1524)
				(type default)
			)
			(layer "B.SilkS")
		)
		(fp_rect
			(start 0.508 0.9398)
			(end -0.508 -0.9398)
			(stroke
				(width 0)
				(type default)
			)
			(fill no)
			(layer "B.CrtYd")
		)
		(fp_rect
			(start 0.508 0.9398)
			(end -0.508 -0.9398)
			(stroke
				(width 0)
				(type default)
			)
			(fill no)
			(layer "B.Fab")
		)
		(pad "1" smd custom
			(at 0 -0.4445 90)
			(size 0.1397 0.1397)
			(layers "B.Cu" "B.Mask" "B.Paste")
			(net "P12V_A_PGOOD")
			(options
				(clearance outline)
				(anchor circle)
			)
			(primitives
				(gr_poly
					(pts
						(arc
							(start -0.1778 0.2794)
							(mid -0.249642 0.249642)
							(end -0.2794 0.1778)
						)
						(arc
							(start -0.2794 -0.1778)
							(mid -0.249642 -0.249642)
							(end -0.1778 -0.2794)
						)
						(arc
							(start 0.1778 -0.2794)
							(mid 0.249642 -0.249642)
							(end 0.2794 -0.1778)
						)
						(arc
							(start 0.2794 0.1778)
							(mid 0.249642 0.249642)
							(end 0.1778 0.2794)
						)
					)
					(width 0)
					(fill yes)
				)
			)
		)
		(pad "2" smd custom
			(at 0 0.4445 90)
			(size 0.1397 0.1397)
			(layers "B.Cu" "B.Mask" "B.Paste")
			(net "P12V_A_PGOOD_R")
			(options
				(clearance outline)
				(anchor circle)
			)
			(primitives
				(gr_poly
					(pts
						(arc
							(start -0.1778 0.2794)
							(mid -0.249642 0.249642)
							(end -0.2794 0.1778)
						)
						(arc
							(start -0.2794 -0.1778)
							(mid -0.249642 -0.249642)
							(end -0.1778 -0.2794)
						)
						(arc
							(start 0.1778 -0.2794)
							(mid 0.249642 -0.249642)
							(end 0.2794 -0.1778)
						)
						(arc
							(start 0.2794 0.1778)
							(mid 0.249642 0.249642)
							(end 0.1778 0.2794)
						)
					)
					(width 0)
					(fill yes)
				)
			)
		)
	)
	(footprint ""
		(layer "B.Cu")
		(at 17.723612 -131.007358 180)
		(property "Reference" "R241"
			(at 0 0 0)
			(layer "B.SilkS")
			(hide yes)
			(effects
				(font
					(size 1.27 1.27)
				)
				(justify mirror)
			)
		)
		(property "Value" "120R2F-GP"
			(at -0.064008 -3.993896 180)
			(unlocked yes)
			(layer "B.Fab")
			(hide yes)
			(effects
				(font
					(size 1.016 1.016)
					(thickness 0.1524)
				)
				(justify mirror)
			)
		)
		(property "Device Type" "R402H16"
			(at -0.064008 -5.517896 180)
			(unlocked yes)
			(layer "B.Fab")
			(hide yes)
			(effects
				(font
					(size 1.016 1.016)
					(thickness 0.1524)
				)
				(justify mirror)
			)
		)
		(duplicate_pad_numbers_are_jumpers no)
		(fp_line
			(start 0.508 -0.9398)
			(end 0.508 0.9398)
			(stroke
				(width 0.1524)
				(type default)
			)
			(layer "B.SilkS")
		)
		(fp_line
			(start -0.508 -0.9398)
			(end 0.508 -0.9398)
			(stroke
				(width 0.1524)
				(type default)
			)
			(layer "B.SilkS")
		)
		(fp_rect
			(start 0.508 0.9398)
			(end -0.508 -0.9398)
			(stroke
				(width 0)
				(type default)
			)
			(fill no)
			(layer "B.CrtYd")
		)
		(fp_rect
			(start 0.508 0.9398)
			(end -0.508 -0.9398)
			(stroke
				(width 0)
				(type default)
			)
			(fill no)
			(layer "B.Fab")
		)
		(pad "1" smd custom
			(at 0 -0.4445)
			(size 0.1397 0.1397)
			(layers "B.Cu" "B.Mask" "B.Paste")
			(net "MEMA_3")
			(options
				(clearance outline)
				(anchor circle)
			)
			(primitives
				(gr_poly
					(pts
						(arc
							(start -0.1778 0.2794)
							(mid -0.249642 0.249642)
							(end -0.2794 0.1778)
						)
						(arc
							(start -0.2794 -0.1778)
							(mid -0.249642 -0.249642)
							(end -0.1778 -0.2794)
						)
						(arc
							(start 0.1778 -0.2794)
							(mid 0.249642 -0.249642)
							(end 0.2794 -0.1778)
						)
						(arc
							(start 0.2794 0.1778)
							(mid 0.249642 0.249642)
							(end 0.1778 0.2794)
						)
					)
					(width 0)
					(fill yes)
				)
			)
		)
		(pad "2" smd custom
			(at 0 0.4445)
			(size 0.1397 0.1397)
			(layers "B.Cu" "B.Mask" "B.Paste")
			(net "P1V2_STBY")
			(options
				(clearance outline)
				(anchor circle)
			)
			(primitives
				(gr_poly
					(pts
						(arc
							(start -0.1778 0.2794)
							(mid -0.249642 0.249642)
							(end -0.2794 0.1778)
						)
						(arc
							(start -0.2794 -0.1778)
							(mid -0.249642 -0.249642)
							(end -0.1778 -0.2794)
						)
						(arc
							(start 0.1778 -0.2794)
							(mid 0.249642 -0.249642)
							(end 0.2794 -0.1778)
						)
						(arc
							(start 0.2794 0.1778)
							(mid 0.249642 0.249642)
							(end 0.1778 0.2794)
						)
					)
					(width 0)
					(fill yes)
				)
			)
		)
	)
	(footprint ""
		(layer "B.Cu")
		(at 63.6778 -138.0744 90)
		(property "Reference" "R186"
			(at 0 0 90)
			(layer "B.SilkS")
			(hide yes)
			(effects
				(font
					(size 1.27 1.27)
				)
				(justify mirror)
			)
		)
		(property "Value" "2K2R2F-GP"
			(at -0.064008 -3.993896 90)
			(unlocked yes)
			(layer "B.Fab")
			(hide yes)
			(effects
				(font
					(size 1.016 1.016)
					(thickness 0.1524)
				)
				(justify mirror)
			)
		)
		(property "Device Type" "R402H16"
			(at -0.064008 -5.517896 90)
			(unlocked yes)
			(layer "B.Fab")
			(hide yes)
			(effects
				(font
					(size 1.016 1.016)
					(thickness 0.1524)
				)
				(justify mirror)
			)
		)
		(duplicate_pad_numbers_are_jumpers no)
		(fp_line
			(start 0.508 -0.9398)
			(end 0.508 0.9398)
			(stroke
				(width 0.1524)
				(type default)
			)
			(layer "B.SilkS")
		)
		(fp_line
			(start -0.508 -0.9398)
			(end 0.508 -0.9398)
			(stroke
				(width 0.1524)
				(type default)
			)
			(layer "B.SilkS")
		)
		(fp_rect
			(start 0.508 0.9398)
			(end -0.508 -0.9398)
			(stroke
				(width 0)
				(type default)
			)
			(fill no)
			(layer "B.CrtYd")
		)
		(fp_rect
			(start 0.508 0.9398)
			(end -0.508 -0.9398)
			(stroke
				(width 0)
				(type default)
			)
			(fill no)
			(layer "B.Fab")
		)
		(pad "1" smd custom
			(at 0 -0.4445 270)
			(size 0.1397 0.1397)
			(layers "B.Cu" "B.Mask" "B.Paste")
			(net "I2C_M2_2_SDA")
			(options
				(clearance outline)
				(anchor circle)
			)
			(primitives
				(gr_poly
					(pts
						(arc
							(start -0.1778 0.2794)
							(mid -0.249642 0.249642)
							(end -0.2794 0.1778)
						)
						(arc
							(start -0.2794 -0.1778)
							(mid -0.249642 -0.249642)
							(end -0.1778 -0.2794)
						)
						(arc
							(start 0.1778 -0.2794)
							(mid 0.249642 -0.249642)
							(end 0.2794 -0.1778)
						)
						(arc
							(start 0.2794 0.1778)
							(mid 0.249642 0.249642)
							(end 0.1778 0.2794)
						)
					)
					(width 0)
					(fill yes)
				)
			)
		)
		(pad "2" smd custom
			(at 0 0.4445 270)
			(size 0.1397 0.1397)
			(layers "B.Cu" "B.Mask" "B.Paste")
			(net "P3V3_STBY")
			(options
				(clearance outline)
				(anchor circle)
			)
			(primitives
				(gr_poly
					(pts
						(arc
							(start -0.1778 0.2794)
							(mid -0.249642 0.249642)
							(end -0.2794 0.1778)
						)
						(arc
							(start -0.2794 -0.1778)
							(mid -0.249642 -0.249642)
							(end -0.1778 -0.2794)
						)
						(arc
							(start 0.1778 -0.2794)
							(mid 0.249642 -0.249642)
							(end 0.2794 -0.1778)
						)
						(arc
							(start 0.2794 0.1778)
							(mid 0.249642 0.249642)
							(end 0.1778 0.2794)
						)
					)
					(width 0)
					(fill yes)
				)
			)
		)
	)
	(footprint ""
		(layer "B.Cu")
		(at 209.325464 -84.021676)
		(property "Reference" "Q20"
			(at 0 0 0)
			(layer "B.SilkS")
			(hide yes)
			(effects
				(font
					(size 1.27 1.27)
				)
				(justify mirror)
			)
		)
		(property "Value" "2N7002K-1-GP"
			(at -0.127 -8.9662 0)
			(unlocked yes)
			(layer "B.Fab")
			(hide yes)
			(effects
				(font
					(size 1.016 1.016)
					(thickness 0.1524)
				)
				(justify mirror)
			)
		)
		(property "Device Type" "SOT23DGS2D4H44"
			(at -0.127 -10.4902 0)
			(unlocked yes)
			(layer "B.Fab")
			(hide yes)
			(effects
				(font
					(size 1.016 1.016)
					(thickness 0.1524)
				)
				(justify mirror)
			)
		)
		(duplicate_pad_numbers_are_jumpers no)
		(fp_line
			(start -1.651 -1.778)
			(end 1.651 -1.778)
			(stroke
				(width 0.1524)
				(type default)
			)
			(layer "B.SilkS")
		)
		(fp_line
			(start -1.651 1.778)
			(end -1.651 -1.778)
			(stroke
				(width 0.1524)
				(type default)
			)
			(layer "B.SilkS")
		)
		(fp_line
			(start 1.651 -1.778)
			(end 1.651 1.778)
			(stroke
				(width 0.1524)
				(type default)
			)
			(layer "B.SilkS")
		)
		(fp_line
			(start 1.651 1.778)
			(end -1.651 1.778)
			(stroke
				(width 0.1524)
				(type default)
			)
			(layer "B.SilkS")
		)
		(fp_poly
			(pts
				(xy 1.778 1.8796) (xy 1.778 -1.8796) (xy -1.778 -1.8796) (xy -1.778 1.8796)
			)
			(stroke
				(width 0)
				(type default)
			)
			(fill no)
			(layer "B.CrtYd")
		)
		(fp_poly
			(pts
				(xy 1.778 1.8796) (xy 1.778 -1.8796) (xy -1.778 -1.8796) (xy -1.778 1.8796)
			)
			(stroke
				(width 0)
				(type default)
			)
			(fill no)
			(layer "B.Fab")
		)
		(pad "D" smd custom
			(at 0 -0.9525 180)
			(size 0.1905 0.1905)
			(layers "B.Cu" "B.Mask" "B.Paste")
			(net "Q21_G")
			(options
				(clearance outline)
				(anchor circle)
			)
			(primitives
				(gr_poly
					(pts
						(arc
							(start -0.1778 -0.5715)
							(mid -0.321484 -0.511984)
							(end -0.381 -0.3683)
						)
						(arc
							(start -0.381 0.3683)
							(mid -0.321484 0.511984)
							(end -0.1778 0.5715)
						)
						(arc
							(start 0.1778 0.5715)
							(mid 0.321484 0.511984)
							(end 0.381 0.3683)
						)
						(arc
							(start 0.381 -0.3683)
							(mid 0.321484 -0.511984)
							(end 0.1778 -0.5715)
						)
					)
					(width 0)
					(fill yes)
				)
			)
		)
		(pad "G" smd custom
			(at 0.98425 0.9525 180)
			(size 0.1905 0.1905)
			(layers "B.Cu" "B.Mask" "B.Paste")
			(net "Q20_G")
			(options
				(clearance outline)
				(anchor circle)
			)
			(primitives
				(gr_poly
					(pts
						(arc
							(start -0.1778 -0.5715)
							(mid -0.321484 -0.511984)
							(end -0.381 -0.3683)
						)
						(arc
							(start -0.381 0.3683)
							(mid -0.321484 0.511984)
							(end -0.1778 0.5715)
						)
						(arc
							(start 0.1778 0.5715)
							(mid 0.321484 0.511984)
							(end 0.381 0.3683)
						)
						(arc
							(start 0.381 -0.3683)
							(mid 0.321484 -0.511984)
							(end 0.1778 -0.5715)
						)
					)
					(width 0)
					(fill yes)
				)
			)
		)
		(pad "S" smd custom
			(at -0.98425 0.9525 180)
			(size 0.1905 0.1905)
			(layers "B.Cu" "B.Mask" "B.Paste")
			(net "GND")
			(options
				(clearance outline)
				(anchor circle)
			)
			(primitives
				(gr_poly
					(pts
						(arc
							(start -0.1778 -0.5715)
							(mid -0.321484 -0.511984)
							(end -0.381 -0.3683)
						)
						(arc
							(start -0.381 0.3683)
							(mid -0.321484 0.511984)
							(end -0.1778 0.5715)
						)
						(arc
							(start 0.1778 0.5715)
							(mid 0.321484 0.511984)
							(end 0.381 0.3683)
						)
						(arc
							(start 0.381 -0.3683)
							(mid 0.321484 -0.511984)
							(end 0.1778 -0.5715)
						)
					)
					(width 0)
					(fill yes)
				)
			)
		)
	)
	(footprint ""
		(layer "B.Cu")
		(at 41.284398 -127.978916)
		(property "Reference" "R314"
			(at 0 0 0)
			(layer "B.SilkS")
			(hide yes)
			(effects
				(font
					(size 1.27 1.27)
				)
				(justify mirror)
			)
		)
		(property "Value" "0R2J-2-GP"
			(at -0.064008 -3.993896 0)
			(unlocked yes)
			(layer "B.Fab")
			(hide yes)
			(effects
				(font
					(size 1.016 1.016)
					(thickness 0.1524)
				)
				(justify mirror)
			)
		)
		(property "Device Type" "R402H16"
			(at -0.064008 -5.517896 0)
			(unlocked yes)
			(layer "B.Fab")
			(hide yes)
			(effects
				(font
					(size 1.016 1.016)
					(thickness 0.1524)
				)
				(justify mirror)
			)
		)
		(duplicate_pad_numbers_are_jumpers no)
		(fp_line
			(start -0.508 -0.9398)
			(end 0.508 -0.9398)
			(stroke
				(width 0.1524)
				(type default)
			)
			(layer "B.SilkS")
		)
		(fp_line
			(start 0.508 -0.9398)
			(end 0.508 0.9398)
			(stroke
				(width 0.1524)
				(type default)
			)
			(layer "B.SilkS")
		)
		(fp_rect
			(start 0.508 0.9398)
			(end -0.508 -0.9398)
			(stroke
				(width 0)
				(type default)
			)
			(fill no)
			(layer "B.CrtYd")
		)
		(fp_rect
			(start 0.508 0.9398)
			(end -0.508 -0.9398)
			(stroke
				(width 0)
				(type default)
			)
			(fill no)
			(layer "B.Fab")
		)
		(pad "1" smd custom
			(at 0 -0.4445 180)
			(size 0.1397 0.1397)
			(layers "B.Cu" "B.Mask" "B.Paste")
			(net "BMC_EXTRST_N")
			(options
				(clearance outline)
				(anchor circle)
			)
			(primitives
				(gr_poly
					(pts
						(arc
							(start -0.1778 0.2794)
							(mid -0.249642 0.249642)
							(end -0.2794 0.1778)
						)
						(arc
							(start -0.2794 -0.1778)
							(mid -0.249642 -0.249642)
							(end -0.1778 -0.2794)
						)
						(arc
							(start 0.1778 -0.2794)
							(mid 0.249642 -0.249642)
							(end 0.2794 -0.1778)
						)
						(arc
							(start 0.2794 0.1778)
							(mid 0.249642 0.249642)
							(end 0.1778 0.2794)
						)
					)
					(width 0)
					(fill yes)
				)
			)
		)
		(pad "2" smd custom
			(at 0 0.4445 180)
			(size 0.1397 0.1397)
			(layers "B.Cu" "B.Mask" "B.Paste")
			(net "RST_BMC_EXTRST_N")
			(options
				(clearance outline)
				(anchor circle)
			)
			(primitives
				(gr_poly
					(pts
						(arc
							(start -0.1778 0.2794)
							(mid -0.249642 0.249642)
							(end -0.2794 0.1778)
						)
						(arc
							(start -0.2794 -0.1778)
							(mid -0.249642 -0.249642)
							(end -0.1778 -0.2794)
						)
						(arc
							(start 0.1778 -0.2794)
							(mid 0.249642 -0.249642)
							(end 0.2794 -0.1778)
						)
						(arc
							(start 0.2794 0.1778)
							(mid 0.249642 0.249642)
							(end 0.1778 0.2794)
						)
					)
					(width 0)
					(fill yes)
				)
			)
		)
	)
	(footprint ""
		(layer "B.Cu")
		(at 55.309262 -134.134352 90)
		(property "Reference" "R784"
			(at 0 0 90)
			(layer "B.SilkS")
			(hide yes)
			(effects
				(font
					(size 1.27 1.27)
				)
				(justify mirror)
			)
		)
		(property "Value" "10KR2F-2-GP"
			(at -0.064008 -3.993896 90)
			(unlocked yes)
			(layer "B.Fab")
			(hide yes)
			(effects
				(font
					(size 1.016 1.016)
					(thickness 0.1524)
				)
				(justify mirror)
			)
		)
		(property "Device Type" "R402H16"
			(at -0.064008 -5.517896 90)
			(unlocked yes)
			(layer "B.Fab")
			(hide yes)
			(effects
				(font
					(size 1.016 1.016)
					(thickness 0.1524)
				)
				(justify mirror)
			)
		)
		(duplicate_pad_numbers_are_jumpers no)
		(fp_line
			(start 0.508 -0.9398)
			(end 0.508 0.9398)
			(stroke
				(width 0.1524)
				(type default)
			)
			(layer "B.SilkS")
		)
		(fp_line
			(start -0.508 -0.9398)
			(end 0.508 -0.9398)
			(stroke
				(width 0.1524)
				(type default)
			)
			(layer "B.SilkS")
		)
		(fp_rect
			(start 0.508 0.9398)
			(end -0.508 -0.9398)
			(stroke
				(width 0)
				(type default)
			)
			(fill no)
			(layer "B.CrtYd")
		)
		(fp_rect
			(start 0.508 0.9398)
			(end -0.508 -0.9398)
			(stroke
				(width 0)
				(type default)
			)
			(fill no)
			(layer "B.Fab")
		)
		(pad "1" smd custom
			(at 0 -0.4445 270)
			(size 0.1397 0.1397)
			(layers "B.Cu" "B.Mask" "B.Paste")
			(net "P3V3_STBY")
			(options
				(clearance outline)
				(anchor circle)
			)
			(primitives
				(gr_poly
					(pts
						(arc
							(start -0.1778 0.2794)
							(mid -0.249642 0.249642)
							(end -0.2794 0.1778)
						)
						(arc
							(start -0.2794 -0.1778)
							(mid -0.249642 -0.249642)
							(end -0.1778 -0.2794)
						)
						(arc
							(start 0.1778 -0.2794)
							(mid 0.249642 -0.249642)
							(end 0.2794 -0.1778)
						)
						(arc
							(start 0.2794 0.1778)
							(mid 0.249642 0.249642)
							(end 0.1778 0.2794)
						)
					)
					(width 0)
					(fill yes)
				)
			)
		)
		(pad "2" smd custom
			(at 0 0.4445 270)
			(size 0.1397 0.1397)
			(layers "B.Cu" "B.Mask" "B.Paste")
			(net "COMP_PWR_BTN_N")
			(options
				(clearance outline)
				(anchor circle)
			)
			(primitives
				(gr_poly
					(pts
						(arc
							(start -0.1778 0.2794)
							(mid -0.249642 0.249642)
							(end -0.2794 0.1778)
						)
						(arc
							(start -0.2794 -0.1778)
							(mid -0.249642 -0.249642)
							(end -0.1778 -0.2794)
						)
						(arc
							(start 0.1778 -0.2794)
							(mid 0.249642 -0.249642)
							(end 0.2794 -0.1778)
						)
						(arc
							(start 0.2794 0.1778)
							(mid 0.249642 0.249642)
							(end 0.1778 0.2794)
						)
					)
					(width 0)
					(fill yes)
				)
			)
		)
	)
	(footprint ""
		(layer "B.Cu")
		(at 125.861572 -10.822178 -90)
		(property "Reference" "R437"
			(at 0 0 90)
			(layer "B.SilkS")
			(hide yes)
			(effects
				(font
					(size 1.27 1.27)
				)
				(justify mirror)
			)
		)
		(property "Value" "100KR2F-L1-GP"
			(at -0.064008 -3.993896 270)
			(unlocked yes)
			(layer "B.Fab")
			(hide yes)
			(effects
				(font
					(size 1.016 1.016)
					(thickness 0.1524)
				)
				(justify mirror)
			)
		)
		(property "Device Type" "R402H16"
			(at -0.064008 -5.517896 270)
			(unlocked yes)
			(layer "B.Fab")
			(hide yes)
			(effects
				(font
					(size 1.016 1.016)
					(thickness 0.1524)
				)
				(justify mirror)
			)
		)
		(duplicate_pad_numbers_are_jumpers no)
		(fp_line
			(start -0.508 -0.9398)
			(end 0.508 -0.9398)
			(stroke
				(width 0.1524)
				(type default)
			)
			(layer "B.SilkS")
		)
		(fp_line
			(start 0.508 -0.9398)
			(end 0.508 0.9398)
			(stroke
				(width 0.1524)
				(type default)
			)
			(layer "B.SilkS")
		)
		(fp_rect
			(start 0.508 0.9398)
			(end -0.508 -0.9398)
			(stroke
				(width 0)
				(type default)
			)
			(fill no)
			(layer "B.CrtYd")
		)
		(fp_rect
			(start 0.508 0.9398)
			(end -0.508 -0.9398)
			(stroke
				(width 0)
				(type default)
			)
			(fill no)
			(layer "B.Fab")
		)
		(pad "1" smd custom
			(at 0 -0.4445 90)
			(size 0.1397 0.1397)
			(layers "B.Cu" "B.Mask" "B.Paste")
			(net "P12V_STBY")
			(options
				(clearance outline)
				(anchor circle)
			)
			(primitives
				(gr_poly
					(pts
						(arc
							(start -0.1778 0.2794)
							(mid -0.249642 0.249642)
							(end -0.2794 0.1778)
						)
						(arc
							(start -0.2794 -0.1778)
							(mid -0.249642 -0.249642)
							(end -0.1778 -0.2794)
						)
						(arc
							(start 0.1778 -0.2794)
							(mid 0.249642 -0.249642)
							(end 0.2794 -0.1778)
						)
						(arc
							(start 0.2794 0.1778)
							(mid 0.249642 0.249642)
							(end 0.1778 0.2794)
						)
					)
					(width 0)
					(fill yes)
				)
			)
		)
		(pad "2" smd custom
			(at 0 0.4445 90)
			(size 0.1397 0.1397)
			(layers "B.Cu" "B.Mask" "B.Paste")
			(net "MB0_P12V_PWGIN_R")
			(options
				(clearance outline)
				(anchor circle)
			)
			(primitives
				(gr_poly
					(pts
						(arc
							(start -0.1778 0.2794)
							(mid -0.249642 0.249642)
							(end -0.2794 0.1778)
						)
						(arc
							(start -0.2794 -0.1778)
							(mid -0.249642 -0.249642)
							(end -0.1778 -0.2794)
						)
						(arc
							(start 0.1778 -0.2794)
							(mid 0.249642 -0.249642)
							(end 0.2794 -0.1778)
						)
						(arc
							(start 0.2794 0.1778)
							(mid 0.249642 0.249642)
							(end 0.1778 0.2794)
						)
					)
					(width 0)
					(fill yes)
				)
			)
		)
	)
	(footprint ""
		(layer "B.Cu")
		(at 60.01004 -134.410958)
		(property "Reference" "TP206"
			(at 0 0 0)
			(layer "B.SilkS")
			(hide yes)
			(effects
				(font
					(size 1.27 1.27)
				)
				(justify mirror)
			)
		)
		(property "Value" "TPAD28-2-GP"
			(at 0.0127 -1.6637 0)
			(unlocked yes)
			(layer "B.Fab")
			(hide yes)
			(effects
				(font
					(size 1.016 1.016)
					(thickness 0.1524)
				)
				(justify mirror)
			)
		)
		(property "Device Type" "TPAD28"
			(at 0.0127 -3.1877 0)
			(unlocked yes)
			(layer "B.Fab")
			(hide yes)
			(effects
				(font
					(size 1.016 1.016)
					(thickness 0.1524)
				)
				(justify mirror)
			)
		)
		(duplicate_pad_numbers_are_jumpers no)
		(fp_poly
			(pts
				(arc
					(start 0.3556 0)
					(mid -0.3556 0)
					(end 0.3556 0)
				)
			)
			(stroke
				(width 0)
				(type default)
			)
			(fill no)
			(layer "B.CrtYd")
		)
		(fp_poly
			(pts
				(arc
					(start 0.6096 0)
					(mid -0.6096 0)
					(end 0.6096 0)
				)
			)
			(stroke
				(width 0)
				(type default)
			)
			(fill no)
			(layer "B.Fab")
		)
		(pad "1" smd circle
			(at 0 0 180)
			(size 0.7112 0.7112)
			(layers "B.Cu" "B.Mask" "B.Paste")
			(net "TP_BMC_EXT1_LED_G")
		)
	)
	(footprint ""
		(layer "B.Cu")
		(at 12.091924 -135.285988 90)
		(property "Reference" "R257"
			(at 0 0 90)
			(layer "B.SilkS")
			(hide yes)
			(effects
				(font
					(size 1.27 1.27)
				)
				(justify mirror)
			)
		)
		(property "Value" "120R2F-GP"
			(at -0.064008 -3.993896 90)
			(unlocked yes)
			(layer "B.Fab")
			(hide yes)
			(effects
				(font
					(size 1.016 1.016)
					(thickness 0.1524)
				)
				(justify mirror)
			)
		)
		(property "Device Type" "R402H16"
			(at -0.064008 -5.517896 90)
			(unlocked yes)
			(layer "B.Fab")
			(hide yes)
			(effects
				(font
					(size 1.016 1.016)
					(thickness 0.1524)
				)
				(justify mirror)
			)
		)
		(duplicate_pad_numbers_are_jumpers no)
		(fp_line
			(start 0.508 -0.9398)
			(end 0.508 0.9398)
			(stroke
				(width 0.1524)
				(type default)
			)
			(layer "B.SilkS")
		)
		(fp_line
			(start -0.508 -0.9398)
			(end 0.508 -0.9398)
			(stroke
				(width 0.1524)
				(type default)
			)
			(layer "B.SilkS")
		)
		(fp_rect
			(start 0.508 0.9398)
			(end -0.508 -0.9398)
			(stroke
				(width 0)
				(type default)
			)
			(fill no)
			(layer "B.CrtYd")
		)
		(fp_rect
			(start 0.508 0.9398)
			(end -0.508 -0.9398)
			(stroke
				(width 0)
				(type default)
			)
			(fill no)
			(layer "B.Fab")
		)
		(pad "1" smd custom
			(at 0 -0.4445 270)
			(size 0.1397 0.1397)
			(layers "B.Cu" "B.Mask" "B.Paste")
			(net "MEMA_11")
			(options
				(clearance outline)
				(anchor circle)
			)
			(primitives
				(gr_poly
					(pts
						(arc
							(start -0.1778 0.2794)
							(mid -0.249642 0.249642)
							(end -0.2794 0.1778)
						)
						(arc
							(start -0.2794 -0.1778)
							(mid -0.249642 -0.249642)
							(end -0.1778 -0.2794)
						)
						(arc
							(start 0.1778 -0.2794)
							(mid 0.249642 -0.249642)
							(end 0.2794 -0.1778)
						)
						(arc
							(start 0.2794 0.1778)
							(mid 0.249642 0.249642)
							(end 0.1778 0.2794)
						)
					)
					(width 0)
					(fill yes)
				)
			)
		)
		(pad "2" smd custom
			(at 0 0.4445 270)
			(size 0.1397 0.1397)
			(layers "B.Cu" "B.Mask" "B.Paste")
			(net "P1V2_STBY")
			(options
				(clearance outline)
				(anchor circle)
			)
			(primitives
				(gr_poly
					(pts
						(arc
							(start -0.1778 0.2794)
							(mid -0.249642 0.249642)
							(end -0.2794 0.1778)
						)
						(arc
							(start -0.2794 -0.1778)
							(mid -0.249642 -0.249642)
							(end -0.1778 -0.2794)
						)
						(arc
							(start 0.1778 -0.2794)
							(mid 0.249642 -0.249642)
							(end 0.2794 -0.1778)
						)
						(arc
							(start 0.2794 0.1778)
							(mid 0.249642 0.249642)
							(end 0.1778 0.2794)
						)
					)
					(width 0)
					(fill yes)
				)
			)
		)
	)
	(footprint ""
		(layer "B.Cu")
		(at 51.03114 -142.61846 180)
		(property "Reference" "R357"
			(at 0 0 0)
			(layer "B.SilkS")
			(hide yes)
			(effects
				(font
					(size 1.27 1.27)
				)
				(justify mirror)
			)
		)
		(property "Value" "4K7R2F-GP"
			(at -0.064008 -3.993896 180)
			(unlocked yes)
			(layer "B.Fab")
			(hide yes)
			(effects
				(font
					(size 1.016 1.016)
					(thickness 0.1524)
				)
				(justify mirror)
			)
		)
		(property "Device Type" "R402H16"
			(at -0.064008 -5.517896 180)
			(unlocked yes)
			(layer "B.Fab")
			(hide yes)
			(effects
				(font
					(size 1.016 1.016)
					(thickness 0.1524)
				)
				(justify mirror)
			)
		)
		(duplicate_pad_numbers_are_jumpers no)
		(fp_line
			(start 0.508 -0.9398)
			(end 0.508 0.9398)
			(stroke
				(width 0.1524)
				(type default)
			)
			(layer "B.SilkS")
		)
		(fp_line
			(start -0.508 -0.9398)
			(end 0.508 -0.9398)
			(stroke
				(width 0.1524)
				(type default)
			)
			(layer "B.SilkS")
		)
		(fp_rect
			(start 0.508 0.9398)
			(end -0.508 -0.9398)
			(stroke
				(width 0)
				(type default)
			)
			(fill no)
			(layer "B.CrtYd")
		)
		(fp_rect
			(start 0.508 0.9398)
			(end -0.508 -0.9398)
			(stroke
				(width 0)
				(type default)
			)
			(fill no)
			(layer "B.Fab")
		)
		(pad "1" smd custom
			(at 0 -0.4445)
			(size 0.1397 0.1397)
			(layers "B.Cu" "B.Mask" "B.Paste")
			(net "P3V3_STBY")
			(options
				(clearance outline)
				(anchor circle)
			)
			(primitives
				(gr_poly
					(pts
						(arc
							(start -0.1778 0.2794)
							(mid -0.249642 0.249642)
							(end -0.2794 0.1778)
						)
						(arc
							(start -0.2794 -0.1778)
							(mid -0.249642 -0.249642)
							(end -0.1778 -0.2794)
						)
						(arc
							(start 0.1778 -0.2794)
							(mid 0.249642 -0.249642)
							(end 0.2794 -0.1778)
						)
						(arc
							(start 0.2794 0.1778)
							(mid 0.249642 0.249642)
							(end 0.1778 0.2794)
						)
					)
					(width 0)
					(fill yes)
				)
			)
		)
		(pad "2" smd custom
			(at 0 0.4445)
			(size 0.1397 0.1397)
			(layers "B.Cu" "B.Mask" "B.Paste")
			(net "JTAG_BMC_TRST_N")
			(options
				(clearance outline)
				(anchor circle)
			)
			(primitives
				(gr_poly
					(pts
						(arc
							(start -0.1778 0.2794)
							(mid -0.249642 0.249642)
							(end -0.2794 0.1778)
						)
						(arc
							(start -0.2794 -0.1778)
							(mid -0.249642 -0.249642)
							(end -0.1778 -0.2794)
						)
						(arc
							(start 0.1778 -0.2794)
							(mid 0.249642 -0.249642)
							(end 0.2794 -0.1778)
						)
						(arc
							(start 0.2794 0.1778)
							(mid 0.249642 0.249642)
							(end 0.1778 0.2794)
						)
					)
					(width 0)
					(fill yes)
				)
			)
		)
	)
	(footprint ""
		(layer "B.Cu")
		(at 86.520274 -98.697796 180)
		(property "Reference" "Q25"
			(at 0 0 0)
			(layer "B.SilkS")
			(hide yes)
			(effects
				(font
					(size 1.27 1.27)
				)
				(justify mirror)
			)
		)
		(property "Value" "2N7002K-1-GP"
			(at -0.127 -8.9662 180)
			(unlocked yes)
			(layer "B.Fab")
			(hide yes)
			(effects
				(font
					(size 1.016 1.016)
					(thickness 0.1524)
				)
				(justify mirror)
			)
		)
		(property "Device Type" "SOT23DGS2D4H44"
			(at -0.127 -10.4902 180)
			(unlocked yes)
			(layer "B.Fab")
			(hide yes)
			(effects
				(font
					(size 1.016 1.016)
					(thickness 0.1524)
				)
				(justify mirror)
			)
		)
		(duplicate_pad_numbers_are_jumpers no)
		(fp_line
			(start 1.651 1.778)
			(end -1.651 1.778)
			(stroke
				(width 0.1524)
				(type default)
			)
			(layer "B.SilkS")
		)
		(fp_line
			(start 1.651 -1.778)
			(end 1.651 1.778)
			(stroke
				(width 0.1524)
				(type default)
			)
			(layer "B.SilkS")
		)
		(fp_line
			(start -1.651 1.778)
			(end -1.651 -1.778)
			(stroke
				(width 0.1524)
				(type default)
			)
			(layer "B.SilkS")
		)
		(fp_line
			(start -1.651 -1.778)
			(end 1.651 -1.778)
			(stroke
				(width 0.1524)
				(type default)
			)
			(layer "B.SilkS")
		)
		(fp_poly
			(pts
				(xy 1.778 1.8796) (xy 1.778 -1.8796) (xy -1.778 -1.8796) (xy -1.778 1.8796)
			)
			(stroke
				(width 0)
				(type default)
			)
			(fill no)
			(layer "B.CrtYd")
		)
		(fp_poly
			(pts
				(xy 1.778 1.8796) (xy 1.778 -1.8796) (xy -1.778 -1.8796) (xy -1.778 1.8796)
			)
			(stroke
				(width 0)
				(type default)
			)
			(fill no)
			(layer "B.Fab")
		)
		(pad "D" smd custom
			(at 0 -0.9525)
			(size 0.1905 0.1905)
			(layers "B.Cu" "B.Mask" "B.Paste")
			(net "CONN_A_PRSNTA")
			(options
				(clearance outline)
				(anchor circle)
			)
			(primitives
				(gr_poly
					(pts
						(arc
							(start -0.1778 -0.5715)
							(mid -0.321484 -0.511984)
							(end -0.381 -0.3683)
						)
						(arc
							(start -0.381 0.3683)
							(mid -0.321484 0.511984)
							(end -0.1778 0.5715)
						)
						(arc
							(start 0.1778 0.5715)
							(mid 0.321484 0.511984)
							(end 0.381 0.3683)
						)
						(arc
							(start 0.381 -0.3683)
							(mid 0.321484 -0.511984)
							(end 0.1778 -0.5715)
						)
					)
					(width 0)
					(fill yes)
				)
			)
		)
		(pad "G" smd custom
			(at 0.98425 0.9525)
			(size 0.1905 0.1905)
			(layers "B.Cu" "B.Mask" "B.Paste")
			(net "MEZZ_A_PRSNT_120_N")
			(options
				(clearance outline)
				(anchor circle)
			)
			(primitives
				(gr_poly
					(pts
						(arc
							(start -0.1778 -0.5715)
							(mid -0.321484 -0.511984)
							(end -0.381 -0.3683)
						)
						(arc
							(start -0.381 0.3683)
							(mid -0.321484 0.511984)
							(end -0.1778 0.5715)
						)
						(arc
							(start 0.1778 0.5715)
							(mid 0.321484 0.511984)
							(end 0.381 0.3683)
						)
						(arc
							(start 0.381 -0.3683)
							(mid 0.321484 -0.511984)
							(end 0.1778 -0.5715)
						)
					)
					(width 0)
					(fill yes)
				)
			)
		)
		(pad "S" smd custom
			(at -0.98425 0.9525)
			(size 0.1905 0.1905)
			(layers "B.Cu" "B.Mask" "B.Paste")
			(net "GND")
			(options
				(clearance outline)
				(anchor circle)
			)
			(primitives
				(gr_poly
					(pts
						(arc
							(start -0.1778 -0.5715)
							(mid -0.321484 -0.511984)
							(end -0.381 -0.3683)
						)
						(arc
							(start -0.381 0.3683)
							(mid -0.321484 0.511984)
							(end -0.1778 0.5715)
						)
						(arc
							(start 0.1778 0.5715)
							(mid 0.321484 0.511984)
							(end 0.381 0.3683)
						)
						(arc
							(start 0.381 -0.3683)
							(mid 0.321484 -0.511984)
							(end 0.1778 -0.5715)
						)
					)
					(width 0)
					(fill yes)
				)
			)
		)
	)
	(footprint ""
		(layer "B.Cu")
		(at 52.2478 -161.1376 -90)
		(property "Reference" "C627"
			(at 0 0 90)
			(layer "B.SilkS")
			(hide yes)
			(effects
				(font
					(size 1.27 1.27)
				)
				(justify mirror)
			)
		)
		(property "Value" "SCD1U25V2KX-2-GP"
			(at -1.1811 -2.7051 270)
			(unlocked yes)
			(layer "B.Fab")
			(hide yes)
			(effects
				(font
					(size 1.016 1.016)
					(thickness 0.1524)
				)
				(justify mirror)
			)
		)
		(property "Device Type" "C402H22"
			(at -1.1811 -4.2291 270)
			(unlocked yes)
			(layer "B.Fab")
			(hide yes)
			(effects
				(font
					(size 1.016 1.016)
					(thickness 0.1524)
				)
				(justify mirror)
			)
		)
		(duplicate_pad_numbers_are_jumpers no)
		(fp_rect
			(start 0.4318 0.9525)
			(end -0.4318 -0.9525)
			(stroke
				(width 0)
				(type default)
			)
			(fill no)
			(layer "B.CrtYd")
		)
		(fp_rect
			(start 0.4318 0.9525)
			(end -0.4318 -0.9525)
			(stroke
				(width 0)
				(type default)
			)
			(fill no)
			(layer "B.Fab")
		)
		(pad "1" smd custom
			(at 0 -0.4445 90)
			(size 0.1524 0.1524)
			(layers "B.Cu" "B.Mask" "B.Paste")
			(net "ADC_P3V3_M2")
			(options
				(clearance outline)
				(anchor circle)
			)
			(primitives
				(gr_poly
					(pts
						(arc
							(start 0.3048 0.2032)
							(mid 0.275042 0.275042)
							(end 0.2032 0.3048)
						)
						(arc
							(start -0.2032 0.3048)
							(mid -0.275042 0.275042)
							(end -0.3048 0.2032)
						)
						(arc
							(start -0.3048 -0.2032)
							(mid -0.275042 -0.275042)
							(end -0.2032 -0.3048)
						)
						(arc
							(start 0.2032 -0.3048)
							(mid 0.275042 -0.275042)
							(end 0.3048 -0.2032)
						)
					)
					(width 0)
					(fill yes)
				)
			)
		)
		(pad "2" smd custom
			(at 0 0.4445 90)
			(size 0.1524 0.1524)
			(layers "B.Cu" "B.Mask" "B.Paste")
			(net "GND")
			(options
				(clearance outline)
				(anchor circle)
			)
			(primitives
				(gr_poly
					(pts
						(arc
							(start 0.3048 0.2032)
							(mid 0.275042 0.275042)
							(end 0.2032 0.3048)
						)
						(arc
							(start -0.2032 0.3048)
							(mid -0.275042 0.275042)
							(end -0.3048 0.2032)
						)
						(arc
							(start -0.3048 -0.2032)
							(mid -0.275042 -0.275042)
							(end -0.2032 -0.3048)
						)
						(arc
							(start 0.2032 -0.3048)
							(mid 0.275042 -0.275042)
							(end 0.3048 -0.2032)
						)
					)
					(width 0)
					(fill yes)
				)
			)
		)
	)
	(footprint ""
		(layer "B.Cu")
		(at 174.9552 -126.113286 90)
		(property "Reference" "C623"
			(at 0 0 90)
			(layer "B.SilkS")
			(hide yes)
			(effects
				(font
					(size 1.27 1.27)
				)
				(justify mirror)
			)
		)
		(property "Value" "SCD1U16V2KX-3GP"
			(at -1.1811 -2.7051 90)
			(unlocked yes)
			(layer "B.Fab")
			(hide yes)
			(effects
				(font
					(size 1.016 1.016)
					(thickness 0.1524)
				)
				(justify mirror)
			)
		)
		(property "Device Type" "C402H22"
			(at -1.1811 -4.2291 90)
			(unlocked yes)
			(layer "B.Fab")
			(hide yes)
			(effects
				(font
					(size 1.016 1.016)
					(thickness 0.1524)
				)
				(justify mirror)
			)
		)
		(duplicate_pad_numbers_are_jumpers no)
		(fp_rect
			(start 0.4318 0.9525)
			(end -0.4318 -0.9525)
			(stroke
				(width 0)
				(type default)
			)
			(fill no)
			(layer "B.CrtYd")
		)
		(fp_rect
			(start 0.4318 0.9525)
			(end -0.4318 -0.9525)
			(stroke
				(width 0)
				(type default)
			)
			(fill no)
			(layer "B.Fab")
		)
		(pad "1" smd custom
			(at 0 -0.4445 270)
			(size 0.1524 0.1524)
			(layers "B.Cu" "B.Mask" "B.Paste")
			(net "P3V3_M2")
			(options
				(clearance outline)
				(anchor circle)
			)
			(primitives
				(gr_poly
					(pts
						(arc
							(start 0.3048 0.2032)
							(mid 0.275042 0.275042)
							(end 0.2032 0.3048)
						)
						(arc
							(start -0.2032 0.3048)
							(mid -0.275042 0.275042)
							(end -0.3048 0.2032)
						)
						(arc
							(start -0.3048 -0.2032)
							(mid -0.275042 -0.275042)
							(end -0.2032 -0.3048)
						)
						(arc
							(start 0.2032 -0.3048)
							(mid 0.275042 -0.275042)
							(end 0.3048 -0.2032)
						)
					)
					(width 0)
					(fill yes)
				)
			)
		)
		(pad "2" smd custom
			(at 0 0.4445 270)
			(size 0.1524 0.1524)
			(layers "B.Cu" "B.Mask" "B.Paste")
			(net "GND")
			(options
				(clearance outline)
				(anchor circle)
			)
			(primitives
				(gr_poly
					(pts
						(arc
							(start 0.3048 0.2032)
							(mid 0.275042 0.275042)
							(end 0.2032 0.3048)
						)
						(arc
							(start -0.2032 0.3048)
							(mid -0.275042 0.275042)
							(end -0.3048 0.2032)
						)
						(arc
							(start -0.3048 -0.2032)
							(mid -0.275042 -0.275042)
							(end -0.2032 -0.3048)
						)
						(arc
							(start 0.2032 -0.3048)
							(mid 0.275042 -0.275042)
							(end 0.3048 -0.2032)
						)
					)
					(width 0)
					(fill yes)
				)
			)
		)
	)
	(footprint ""
		(layer "B.Cu")
		(at 194.425062 -133.83895 180)
		(property "Reference" "C605"
			(at 0 0 0)
			(layer "B.SilkS")
			(hide yes)
			(effects
				(font
					(size 1.27 1.27)
				)
				(justify mirror)
			)
		)
		(property "Value" "SCD1U16V2KX-3GP"
			(at -1.1811 -2.7051 180)
			(unlocked yes)
			(layer "B.Fab")
			(hide yes)
			(effects
				(font
					(size 1.016 1.016)
					(thickness 0.1524)
				)
				(justify mirror)
			)
		)
		(property "Device Type" "C402H22"
			(at -1.1811 -4.2291 180)
			(unlocked yes)
			(layer "B.Fab")
			(hide yes)
			(effects
				(font
					(size 1.016 1.016)
					(thickness 0.1524)
				)
				(justify mirror)
			)
		)
		(duplicate_pad_numbers_are_jumpers no)
		(fp_rect
			(start 0.4318 0.9525)
			(end -0.4318 -0.9525)
			(stroke
				(width 0)
				(type default)
			)
			(fill no)
			(layer "B.CrtYd")
		)
		(fp_rect
			(start 0.4318 0.9525)
			(end -0.4318 -0.9525)
			(stroke
				(width 0)
				(type default)
			)
			(fill no)
			(layer "B.Fab")
		)
		(pad "1" smd custom
			(at 0 -0.4445)
			(size 0.1524 0.1524)
			(layers "B.Cu" "B.Mask" "B.Paste")
			(net "P3V3_M2")
			(options
				(clearance outline)
				(anchor circle)
			)
			(primitives
				(gr_poly
					(pts
						(arc
							(start 0.3048 0.2032)
							(mid 0.275042 0.275042)
							(end 0.2032 0.3048)
						)
						(arc
							(start -0.2032 0.3048)
							(mid -0.275042 0.275042)
							(end -0.3048 0.2032)
						)
						(arc
							(start -0.3048 -0.2032)
							(mid -0.275042 -0.275042)
							(end -0.2032 -0.3048)
						)
						(arc
							(start 0.2032 -0.3048)
							(mid 0.275042 -0.275042)
							(end 0.3048 -0.2032)
						)
					)
					(width 0)
					(fill yes)
				)
			)
		)
		(pad "2" smd custom
			(at 0 0.4445)
			(size 0.1524 0.1524)
			(layers "B.Cu" "B.Mask" "B.Paste")
			(net "GND")
			(options
				(clearance outline)
				(anchor circle)
			)
			(primitives
				(gr_poly
					(pts
						(arc
							(start 0.3048 0.2032)
							(mid 0.275042 0.275042)
							(end 0.2032 0.3048)
						)
						(arc
							(start -0.2032 0.3048)
							(mid -0.275042 0.275042)
							(end -0.3048 0.2032)
						)
						(arc
							(start -0.3048 -0.2032)
							(mid -0.275042 -0.275042)
							(end -0.2032 -0.3048)
						)
						(arc
							(start 0.2032 -0.3048)
							(mid 0.275042 -0.275042)
							(end 0.3048 -0.2032)
						)
					)
					(width 0)
					(fill yes)
				)
			)
		)
	)
	(footprint ""
		(layer "B.Cu")
		(at 170.035728 -122.580908 -90)
		(property "Reference" "C641"
			(at 0 0 90)
			(layer "B.SilkS")
			(hide yes)
			(effects
				(font
					(size 1.27 1.27)
				)
				(justify mirror)
			)
		)
		(property "Value" "SCD1U16V2KX-3GP"
			(at -1.1811 -2.7051 270)
			(unlocked yes)
			(layer "B.Fab")
			(hide yes)
			(effects
				(font
					(size 1.016 1.016)
					(thickness 0.1524)
				)
				(justify mirror)
			)
		)
		(property "Device Type" "C402H22"
			(at -1.1811 -4.2291 270)
			(unlocked yes)
			(layer "B.Fab")
			(hide yes)
			(effects
				(font
					(size 1.016 1.016)
					(thickness 0.1524)
				)
				(justify mirror)
			)
		)
		(duplicate_pad_numbers_are_jumpers no)
		(fp_rect
			(start 0.4318 0.9525)
			(end -0.4318 -0.9525)
			(stroke
				(width 0)
				(type default)
			)
			(fill no)
			(layer "B.CrtYd")
		)
		(fp_rect
			(start 0.4318 0.9525)
			(end -0.4318 -0.9525)
			(stroke
				(width 0)
				(type default)
			)
			(fill no)
			(layer "B.Fab")
		)
		(pad "1" smd custom
			(at 0 -0.4445 90)
			(size 0.1524 0.1524)
			(layers "B.Cu" "B.Mask" "B.Paste")
			(net "P3V3_M2")
			(options
				(clearance outline)
				(anchor circle)
			)
			(primitives
				(gr_poly
					(pts
						(arc
							(start 0.3048 0.2032)
							(mid 0.275042 0.275042)
							(end 0.2032 0.3048)
						)
						(arc
							(start -0.2032 0.3048)
							(mid -0.275042 0.275042)
							(end -0.3048 0.2032)
						)
						(arc
							(start -0.3048 -0.2032)
							(mid -0.275042 -0.275042)
							(end -0.2032 -0.3048)
						)
						(arc
							(start 0.2032 -0.3048)
							(mid 0.275042 -0.275042)
							(end 0.3048 -0.2032)
						)
					)
					(width 0)
					(fill yes)
				)
			)
		)
		(pad "2" smd custom
			(at 0 0.4445 90)
			(size 0.1524 0.1524)
			(layers "B.Cu" "B.Mask" "B.Paste")
			(net "GND")
			(options
				(clearance outline)
				(anchor circle)
			)
			(primitives
				(gr_poly
					(pts
						(arc
							(start 0.3048 0.2032)
							(mid 0.275042 0.275042)
							(end 0.2032 0.3048)
						)
						(arc
							(start -0.2032 0.3048)
							(mid -0.275042 0.275042)
							(end -0.3048 0.2032)
						)
						(arc
							(start -0.3048 -0.2032)
							(mid -0.275042 -0.275042)
							(end -0.2032 -0.3048)
						)
						(arc
							(start 0.2032 -0.3048)
							(mid 0.275042 -0.275042)
							(end 0.3048 -0.2032)
						)
					)
					(width 0)
					(fill yes)
				)
			)
		)
	)
	(footprint ""
		(layer "B.Cu")
		(at 51.0794 -122.682 -90)
		(property "Reference" "R341"
			(at 0 0 90)
			(layer "B.SilkS")
			(hide yes)
			(effects
				(font
					(size 1.27 1.27)
				)
				(justify mirror)
			)
		)
		(property "Value" "4K7R2F-GP"
			(at -0.064008 -3.993896 270)
			(unlocked yes)
			(layer "B.Fab")
			(hide yes)
			(effects
				(font
					(size 1.016 1.016)
					(thickness 0.1524)
				)
				(justify mirror)
			)
		)
		(property "Device Type" "R402H16"
			(at -0.064008 -5.517896 270)
			(unlocked yes)
			(layer "B.Fab")
			(hide yes)
			(effects
				(font
					(size 1.016 1.016)
					(thickness 0.1524)
				)
				(justify mirror)
			)
		)
		(duplicate_pad_numbers_are_jumpers no)
		(fp_line
			(start -0.508 -0.9398)
			(end 0.508 -0.9398)
			(stroke
				(width 0.1524)
				(type default)
			)
			(layer "B.SilkS")
		)
		(fp_line
			(start 0.508 -0.9398)
			(end 0.508 0.9398)
			(stroke
				(width 0.1524)
				(type default)
			)
			(layer "B.SilkS")
		)
		(fp_rect
			(start 0.508 0.9398)
			(end -0.508 -0.9398)
			(stroke
				(width 0)
				(type default)
			)
			(fill no)
			(layer "B.CrtYd")
		)
		(fp_rect
			(start 0.508 0.9398)
			(end -0.508 -0.9398)
			(stroke
				(width 0)
				(type default)
			)
			(fill no)
			(layer "B.Fab")
		)
		(pad "1" smd custom
			(at 0 -0.4445 90)
			(size 0.1397 0.1397)
			(layers "B.Cu" "B.Mask" "B.Paste")
			(net "TEMP_3_A2")
			(options
				(clearance outline)
				(anchor circle)
			)
			(primitives
				(gr_poly
					(pts
						(arc
							(start -0.1778 0.2794)
							(mid -0.249642 0.249642)
							(end -0.2794 0.1778)
						)
						(arc
							(start -0.2794 -0.1778)
							(mid -0.249642 -0.249642)
							(end -0.1778 -0.2794)
						)
						(arc
							(start 0.1778 -0.2794)
							(mid 0.249642 -0.249642)
							(end 0.2794 -0.1778)
						)
						(arc
							(start 0.2794 0.1778)
							(mid 0.249642 0.249642)
							(end 0.1778 0.2794)
						)
					)
					(width 0)
					(fill yes)
				)
			)
		)
		(pad "2" smd custom
			(at 0 0.4445 90)
			(size 0.1397 0.1397)
			(layers "B.Cu" "B.Mask" "B.Paste")
			(net "GND")
			(options
				(clearance outline)
				(anchor circle)
			)
			(primitives
				(gr_poly
					(pts
						(arc
							(start -0.1778 0.2794)
							(mid -0.249642 0.249642)
							(end -0.2794 0.1778)
						)
						(arc
							(start -0.2794 -0.1778)
							(mid -0.249642 -0.249642)
							(end -0.1778 -0.2794)
						)
						(arc
							(start 0.1778 -0.2794)
							(mid 0.249642 -0.249642)
							(end 0.2794 -0.1778)
						)
						(arc
							(start 0.2794 0.1778)
							(mid 0.249642 0.249642)
							(end 0.1778 0.2794)
						)
					)
					(width 0)
					(fill yes)
				)
			)
		)
	)
	(footprint ""
		(layer "B.Cu")
		(at 128.651 -14.351)
		(property "Reference" "C145"
			(at 0 0 0)
			(layer "B.SilkS")
			(hide yes)
			(effects
				(font
					(size 1.27 1.27)
				)
				(justify mirror)
			)
		)
		(property "Value" "SC1U16V3KX-5GP"
			(at 0 -2.8194 0)
			(unlocked yes)
			(layer "B.Fab")
			(hide yes)
			(effects
				(font
					(size 1.016 1.016)
					(thickness 0.1524)
				)
				(justify mirror)
			)
		)
		(property "Device Type" "C603H36"
			(at 0 -4.3434 0)
			(unlocked yes)
			(layer "B.Fab")
			(hide yes)
			(effects
				(font
					(size 1.016 1.016)
					(thickness 0.1524)
				)
				(justify mirror)
			)
		)
		(duplicate_pad_numbers_are_jumpers no)
		(fp_line
			(start -0.508 0)
			(end 0.508 0)
			(stroke
				(width 0.2032)
				(type default)
			)
			(layer "B.SilkS")
		)
		(fp_rect
			(start 0.5842 1.3335)
			(end -0.5842 -1.3335)
			(stroke
				(width 0)
				(type default)
			)
			(fill no)
			(layer "B.CrtYd")
		)
		(fp_rect
			(start 0.5842 1.3335)
			(end -0.5842 -1.3335)
			(stroke
				(width 0)
				(type default)
			)
			(fill no)
			(layer "B.Fab")
		)
		(pad "1" smd custom
			(at 0 -0.762 180)
			(size 0.2159 0.2159)
			(layers "B.Cu" "B.Mask" "B.Paste")
			(net "MB0_CM_UV_R")
			(options
				(clearance outline)
				(anchor circle)
			)
			(primitives
				(gr_poly
					(pts
						(arc
							(start -0.3302 0.4318)
							(mid -0.402042 0.402042)
							(end -0.4318 0.3302)
						)
						(arc
							(start -0.4318 -0.3302)
							(mid -0.402042 -0.402042)
							(end -0.3302 -0.4318)
						)
						(arc
							(start 0.3302 -0.4318)
							(mid 0.402042 -0.402042)
							(end 0.4318 -0.3302)
						)
						(arc
							(start 0.4318 0.3302)
							(mid 0.402042 0.402042)
							(end 0.3302 0.4318)
						)
					)
					(width 0)
					(fill yes)
				)
			)
		)
		(pad "2" smd custom
			(at 0 0.762 180)
			(size 0.2159 0.2159)
			(layers "B.Cu" "B.Mask" "B.Paste")
			(net "AGND_CURRENT_MON")
			(options
				(clearance outline)
				(anchor circle)
			)
			(primitives
				(gr_poly
					(pts
						(arc
							(start -0.3302 0.4318)
							(mid -0.402042 0.402042)
							(end -0.4318 0.3302)
						)
						(arc
							(start -0.4318 -0.3302)
							(mid -0.402042 -0.402042)
							(end -0.3302 -0.4318)
						)
						(arc
							(start 0.3302 -0.4318)
							(mid 0.402042 -0.402042)
							(end 0.4318 -0.3302)
						)
						(arc
							(start 0.4318 0.3302)
							(mid 0.402042 0.402042)
							(end 0.3302 0.4318)
						)
					)
					(width 0)
					(fill yes)
				)
			)
		)
	)
	(footprint ""
		(layer "B.Cu")
		(at 12.7762 -148.9329 -90)
		(property "Reference" "C63"
			(at 0 0 90)
			(layer "B.SilkS")
			(hide yes)
			(effects
				(font
					(size 1.27 1.27)
				)
				(justify mirror)
			)
		)
		(property "Value" "SC4D7U25V5KX-1-GP"
			(at 0.0762 -6.1214 270)
			(unlocked yes)
			(layer "B.Fab")
			(hide yes)
			(effects
				(font
					(size 1.016 1.016)
					(thickness 0.1524)
				)
				(justify mirror)
			)
		)
		(property "Device Type" "C805H58"
			(at 0.0762 -8.1534 270)
			(unlocked yes)
			(layer "B.Fab")
			(hide yes)
			(effects
				(font
					(size 1.016 1.016)
					(thickness 0.1524)
				)
				(justify mirror)
			)
		)
		(duplicate_pad_numbers_are_jumpers no)
		(fp_line
			(start -0.635 0)
			(end 0.635 0)
			(stroke
				(width 0.508)
				(type default)
			)
			(layer "B.SilkS")
		)
		(fp_rect
			(start 0.9652 1.778)
			(end -0.9652 -1.778)
			(stroke
				(width 0)
				(type default)
			)
			(fill no)
			(layer "B.CrtYd")
		)
		(fp_poly
			(pts
				(xy 0.9652 -1.778) (xy -0.9652 -1.778) (xy -0.9652 1.778) (xy 0.9652 1.778)
			)
			(stroke
				(width 0)
				(type default)
			)
			(fill no)
			(layer "B.Fab")
		)
		(pad "1" smd rect
			(at 0 -0.9652 90)
			(size 1.397 1.143)
			(layers "B.Cu" "B.Mask" "B.Paste")
			(net "P1V2_STBY")
		)
		(pad "2" smd rect
			(at 0 0.9652 90)
			(size 1.397 1.143)
			(layers "B.Cu" "B.Mask" "B.Paste")
			(net "GND")
		)
	)
	(footprint ""
		(layer "B.Cu")
		(at 48.887634 -155.610052)
		(property "Reference" "R323"
			(at 0 0 0)
			(layer "B.SilkS")
			(hide yes)
			(effects
				(font
					(size 1.27 1.27)
				)
				(justify mirror)
			)
		)
		(property "Value" "4K7R2F-GP"
			(at -0.064008 -3.993896 0)
			(unlocked yes)
			(layer "B.Fab")
			(hide yes)
			(effects
				(font
					(size 1.016 1.016)
					(thickness 0.1524)
				)
				(justify mirror)
			)
		)
		(property "Device Type" "R402H16"
			(at -0.064008 -5.517896 0)
			(unlocked yes)
			(layer "B.Fab")
			(hide yes)
			(effects
				(font
					(size 1.016 1.016)
					(thickness 0.1524)
				)
				(justify mirror)
			)
		)
		(duplicate_pad_numbers_are_jumpers no)
		(fp_line
			(start -0.508 -0.9398)
			(end 0.508 -0.9398)
			(stroke
				(width 0.1524)
				(type default)
			)
			(layer "B.SilkS")
		)
		(fp_line
			(start 0.508 -0.9398)
			(end 0.508 0.9398)
			(stroke
				(width 0.1524)
				(type default)
			)
			(layer "B.SilkS")
		)
		(fp_rect
			(start 0.508 0.9398)
			(end -0.508 -0.9398)
			(stroke
				(width 0)
				(type default)
			)
			(fill no)
			(layer "B.CrtYd")
		)
		(fp_rect
			(start 0.508 0.9398)
			(end -0.508 -0.9398)
			(stroke
				(width 0)
				(type default)
			)
			(fill no)
			(layer "B.Fab")
		)
		(pad "1" smd custom
			(at 0 -0.4445 180)
			(size 0.1397 0.1397)
			(layers "B.Cu" "B.Mask" "B.Paste")
			(net "GND")
			(options
				(clearance outline)
				(anchor circle)
			)
			(primitives
				(gr_poly
					(pts
						(arc
							(start -0.1778 0.2794)
							(mid -0.249642 0.249642)
							(end -0.2794 0.1778)
						)
						(arc
							(start -0.2794 -0.1778)
							(mid -0.249642 -0.249642)
							(end -0.1778 -0.2794)
						)
						(arc
							(start 0.1778 -0.2794)
							(mid 0.249642 -0.249642)
							(end 0.2794 -0.1778)
						)
						(arc
							(start 0.2794 0.1778)
							(mid 0.249642 0.249642)
							(end 0.1778 0.2794)
						)
					)
					(width 0)
					(fill yes)
				)
			)
		)
		(pad "2" smd custom
			(at 0 0.4445 180)
			(size 0.1397 0.1397)
			(layers "B.Cu" "B.Mask" "B.Paste")
			(net "BOARD_REV_1")
			(options
				(clearance outline)
				(anchor circle)
			)
			(primitives
				(gr_poly
					(pts
						(arc
							(start -0.1778 0.2794)
							(mid -0.249642 0.249642)
							(end -0.2794 0.1778)
						)
						(arc
							(start -0.2794 -0.1778)
							(mid -0.249642 -0.249642)
							(end -0.1778 -0.2794)
						)
						(arc
							(start 0.1778 -0.2794)
							(mid 0.249642 -0.249642)
							(end 0.2794 -0.1778)
						)
						(arc
							(start 0.2794 0.1778)
							(mid 0.249642 0.249642)
							(end 0.1778 0.2794)
						)
					)
					(width 0)
					(fill yes)
				)
			)
		)
	)
	(footprint ""
		(layer "B.Cu")
		(at 129.921 -14.351)
		(property "Reference" "R448"
			(at 0 0 0)
			(layer "B.SilkS")
			(hide yes)
			(effects
				(font
					(size 1.27 1.27)
				)
				(justify mirror)
			)
		)
		(property "Value" "5K1R2F-3-GP"
			(at -0.064008 -3.993896 0)
			(unlocked yes)
			(layer "B.Fab")
			(hide yes)
			(effects
				(font
					(size 1.016 1.016)
					(thickness 0.1524)
				)
				(justify mirror)
			)
		)
		(property "Device Type" "R402H16"
			(at -0.064008 -5.517896 0)
			(unlocked yes)
			(layer "B.Fab")
			(hide yes)
			(effects
				(font
					(size 1.016 1.016)
					(thickness 0.1524)
				)
				(justify mirror)
			)
		)
		(duplicate_pad_numbers_are_jumpers no)
		(fp_line
			(start -0.508 -0.9398)
			(end 0.508 -0.9398)
			(stroke
				(width 0.1524)
				(type default)
			)
			(layer "B.SilkS")
		)
		(fp_line
			(start 0.508 -0.9398)
			(end 0.508 0.9398)
			(stroke
				(width 0.1524)
				(type default)
			)
			(layer "B.SilkS")
		)
		(fp_rect
			(start 0.508 0.9398)
			(end -0.508 -0.9398)
			(stroke
				(width 0)
				(type default)
			)
			(fill no)
			(layer "B.CrtYd")
		)
		(fp_rect
			(start 0.508 0.9398)
			(end -0.508 -0.9398)
			(stroke
				(width 0)
				(type default)
			)
			(fill no)
			(layer "B.Fab")
		)
		(pad "1" smd custom
			(at 0 -0.4445 180)
			(size 0.1397 0.1397)
			(layers "B.Cu" "B.Mask" "B.Paste")
			(net "MB0_CM_UV_R")
			(options
				(clearance outline)
				(anchor circle)
			)
			(primitives
				(gr_poly
					(pts
						(arc
							(start -0.1778 0.2794)
							(mid -0.249642 0.249642)
							(end -0.2794 0.1778)
						)
						(arc
							(start -0.2794 -0.1778)
							(mid -0.249642 -0.249642)
							(end -0.1778 -0.2794)
						)
						(arc
							(start 0.1778 -0.2794)
							(mid 0.249642 -0.249642)
							(end 0.2794 -0.1778)
						)
						(arc
							(start 0.2794 0.1778)
							(mid 0.249642 0.249642)
							(end 0.1778 0.2794)
						)
					)
					(width 0)
					(fill yes)
				)
			)
		)
		(pad "2" smd custom
			(at 0 0.4445 180)
			(size 0.1397 0.1397)
			(layers "B.Cu" "B.Mask" "B.Paste")
			(net "AGND_CURRENT_MON")
			(options
				(clearance outline)
				(anchor circle)
			)
			(primitives
				(gr_poly
					(pts
						(arc
							(start -0.1778 0.2794)
							(mid -0.249642 0.249642)
							(end -0.2794 0.1778)
						)
						(arc
							(start -0.2794 -0.1778)
							(mid -0.249642 -0.249642)
							(end -0.1778 -0.2794)
						)
						(arc
							(start 0.1778 -0.2794)
							(mid 0.249642 -0.249642)
							(end 0.2794 -0.1778)
						)
						(arc
							(start 0.2794 0.1778)
							(mid 0.249642 0.249642)
							(end 0.1778 0.2794)
						)
					)
					(width 0)
					(fill yes)
				)
			)
		)
	)
	(footprint ""
		(layer "B.Cu")
		(at 126.5301 -14.48562)
		(property "Reference" "R447"
			(at 0 0 0)
			(layer "B.SilkS")
			(hide yes)
			(effects
				(font
					(size 1.27 1.27)
				)
				(justify mirror)
			)
		)
		(property "Value" "4K12R2F-3-GP"
			(at -0.064008 -3.993896 0)
			(unlocked yes)
			(layer "B.Fab")
			(hide yes)
			(effects
				(font
					(size 1.016 1.016)
					(thickness 0.1524)
				)
				(justify mirror)
			)
		)
		(property "Device Type" "R402H16"
			(at -0.064008 -5.517896 0)
			(unlocked yes)
			(layer "B.Fab")
			(hide yes)
			(effects
				(font
					(size 1.016 1.016)
					(thickness 0.1524)
				)
				(justify mirror)
			)
		)
		(duplicate_pad_numbers_are_jumpers no)
		(fp_line
			(start -0.508 -0.9398)
			(end 0.508 -0.9398)
			(stroke
				(width 0.1524)
				(type default)
			)
			(layer "B.SilkS")
		)
		(fp_line
			(start 0.508 -0.9398)
			(end 0.508 0.9398)
			(stroke
				(width 0.1524)
				(type default)
			)
			(layer "B.SilkS")
		)
		(fp_rect
			(start 0.508 0.9398)
			(end -0.508 -0.9398)
			(stroke
				(width 0)
				(type default)
			)
			(fill no)
			(layer "B.CrtYd")
		)
		(fp_rect
			(start 0.508 0.9398)
			(end -0.508 -0.9398)
			(stroke
				(width 0)
				(type default)
			)
			(fill no)
			(layer "B.Fab")
		)
		(pad "1" smd custom
			(at 0 -0.4445 180)
			(size 0.1397 0.1397)
			(layers "B.Cu" "B.Mask" "B.Paste")
			(net "MB0_CM_OV_R")
			(options
				(clearance outline)
				(anchor circle)
			)
			(primitives
				(gr_poly
					(pts
						(arc
							(start -0.1778 0.2794)
							(mid -0.249642 0.249642)
							(end -0.2794 0.1778)
						)
						(arc
							(start -0.2794 -0.1778)
							(mid -0.249642 -0.249642)
							(end -0.1778 -0.2794)
						)
						(arc
							(start 0.1778 -0.2794)
							(mid 0.249642 -0.249642)
							(end 0.2794 -0.1778)
						)
						(arc
							(start 0.2794 0.1778)
							(mid 0.249642 0.249642)
							(end 0.1778 0.2794)
						)
					)
					(width 0)
					(fill yes)
				)
			)
		)
		(pad "2" smd custom
			(at 0 0.4445 180)
			(size 0.1397 0.1397)
			(layers "B.Cu" "B.Mask" "B.Paste")
			(net "AGND_CURRENT_MON")
			(options
				(clearance outline)
				(anchor circle)
			)
			(primitives
				(gr_poly
					(pts
						(arc
							(start -0.1778 0.2794)
							(mid -0.249642 0.249642)
							(end -0.2794 0.1778)
						)
						(arc
							(start -0.2794 -0.1778)
							(mid -0.249642 -0.249642)
							(end -0.1778 -0.2794)
						)
						(arc
							(start 0.1778 -0.2794)
							(mid 0.249642 -0.249642)
							(end 0.2794 -0.1778)
						)
						(arc
							(start 0.2794 0.1778)
							(mid 0.249642 0.249642)
							(end 0.1778 0.2794)
						)
					)
					(width 0)
					(fill yes)
				)
			)
		)
	)
	(footprint ""
		(layer "B.Cu")
		(at 35.941 -157.5308 -90)
		(property "Reference" "R706"
			(at 0 0 90)
			(layer "B.SilkS")
			(hide yes)
			(effects
				(font
					(size 1.27 1.27)
				)
				(justify mirror)
			)
		)
		(property "Value" "4K7R2F-GP"
			(at -0.064008 -3.993896 270)
			(unlocked yes)
			(layer "B.Fab")
			(hide yes)
			(effects
				(font
					(size 1.016 1.016)
					(thickness 0.1524)
				)
				(justify mirror)
			)
		)
		(property "Device Type" "R402H16"
			(at -0.064008 -5.517896 270)
			(unlocked yes)
			(layer "B.Fab")
			(hide yes)
			(effects
				(font
					(size 1.016 1.016)
					(thickness 0.1524)
				)
				(justify mirror)
			)
		)
		(duplicate_pad_numbers_are_jumpers no)
		(fp_line
			(start -0.508 -0.9398)
			(end 0.508 -0.9398)
			(stroke
				(width 0.1524)
				(type default)
			)
			(layer "B.SilkS")
		)
		(fp_line
			(start 0.508 -0.9398)
			(end 0.508 0.9398)
			(stroke
				(width 0.1524)
				(type default)
			)
			(layer "B.SilkS")
		)
		(fp_rect
			(start 0.508 0.9398)
			(end -0.508 -0.9398)
			(stroke
				(width 0)
				(type default)
			)
			(fill no)
			(layer "B.CrtYd")
		)
		(fp_rect
			(start 0.508 0.9398)
			(end -0.508 -0.9398)
			(stroke
				(width 0)
				(type default)
			)
			(fill no)
			(layer "B.Fab")
		)
		(pad "1" smd custom
			(at 0 -0.4445 90)
			(size 0.1397 0.1397)
			(layers "B.Cu" "B.Mask" "B.Paste")
			(net "IOM_TYPE3")
			(options
				(clearance outline)
				(anchor circle)
			)
			(primitives
				(gr_poly
					(pts
						(arc
							(start -0.1778 0.2794)
							(mid -0.249642 0.249642)
							(end -0.2794 0.1778)
						)
						(arc
							(start -0.2794 -0.1778)
							(mid -0.249642 -0.249642)
							(end -0.1778 -0.2794)
						)
						(arc
							(start 0.1778 -0.2794)
							(mid 0.249642 -0.249642)
							(end 0.2794 -0.1778)
						)
						(arc
							(start 0.2794 0.1778)
							(mid 0.249642 0.249642)
							(end 0.1778 0.2794)
						)
					)
					(width 0)
					(fill yes)
				)
			)
		)
		(pad "2" smd custom
			(at 0 0.4445 90)
			(size 0.1397 0.1397)
			(layers "B.Cu" "B.Mask" "B.Paste")
			(net "GND")
			(options
				(clearance outline)
				(anchor circle)
			)
			(primitives
				(gr_poly
					(pts
						(arc
							(start -0.1778 0.2794)
							(mid -0.249642 0.249642)
							(end -0.2794 0.1778)
						)
						(arc
							(start -0.2794 -0.1778)
							(mid -0.249642 -0.249642)
							(end -0.1778 -0.2794)
						)
						(arc
							(start 0.1778 -0.2794)
							(mid 0.249642 -0.249642)
							(end 0.2794 -0.1778)
						)
						(arc
							(start 0.2794 0.1778)
							(mid 0.249642 0.249642)
							(end 0.1778 0.2794)
						)
					)
					(width 0)
					(fill yes)
				)
			)
		)
	)
	(footprint ""
		(layer "B.Cu")
		(at 52.78628 -144.99844)
		(property "Reference" "TP52"
			(at 0 0 0)
			(layer "B.SilkS")
			(hide yes)
			(effects
				(font
					(size 1.27 1.27)
				)
				(justify mirror)
			)
		)
		(property "Value" "TPAD28-2-GP"
			(at 0.0127 -1.6637 0)
			(unlocked yes)
			(layer "B.Fab")
			(hide yes)
			(effects
				(font
					(size 1.016 1.016)
					(thickness 0.1524)
				)
				(justify mirror)
			)
		)
		(property "Device Type" "TPAD28"
			(at 0.0127 -3.1877 0)
			(unlocked yes)
			(layer "B.Fab")
			(hide yes)
			(effects
				(font
					(size 1.016 1.016)
					(thickness 0.1524)
				)
				(justify mirror)
			)
		)
		(duplicate_pad_numbers_are_jumpers no)
		(fp_poly
			(pts
				(arc
					(start 0.3556 0)
					(mid -0.3556 0)
					(end 0.3556 0)
				)
			)
			(stroke
				(width 0)
				(type default)
			)
			(fill no)
			(layer "B.CrtYd")
		)
		(fp_poly
			(pts
				(arc
					(start 0.6096 0)
					(mid -0.6096 0)
					(end 0.6096 0)
				)
			)
			(stroke
				(width 0)
				(type default)
			)
			(fill no)
			(layer "B.Fab")
		)
		(pad "1" smd circle
			(at 0 0 180)
			(size 0.7112 0.7112)
			(layers "B.Cu" "B.Mask" "B.Paste")
			(net "RMII_BMC_MDIO_R")
		)
	)
	(footprint ""
		(layer "B.Cu")
		(at 91.2114 -169.05732 90)
		(property "Reference" "R795"
			(at 0 0 90)
			(layer "B.SilkS")
			(hide yes)
			(effects
				(font
					(size 1.27 1.27)
				)
				(justify mirror)
			)
		)
		(property "Value" "0R2J-2-GP"
			(at -0.064008 -3.993896 90)
			(unlocked yes)
			(layer "B.Fab")
			(hide yes)
			(effects
				(font
					(size 1.016 1.016)
					(thickness 0.1524)
				)
				(justify mirror)
			)
		)
		(property "Device Type" "R402H16"
			(at -0.064008 -5.517896 90)
			(unlocked yes)
			(layer "B.Fab")
			(hide yes)
			(effects
				(font
					(size 1.016 1.016)
					(thickness 0.1524)
				)
				(justify mirror)
			)
		)
		(duplicate_pad_numbers_are_jumpers no)
		(fp_line
			(start 0.508 -0.9398)
			(end 0.508 0.9398)
			(stroke
				(width 0.1524)
				(type default)
			)
			(layer "B.SilkS")
		)
		(fp_line
			(start -0.508 -0.9398)
			(end 0.508 -0.9398)
			(stroke
				(width 0.1524)
				(type default)
			)
			(layer "B.SilkS")
		)
		(fp_rect
			(start 0.508 0.9398)
			(end -0.508 -0.9398)
			(stroke
				(width 0)
				(type default)
			)
			(fill no)
			(layer "B.CrtYd")
		)
		(fp_rect
			(start 0.508 0.9398)
			(end -0.508 -0.9398)
			(stroke
				(width 0)
				(type default)
			)
			(fill no)
			(layer "B.Fab")
		)
		(pad "1" smd custom
			(at 0 -0.4445 270)
			(size 0.1397 0.1397)
			(layers "B.Cu" "B.Mask" "B.Paste")
			(net "UART_COMP_IN_RX_AND_R")
			(options
				(clearance outline)
				(anchor circle)
			)
			(primitives
				(gr_poly
					(pts
						(arc
							(start -0.1778 0.2794)
							(mid -0.249642 0.249642)
							(end -0.2794 0.1778)
						)
						(arc
							(start -0.2794 -0.1778)
							(mid -0.249642 -0.249642)
							(end -0.1778 -0.2794)
						)
						(arc
							(start 0.1778 -0.2794)
							(mid 0.249642 -0.249642)
							(end 0.2794 -0.1778)
						)
						(arc
							(start 0.2794 0.1778)
							(mid 0.249642 0.249642)
							(end 0.1778 0.2794)
						)
					)
					(width 0)
					(fill yes)
				)
			)
		)
		(pad "2" smd custom
			(at 0 0.4445 270)
			(size 0.1397 0.1397)
			(layers "B.Cu" "B.Mask" "B.Paste")
			(net "UART_COMP_IN_RX_AND")
			(options
				(clearance outline)
				(anchor circle)
			)
			(primitives
				(gr_poly
					(pts
						(arc
							(start -0.1778 0.2794)
							(mid -0.249642 0.249642)
							(end -0.2794 0.1778)
						)
						(arc
							(start -0.2794 -0.1778)
							(mid -0.249642 -0.249642)
							(end -0.1778 -0.2794)
						)
						(arc
							(start 0.1778 -0.2794)
							(mid 0.249642 -0.249642)
							(end 0.2794 -0.1778)
						)
						(arc
							(start 0.2794 0.1778)
							(mid 0.249642 0.249642)
							(end 0.1778 0.2794)
						)
					)
					(width 0)
					(fill yes)
				)
			)
		)
	)
	(footprint ""
		(layer "B.Cu")
		(at 52.7304 -126.33452 180)
		(property "Reference" "C505"
			(at 0 0 0)
			(layer "B.SilkS")
			(hide yes)
			(effects
				(font
					(size 1.27 1.27)
				)
				(justify mirror)
			)
		)
		(property "Value" "SCD1U16V2KX-3GP"
			(at -1.1811 -2.7051 180)
			(unlocked yes)
			(layer "B.Fab")
			(hide yes)
			(effects
				(font
					(size 1.016 1.016)
					(thickness 0.1524)
				)
				(justify mirror)
			)
		)
		(property "Device Type" "C402H22"
			(at -1.1811 -4.2291 180)
			(unlocked yes)
			(layer "B.Fab")
			(hide yes)
			(effects
				(font
					(size 1.016 1.016)
					(thickness 0.1524)
				)
				(justify mirror)
			)
		)
		(duplicate_pad_numbers_are_jumpers no)
		(fp_rect
			(start 0.4318 0.9525)
			(end -0.4318 -0.9525)
			(stroke
				(width 0)
				(type default)
			)
			(fill no)
			(layer "B.CrtYd")
		)
		(fp_rect
			(start 0.4318 0.9525)
			(end -0.4318 -0.9525)
			(stroke
				(width 0)
				(type default)
			)
			(fill no)
			(layer "B.Fab")
		)
		(pad "1" smd custom
			(at 0 -0.4445)
			(size 0.1524 0.1524)
			(layers "B.Cu" "B.Mask" "B.Paste")
			(net "P3V3_STBY")
			(options
				(clearance outline)
				(anchor circle)
			)
			(primitives
				(gr_poly
					(pts
						(arc
							(start 0.3048 0.2032)
							(mid 0.275042 0.275042)
							(end 0.2032 0.3048)
						)
						(arc
							(start -0.2032 0.3048)
							(mid -0.275042 0.275042)
							(end -0.3048 0.2032)
						)
						(arc
							(start -0.3048 -0.2032)
							(mid -0.275042 -0.275042)
							(end -0.2032 -0.3048)
						)
						(arc
							(start 0.2032 -0.3048)
							(mid 0.275042 -0.275042)
							(end 0.3048 -0.2032)
						)
					)
					(width 0)
					(fill yes)
				)
			)
		)
		(pad "2" smd custom
			(at 0 0.4445)
			(size 0.1524 0.1524)
			(layers "B.Cu" "B.Mask" "B.Paste")
			(net "GND")
			(options
				(clearance outline)
				(anchor circle)
			)
			(primitives
				(gr_poly
					(pts
						(arc
							(start 0.3048 0.2032)
							(mid 0.275042 0.275042)
							(end 0.2032 0.3048)
						)
						(arc
							(start -0.2032 0.3048)
							(mid -0.275042 0.275042)
							(end -0.3048 0.2032)
						)
						(arc
							(start -0.3048 -0.2032)
							(mid -0.275042 -0.275042)
							(end -0.2032 -0.3048)
						)
						(arc
							(start 0.2032 -0.3048)
							(mid 0.275042 -0.275042)
							(end 0.3048 -0.2032)
						)
					)
					(width 0)
					(fill yes)
				)
			)
		)
	)
	(footprint ""
		(layer "B.Cu")
		(at 12.11199 -142.463266 90)
		(property "Reference" "R212"
			(at 0 0 90)
			(layer "B.SilkS")
			(hide yes)
			(effects
				(font
					(size 1.27 1.27)
				)
				(justify mirror)
			)
		)
		(property "Value" "120R2F-GP"
			(at -0.064008 -3.993896 90)
			(unlocked yes)
			(layer "B.Fab")
			(hide yes)
			(effects
				(font
					(size 1.016 1.016)
					(thickness 0.1524)
				)
				(justify mirror)
			)
		)
		(property "Device Type" "R402H16"
			(at -0.064008 -5.517896 90)
			(unlocked yes)
			(layer "B.Fab")
			(hide yes)
			(effects
				(font
					(size 1.016 1.016)
					(thickness 0.1524)
				)
				(justify mirror)
			)
		)
		(duplicate_pad_numbers_are_jumpers no)
		(fp_line
			(start 0.508 -0.9398)
			(end 0.508 0.9398)
			(stroke
				(width 0.1524)
				(type default)
			)
			(layer "B.SilkS")
		)
		(fp_line
			(start -0.508 -0.9398)
			(end 0.508 -0.9398)
			(stroke
				(width 0.1524)
				(type default)
			)
			(layer "B.SilkS")
		)
		(fp_rect
			(start 0.508 0.9398)
			(end -0.508 -0.9398)
			(stroke
				(width 0)
				(type default)
			)
			(fill no)
			(layer "B.CrtYd")
		)
		(fp_rect
			(start 0.508 0.9398)
			(end -0.508 -0.9398)
			(stroke
				(width 0)
				(type default)
			)
			(fill no)
			(layer "B.Fab")
		)
		(pad "1" smd custom
			(at 0 -0.4445 270)
			(size 0.1397 0.1397)
			(layers "B.Cu" "B.Mask" "B.Paste")
			(net "MEMODT")
			(options
				(clearance outline)
				(anchor circle)
			)
			(primitives
				(gr_poly
					(pts
						(arc
							(start -0.1778 0.2794)
							(mid -0.249642 0.249642)
							(end -0.2794 0.1778)
						)
						(arc
							(start -0.2794 -0.1778)
							(mid -0.249642 -0.249642)
							(end -0.1778 -0.2794)
						)
						(arc
							(start 0.1778 -0.2794)
							(mid 0.249642 -0.249642)
							(end 0.2794 -0.1778)
						)
						(arc
							(start 0.2794 0.1778)
							(mid 0.249642 0.249642)
							(end 0.1778 0.2794)
						)
					)
					(width 0)
					(fill yes)
				)
			)
		)
		(pad "2" smd custom
			(at 0 0.4445 270)
			(size 0.1397 0.1397)
			(layers "B.Cu" "B.Mask" "B.Paste")
			(net "P1V2_STBY")
			(options
				(clearance outline)
				(anchor circle)
			)
			(primitives
				(gr_poly
					(pts
						(arc
							(start -0.1778 0.2794)
							(mid -0.249642 0.249642)
							(end -0.2794 0.1778)
						)
						(arc
							(start -0.2794 -0.1778)
							(mid -0.249642 -0.249642)
							(end -0.1778 -0.2794)
						)
						(arc
							(start 0.1778 -0.2794)
							(mid 0.249642 -0.249642)
							(end 0.2794 -0.1778)
						)
						(arc
							(start 0.2794 0.1778)
							(mid 0.249642 0.249642)
							(end 0.1778 0.2794)
						)
					)
					(width 0)
					(fill yes)
				)
			)
		)
	)
	(footprint ""
		(layer "B.Cu")
		(at 200.829418 -130.391408 180)
		(property "Reference" "C607"
			(at 0 0 0)
			(layer "B.SilkS")
			(hide yes)
			(effects
				(font
					(size 1.27 1.27)
				)
				(justify mirror)
			)
		)
		(property "Value" "SCD1U16V2KX-3GP"
			(at -1.1811 -2.7051 180)
			(unlocked yes)
			(layer "B.Fab")
			(hide yes)
			(effects
				(font
					(size 1.016 1.016)
					(thickness 0.1524)
				)
				(justify mirror)
			)
		)
		(property "Device Type" "C402H22"
			(at -1.1811 -4.2291 180)
			(unlocked yes)
			(layer "B.Fab")
			(hide yes)
			(effects
				(font
					(size 1.016 1.016)
					(thickness 0.1524)
				)
				(justify mirror)
			)
		)
		(duplicate_pad_numbers_are_jumpers no)
		(fp_rect
			(start 0.4318 0.9525)
			(end -0.4318 -0.9525)
			(stroke
				(width 0)
				(type default)
			)
			(fill no)
			(layer "B.CrtYd")
		)
		(fp_rect
			(start 0.4318 0.9525)
			(end -0.4318 -0.9525)
			(stroke
				(width 0)
				(type default)
			)
			(fill no)
			(layer "B.Fab")
		)
		(pad "1" smd custom
			(at 0 -0.4445)
			(size 0.1524 0.1524)
			(layers "B.Cu" "B.Mask" "B.Paste")
			(net "P3V3_M2")
			(options
				(clearance outline)
				(anchor circle)
			)
			(primitives
				(gr_poly
					(pts
						(arc
							(start 0.3048 0.2032)
							(mid 0.275042 0.275042)
							(end 0.2032 0.3048)
						)
						(arc
							(start -0.2032 0.3048)
							(mid -0.275042 0.275042)
							(end -0.3048 0.2032)
						)
						(arc
							(start -0.3048 -0.2032)
							(mid -0.275042 -0.275042)
							(end -0.2032 -0.3048)
						)
						(arc
							(start 0.2032 -0.3048)
							(mid 0.275042 -0.275042)
							(end 0.3048 -0.2032)
						)
					)
					(width 0)
					(fill yes)
				)
			)
		)
		(pad "2" smd custom
			(at 0 0.4445)
			(size 0.1524 0.1524)
			(layers "B.Cu" "B.Mask" "B.Paste")
			(net "GND")
			(options
				(clearance outline)
				(anchor circle)
			)
			(primitives
				(gr_poly
					(pts
						(arc
							(start 0.3048 0.2032)
							(mid 0.275042 0.275042)
							(end 0.2032 0.3048)
						)
						(arc
							(start -0.2032 0.3048)
							(mid -0.275042 0.275042)
							(end -0.3048 0.2032)
						)
						(arc
							(start -0.3048 -0.2032)
							(mid -0.275042 -0.275042)
							(end -0.2032 -0.3048)
						)
						(arc
							(start 0.2032 -0.3048)
							(mid 0.275042 -0.275042)
							(end 0.3048 -0.2032)
						)
					)
					(width 0)
					(fill yes)
				)
			)
		)
	)
	(footprint ""
		(layer "B.Cu")
		(at 81.76387 -48.653446 -90)
		(property "Reference" "C25"
			(at 0 0 90)
			(layer "B.SilkS")
			(hide yes)
			(effects
				(font
					(size 1.27 1.27)
				)
				(justify mirror)
			)
		)
		(property "Value" "SC2D2U25V5KX-2-GP"
			(at 0.0762 -6.1214 270)
			(unlocked yes)
			(layer "B.Fab")
			(hide yes)
			(effects
				(font
					(size 1.016 1.016)
					(thickness 0.1524)
				)
				(justify mirror)
			)
		)
		(property "Device Type" "C805H54"
			(at 0.0762 -8.1534 270)
			(unlocked yes)
			(layer "B.Fab")
			(hide yes)
			(effects
				(font
					(size 1.016 1.016)
					(thickness 0.1524)
				)
				(justify mirror)
			)
		)
		(duplicate_pad_numbers_are_jumpers no)
		(fp_line
			(start -0.635 0)
			(end 0.635 0)
			(stroke
				(width 0.508)
				(type default)
			)
			(layer "B.SilkS")
		)
		(fp_rect
			(start 0.9652 1.778)
			(end -0.9652 -1.778)
			(stroke
				(width 0)
				(type default)
			)
			(fill no)
			(layer "B.CrtYd")
		)
		(fp_poly
			(pts
				(xy 0.9652 -1.778) (xy -0.9652 -1.778) (xy -0.9652 1.778) (xy 0.9652 1.778)
			)
			(stroke
				(width 0)
				(type default)
			)
			(fill no)
			(layer "B.Fab")
		)
		(pad "1" smd rect
			(at 0 -0.9652 90)
			(size 1.397 1.143)
			(layers "B.Cu" "B.Mask" "B.Paste")
			(net "P5V_STBY")
		)
		(pad "2" smd rect
			(at 0 0.9652 90)
			(size 1.397 1.143)
			(layers "B.Cu" "B.Mask" "B.Paste")
			(net "GND")
		)
	)
	(footprint ""
		(layer "B.Cu")
		(at 195.441062 -133.83895 180)
		(property "Reference" "C626"
			(at 0 0 0)
			(layer "B.SilkS")
			(hide yes)
			(effects
				(font
					(size 1.27 1.27)
				)
				(justify mirror)
			)
		)
		(property "Value" "SCD1U16V2KX-3GP"
			(at -1.1811 -2.7051 180)
			(unlocked yes)
			(layer "B.Fab")
			(hide yes)
			(effects
				(font
					(size 1.016 1.016)
					(thickness 0.1524)
				)
				(justify mirror)
			)
		)
		(property "Device Type" "C402H22"
			(at -1.1811 -4.2291 180)
			(unlocked yes)
			(layer "B.Fab")
			(hide yes)
			(effects
				(font
					(size 1.016 1.016)
					(thickness 0.1524)
				)
				(justify mirror)
			)
		)
		(duplicate_pad_numbers_are_jumpers no)
		(fp_rect
			(start 0.4318 0.9525)
			(end -0.4318 -0.9525)
			(stroke
				(width 0)
				(type default)
			)
			(fill no)
			(layer "B.CrtYd")
		)
		(fp_rect
			(start 0.4318 0.9525)
			(end -0.4318 -0.9525)
			(stroke
				(width 0)
				(type default)
			)
			(fill no)
			(layer "B.Fab")
		)
		(pad "1" smd custom
			(at 0 -0.4445)
			(size 0.1524 0.1524)
			(layers "B.Cu" "B.Mask" "B.Paste")
			(net "P3V3_M2")
			(options
				(clearance outline)
				(anchor circle)
			)
			(primitives
				(gr_poly
					(pts
						(arc
							(start 0.3048 0.2032)
							(mid 0.275042 0.275042)
							(end 0.2032 0.3048)
						)
						(arc
							(start -0.2032 0.3048)
							(mid -0.275042 0.275042)
							(end -0.3048 0.2032)
						)
						(arc
							(start -0.3048 -0.2032)
							(mid -0.275042 -0.275042)
							(end -0.2032 -0.3048)
						)
						(arc
							(start 0.2032 -0.3048)
							(mid 0.275042 -0.275042)
							(end 0.3048 -0.2032)
						)
					)
					(width 0)
					(fill yes)
				)
			)
		)
		(pad "2" smd custom
			(at 0 0.4445)
			(size 0.1524 0.1524)
			(layers "B.Cu" "B.Mask" "B.Paste")
			(net "GND")
			(options
				(clearance outline)
				(anchor circle)
			)
			(primitives
				(gr_poly
					(pts
						(arc
							(start 0.3048 0.2032)
							(mid 0.275042 0.275042)
							(end 0.2032 0.3048)
						)
						(arc
							(start -0.2032 0.3048)
							(mid -0.275042 0.275042)
							(end -0.3048 0.2032)
						)
						(arc
							(start -0.3048 -0.2032)
							(mid -0.275042 -0.275042)
							(end -0.2032 -0.3048)
						)
						(arc
							(start 0.2032 -0.3048)
							(mid 0.275042 -0.275042)
							(end 0.3048 -0.2032)
						)
					)
					(width 0)
					(fill yes)
				)
			)
		)
	)
	(footprint ""
		(layer "B.Cu")
		(at 61.26988 -142.880334 90)
		(property "Reference" "R151"
			(at 0 0 90)
			(layer "B.SilkS")
			(hide yes)
			(effects
				(font
					(size 1.27 1.27)
				)
				(justify mirror)
			)
		)
		(property "Value" "0R2J-2-GP"
			(at -0.064008 -3.993896 90)
			(unlocked yes)
			(layer "B.Fab")
			(hide yes)
			(effects
				(font
					(size 1.016 1.016)
					(thickness 0.1524)
				)
				(justify mirror)
			)
		)
		(property "Device Type" "R402H16"
			(at -0.064008 -5.517896 90)
			(unlocked yes)
			(layer "B.Fab")
			(hide yes)
			(effects
				(font
					(size 1.016 1.016)
					(thickness 0.1524)
				)
				(justify mirror)
			)
		)
		(duplicate_pad_numbers_are_jumpers no)
		(fp_line
			(start 0.508 -0.9398)
			(end 0.508 0.9398)
			(stroke
				(width 0.1524)
				(type default)
			)
			(layer "B.SilkS")
		)
		(fp_line
			(start -0.508 -0.9398)
			(end 0.508 -0.9398)
			(stroke
				(width 0.1524)
				(type default)
			)
			(layer "B.SilkS")
		)
		(fp_rect
			(start 0.508 0.9398)
			(end -0.508 -0.9398)
			(stroke
				(width 0)
				(type default)
			)
			(fill no)
			(layer "B.CrtYd")
		)
		(fp_rect
			(start 0.508 0.9398)
			(end -0.508 -0.9398)
			(stroke
				(width 0)
				(type default)
			)
			(fill no)
			(layer "B.Fab")
		)
		(pad "1" smd custom
			(at 0 -0.4445 270)
			(size 0.1397 0.1397)
			(layers "B.Cu" "B.Mask" "B.Paste")
			(net "BMC_SMB10_CLK")
			(options
				(clearance outline)
				(anchor circle)
			)
			(primitives
				(gr_poly
					(pts
						(arc
							(start -0.1778 0.2794)
							(mid -0.249642 0.249642)
							(end -0.2794 0.1778)
						)
						(arc
							(start -0.2794 -0.1778)
							(mid -0.249642 -0.249642)
							(end -0.1778 -0.2794)
						)
						(arc
							(start 0.1778 -0.2794)
							(mid 0.249642 -0.249642)
							(end 0.2794 -0.1778)
						)
						(arc
							(start 0.2794 0.1778)
							(mid 0.249642 0.249642)
							(end 0.1778 0.2794)
						)
					)
					(width 0)
					(fill yes)
				)
			)
		)
		(pad "2" smd custom
			(at 0 0.4445 270)
			(size 0.1397 0.1397)
			(layers "B.Cu" "B.Mask" "B.Paste")
			(net "I2C_EXP_LOC_SCL_OUT")
			(options
				(clearance outline)
				(anchor circle)
			)
			(primitives
				(gr_poly
					(pts
						(arc
							(start -0.1778 0.2794)
							(mid -0.249642 0.249642)
							(end -0.2794 0.1778)
						)
						(arc
							(start -0.2794 -0.1778)
							(mid -0.249642 -0.249642)
							(end -0.1778 -0.2794)
						)
						(arc
							(start 0.1778 -0.2794)
							(mid 0.249642 -0.249642)
							(end 0.2794 -0.1778)
						)
						(arc
							(start 0.2794 0.1778)
							(mid 0.249642 0.249642)
							(end 0.1778 0.2794)
						)
					)
					(width 0)
					(fill yes)
				)
			)
		)
	)
	(footprint ""
		(layer "B.Cu")
		(at 25.89022 -146.418808 90)
		(property "Reference" "C73"
			(at 0 0 90)
			(layer "B.SilkS")
			(hide yes)
			(effects
				(font
					(size 1.27 1.27)
				)
				(justify mirror)
			)
		)
		(property "Value" "SCD1U16V2KX-3GP"
			(at -1.1811 -2.7051 90)
			(unlocked yes)
			(layer "B.Fab")
			(hide yes)
			(effects
				(font
					(size 1.016 1.016)
					(thickness 0.1524)
				)
				(justify mirror)
			)
		)
		(property "Device Type" "C402H22"
			(at -1.1811 -4.2291 90)
			(unlocked yes)
			(layer "B.Fab")
			(hide yes)
			(effects
				(font
					(size 1.016 1.016)
					(thickness 0.1524)
				)
				(justify mirror)
			)
		)
		(duplicate_pad_numbers_are_jumpers no)
		(fp_rect
			(start 0.4318 0.9525)
			(end -0.4318 -0.9525)
			(stroke
				(width 0)
				(type default)
			)
			(fill no)
			(layer "B.CrtYd")
		)
		(fp_rect
			(start 0.4318 0.9525)
			(end -0.4318 -0.9525)
			(stroke
				(width 0)
				(type default)
			)
			(fill no)
			(layer "B.Fab")
		)
		(pad "1" smd custom
			(at 0 -0.4445 270)
			(size 0.1524 0.1524)
			(layers "B.Cu" "B.Mask" "B.Paste")
			(net "GND")
			(options
				(clearance outline)
				(anchor circle)
			)
			(primitives
				(gr_poly
					(pts
						(arc
							(start 0.3048 0.2032)
							(mid 0.275042 0.275042)
							(end 0.2032 0.3048)
						)
						(arc
							(start -0.2032 0.3048)
							(mid -0.275042 0.275042)
							(end -0.3048 0.2032)
						)
						(arc
							(start -0.3048 -0.2032)
							(mid -0.275042 -0.275042)
							(end -0.2032 -0.3048)
						)
						(arc
							(start 0.2032 -0.3048)
							(mid 0.275042 -0.275042)
							(end 0.3048 -0.2032)
						)
					)
					(width 0)
					(fill yes)
				)
			)
		)
		(pad "2" smd custom
			(at 0 0.4445 270)
			(size 0.1524 0.1524)
			(layers "B.Cu" "B.Mask" "B.Paste")
			(net "P1V2_STBY")
			(options
				(clearance outline)
				(anchor circle)
			)
			(primitives
				(gr_poly
					(pts
						(arc
							(start 0.3048 0.2032)
							(mid 0.275042 0.275042)
							(end 0.2032 0.3048)
						)
						(arc
							(start -0.2032 0.3048)
							(mid -0.275042 0.275042)
							(end -0.3048 0.2032)
						)
						(arc
							(start -0.3048 -0.2032)
							(mid -0.275042 -0.275042)
							(end -0.2032 -0.3048)
						)
						(arc
							(start 0.2032 -0.3048)
							(mid 0.275042 -0.275042)
							(end 0.3048 -0.2032)
						)
					)
					(width 0)
					(fill yes)
				)
			)
		)
	)
	(footprint ""
		(layer "B.Cu")
		(at 37.592 -120.3452 180)
		(property "Reference" "R91"
			(at 0 0 0)
			(layer "B.SilkS")
			(hide yes)
			(effects
				(font
					(size 1.27 1.27)
				)
				(justify mirror)
			)
		)
		(property "Value" "300R2F-GP"
			(at -0.064008 -3.993896 180)
			(unlocked yes)
			(layer "B.Fab")
			(hide yes)
			(effects
				(font
					(size 1.016 1.016)
					(thickness 0.1524)
				)
				(justify mirror)
			)
		)
		(property "Device Type" "R402H16"
			(at -0.064008 -5.517896 180)
			(unlocked yes)
			(layer "B.Fab")
			(hide yes)
			(effects
				(font
					(size 1.016 1.016)
					(thickness 0.1524)
				)
				(justify mirror)
			)
		)
		(duplicate_pad_numbers_are_jumpers no)
		(fp_line
			(start 0.508 -0.9398)
			(end 0.508 0.9398)
			(stroke
				(width 0.1524)
				(type default)
			)
			(layer "B.SilkS")
		)
		(fp_line
			(start -0.508 -0.9398)
			(end 0.508 -0.9398)
			(stroke
				(width 0.1524)
				(type default)
			)
			(layer "B.SilkS")
		)
		(fp_rect
			(start 0.508 0.9398)
			(end -0.508 -0.9398)
			(stroke
				(width 0)
				(type default)
			)
			(fill no)
			(layer "B.CrtYd")
		)
		(fp_rect
			(start 0.508 0.9398)
			(end -0.508 -0.9398)
			(stroke
				(width 0)
				(type default)
			)
			(fill no)
			(layer "B.Fab")
		)
		(pad "1" smd custom
			(at 0 -0.4445)
			(size 0.1397 0.1397)
			(layers "B.Cu" "B.Mask" "B.Paste")
			(net "GND")
			(options
				(clearance outline)
				(anchor circle)
			)
			(primitives
				(gr_poly
					(pts
						(arc
							(start -0.1778 0.2794)
							(mid -0.249642 0.249642)
							(end -0.2794 0.1778)
						)
						(arc
							(start -0.2794 -0.1778)
							(mid -0.249642 -0.249642)
							(end -0.1778 -0.2794)
						)
						(arc
							(start 0.1778 -0.2794)
							(mid 0.249642 -0.249642)
							(end 0.2794 -0.1778)
						)
						(arc
							(start 0.2794 0.1778)
							(mid 0.249642 0.249642)
							(end 0.1778 0.2794)
						)
					)
					(width 0)
					(fill yes)
				)
			)
		)
		(pad "2" smd custom
			(at 0 0.4445)
			(size 0.1397 0.1397)
			(layers "B.Cu" "B.Mask" "B.Paste")
			(net "BMC_CPU_DIS")
			(options
				(clearance outline)
				(anchor circle)
			)
			(primitives
				(gr_poly
					(pts
						(arc
							(start -0.1778 0.2794)
							(mid -0.249642 0.249642)
							(end -0.2794 0.1778)
						)
						(arc
							(start -0.2794 -0.1778)
							(mid -0.249642 -0.249642)
							(end -0.1778 -0.2794)
						)
						(arc
							(start 0.1778 -0.2794)
							(mid 0.249642 -0.249642)
							(end 0.2794 -0.1778)
						)
						(arc
							(start 0.2794 0.1778)
							(mid 0.249642 0.249642)
							(end 0.1778 0.2794)
						)
					)
					(width 0)
					(fill yes)
				)
			)
		)
	)
	(footprint ""
		(layer "B.Cu")
		(at 198.797418 -130.391408 180)
		(property "Reference" "C609"
			(at 0 0 0)
			(layer "B.SilkS")
			(hide yes)
			(effects
				(font
					(size 1.27 1.27)
				)
				(justify mirror)
			)
		)
		(property "Value" "SCD1U16V2KX-3GP"
			(at -1.1811 -2.7051 180)
			(unlocked yes)
			(layer "B.Fab")
			(hide yes)
			(effects
				(font
					(size 1.016 1.016)
					(thickness 0.1524)
				)
				(justify mirror)
			)
		)
		(property "Device Type" "C402H22"
			(at -1.1811 -4.2291 180)
			(unlocked yes)
			(layer "B.Fab")
			(hide yes)
			(effects
				(font
					(size 1.016 1.016)
					(thickness 0.1524)
				)
				(justify mirror)
			)
		)
		(duplicate_pad_numbers_are_jumpers no)
		(fp_rect
			(start 0.4318 0.9525)
			(end -0.4318 -0.9525)
			(stroke
				(width 0)
				(type default)
			)
			(fill no)
			(layer "B.CrtYd")
		)
		(fp_rect
			(start 0.4318 0.9525)
			(end -0.4318 -0.9525)
			(stroke
				(width 0)
				(type default)
			)
			(fill no)
			(layer "B.Fab")
		)
		(pad "1" smd custom
			(at 0 -0.4445)
			(size 0.1524 0.1524)
			(layers "B.Cu" "B.Mask" "B.Paste")
			(net "P3V3_M2")
			(options
				(clearance outline)
				(anchor circle)
			)
			(primitives
				(gr_poly
					(pts
						(arc
							(start 0.3048 0.2032)
							(mid 0.275042 0.275042)
							(end 0.2032 0.3048)
						)
						(arc
							(start -0.2032 0.3048)
							(mid -0.275042 0.275042)
							(end -0.3048 0.2032)
						)
						(arc
							(start -0.3048 -0.2032)
							(mid -0.275042 -0.275042)
							(end -0.2032 -0.3048)
						)
						(arc
							(start 0.2032 -0.3048)
							(mid 0.275042 -0.275042)
							(end 0.3048 -0.2032)
						)
					)
					(width 0)
					(fill yes)
				)
			)
		)
		(pad "2" smd custom
			(at 0 0.4445)
			(size 0.1524 0.1524)
			(layers "B.Cu" "B.Mask" "B.Paste")
			(net "GND")
			(options
				(clearance outline)
				(anchor circle)
			)
			(primitives
				(gr_poly
					(pts
						(arc
							(start 0.3048 0.2032)
							(mid 0.275042 0.275042)
							(end 0.2032 0.3048)
						)
						(arc
							(start -0.2032 0.3048)
							(mid -0.275042 0.275042)
							(end -0.3048 0.2032)
						)
						(arc
							(start -0.3048 -0.2032)
							(mid -0.275042 -0.275042)
							(end -0.2032 -0.3048)
						)
						(arc
							(start 0.2032 -0.3048)
							(mid 0.275042 -0.275042)
							(end 0.3048 -0.2032)
						)
					)
					(width 0)
					(fill yes)
				)
			)
		)
	)
	(footprint ""
		(layer "B.Cu")
		(at 69.547486 -142.776194 180)
		(property "Reference" "R193"
			(at 0 0 0)
			(layer "B.SilkS")
			(hide yes)
			(effects
				(font
					(size 1.27 1.27)
				)
				(justify mirror)
			)
		)
		(property "Value" "20KR2F-L-GP"
			(at -0.064008 -3.993896 180)
			(unlocked yes)
			(layer "B.Fab")
			(hide yes)
			(effects
				(font
					(size 1.016 1.016)
					(thickness 0.1524)
				)
				(justify mirror)
			)
		)
		(property "Device Type" "R402H16"
			(at -0.064008 -5.517896 180)
			(unlocked yes)
			(layer "B.Fab")
			(hide yes)
			(effects
				(font
					(size 1.016 1.016)
					(thickness 0.1524)
				)
				(justify mirror)
			)
		)
		(duplicate_pad_numbers_are_jumpers no)
		(fp_line
			(start 0.508 -0.9398)
			(end 0.508 0.9398)
			(stroke
				(width 0.1524)
				(type default)
			)
			(layer "B.SilkS")
		)
		(fp_line
			(start -0.508 -0.9398)
			(end 0.508 -0.9398)
			(stroke
				(width 0.1524)
				(type default)
			)
			(layer "B.SilkS")
		)
		(fp_rect
			(start 0.508 0.9398)
			(end -0.508 -0.9398)
			(stroke
				(width 0)
				(type default)
			)
			(fill no)
			(layer "B.CrtYd")
		)
		(fp_rect
			(start 0.508 0.9398)
			(end -0.508 -0.9398)
			(stroke
				(width 0)
				(type default)
			)
			(fill no)
			(layer "B.Fab")
		)
		(pad "1" smd custom
			(at 0 -0.4445)
			(size 0.1397 0.1397)
			(layers "B.Cu" "B.Mask" "B.Paste")
			(net "P3V3_STBY")
			(options
				(clearance outline)
				(anchor circle)
			)
			(primitives
				(gr_poly
					(pts
						(arc
							(start -0.1778 0.2794)
							(mid -0.249642 0.249642)
							(end -0.2794 0.1778)
						)
						(arc
							(start -0.2794 -0.1778)
							(mid -0.249642 -0.249642)
							(end -0.1778 -0.2794)
						)
						(arc
							(start 0.1778 -0.2794)
							(mid 0.249642 -0.249642)
							(end 0.2794 -0.1778)
						)
						(arc
							(start 0.2794 0.1778)
							(mid 0.249642 0.249642)
							(end 0.1778 0.2794)
						)
					)
					(width 0)
					(fill yes)
				)
			)
		)
		(pad "2" smd custom
			(at 0 0.4445)
			(size 0.1397 0.1397)
			(layers "B.Cu" "B.Mask" "B.Paste")
			(net "I2C_DEBUG_SCL_L")
			(options
				(clearance outline)
				(anchor circle)
			)
			(primitives
				(gr_poly
					(pts
						(arc
							(start -0.1778 0.2794)
							(mid -0.249642 0.249642)
							(end -0.2794 0.1778)
						)
						(arc
							(start -0.2794 -0.1778)
							(mid -0.249642 -0.249642)
							(end -0.1778 -0.2794)
						)
						(arc
							(start 0.1778 -0.2794)
							(mid 0.249642 -0.249642)
							(end 0.2794 -0.1778)
						)
						(arc
							(start 0.2794 0.1778)
							(mid 0.249642 0.249642)
							(end 0.1778 0.2794)
						)
					)
					(width 0)
					(fill yes)
				)
			)
		)
	)
	(footprint ""
		(layer "B.Cu")
		(at 38.1 -149.987 90)
		(property "Reference" "R740"
			(at 0 0 90)
			(layer "B.SilkS")
			(hide yes)
			(effects
				(font
					(size 1.27 1.27)
				)
				(justify mirror)
			)
		)
		(property "Value" "4K7R2F-GP"
			(at -0.064008 -3.993896 90)
			(unlocked yes)
			(layer "B.Fab")
			(hide yes)
			(effects
				(font
					(size 1.016 1.016)
					(thickness 0.1524)
				)
				(justify mirror)
			)
		)
		(property "Device Type" "R402H16"
			(at -0.064008 -5.517896 90)
			(unlocked yes)
			(layer "B.Fab")
			(hide yes)
			(effects
				(font
					(size 1.016 1.016)
					(thickness 0.1524)
				)
				(justify mirror)
			)
		)
		(duplicate_pad_numbers_are_jumpers no)
		(fp_line
			(start 0.508 -0.9398)
			(end 0.508 0.9398)
			(stroke
				(width 0.1524)
				(type default)
			)
			(layer "B.SilkS")
		)
		(fp_line
			(start -0.508 -0.9398)
			(end 0.508 -0.9398)
			(stroke
				(width 0.1524)
				(type default)
			)
			(layer "B.SilkS")
		)
		(fp_rect
			(start 0.508 0.9398)
			(end -0.508 -0.9398)
			(stroke
				(width 0)
				(type default)
			)
			(fill no)
			(layer "B.CrtYd")
		)
		(fp_rect
			(start 0.508 0.9398)
			(end -0.508 -0.9398)
			(stroke
				(width 0)
				(type default)
			)
			(fill no)
			(layer "B.Fab")
		)
		(pad "1" smd custom
			(at 0 -0.4445 270)
			(size 0.1397 0.1397)
			(layers "B.Cu" "B.Mask" "B.Paste")
			(net "GND")
			(options
				(clearance outline)
				(anchor circle)
			)
			(primitives
				(gr_poly
					(pts
						(arc
							(start -0.1778 0.2794)
							(mid -0.249642 0.249642)
							(end -0.2794 0.1778)
						)
						(arc
							(start -0.2794 -0.1778)
							(mid -0.249642 -0.249642)
							(end -0.1778 -0.2794)
						)
						(arc
							(start 0.1778 -0.2794)
							(mid 0.249642 -0.249642)
							(end 0.2794 -0.1778)
						)
						(arc
							(start 0.2794 0.1778)
							(mid 0.249642 0.249642)
							(end 0.1778 0.2794)
						)
					)
					(width 0)
					(fill yes)
				)
			)
		)
		(pad "2" smd custom
			(at 0 0.4445 270)
			(size 0.1397 0.1397)
			(layers "B.Cu" "B.Mask" "B.Paste")
			(net "IOM_TYPE0")
			(options
				(clearance outline)
				(anchor circle)
			)
			(primitives
				(gr_poly
					(pts
						(arc
							(start -0.1778 0.2794)
							(mid -0.249642 0.249642)
							(end -0.2794 0.1778)
						)
						(arc
							(start -0.2794 -0.1778)
							(mid -0.249642 -0.249642)
							(end -0.1778 -0.2794)
						)
						(arc
							(start 0.1778 -0.2794)
							(mid 0.249642 -0.249642)
							(end 0.2794 -0.1778)
						)
						(arc
							(start 0.2794 0.1778)
							(mid 0.249642 0.249642)
							(end 0.1778 0.2794)
						)
					)
					(width 0)
					(fill yes)
				)
			)
		)
	)
	(footprint ""
		(layer "B.Cu")
		(at 77.137768 -147.114006 -90)
		(property "Reference" "U45"
			(at 0 0 90)
			(layer "B.SilkS")
			(hide yes)
			(effects
				(font
					(size 1.27 1.27)
				)
				(justify mirror)
			)
		)
		(property "Value" "PCA9306DCTT-GP"
			(at 0 -11.6332 270)
			(unlocked yes)
			(layer "B.Fab")
			(hide yes)
			(effects
				(font
					(size 1.016 1.016)
					(thickness 0.1524)
				)
				(justify mirror)
			)
		)
		(property "Device Type" "SSOIC8H52"
			(at 0 -13.1572 270)
			(unlocked yes)
			(layer "B.Fab")
			(hide yes)
			(effects
				(font
					(size 1.016 1.016)
					(thickness 0.1524)
				)
				(justify mirror)
			)
		)
		(duplicate_pad_numbers_are_jumpers no)
		(fp_line
			(start -1.0668 0.5842)
			(end 1.524 0.5842)
			(stroke
				(width 0.1524)
				(type default)
			)
			(layer "B.SilkS")
		)
		(fp_line
			(start 1.524 0.5842)
			(end 1.524 2.286)
			(stroke
				(width 0.508)
				(type default)
			)
			(layer "B.SilkS")
		)
		(fp_line
			(start 1.397 0)
			(end 1.7018 0.3048)
			(stroke
				(width 0.1524)
				(type default)
			)
			(layer "B.SilkS")
		)
		(fp_line
			(start 1.397 0)
			(end 1.7018 -0.3048)
			(stroke
				(width 0.1524)
				(type default)
			)
			(layer "B.SilkS")
		)
		(fp_line
			(start -1.0668 -0.5842)
			(end -1.0668 0.5842)
			(stroke
				(width 0.1524)
				(type default)
			)
			(layer "B.SilkS")
		)
		(fp_line
			(start 1.7018 -0.5842)
			(end 1.7018 2.286)
			(stroke
				(width 0.1524)
				(type default)
			)
			(layer "B.SilkS")
		)
		(fp_line
			(start 1.7018 -0.5842)
			(end -1.0668 -0.5842)
			(stroke
				(width 0.1524)
				(type default)
			)
			(layer "B.SilkS")
		)
		(fp_poly
			(pts
				(xy 1.1684 -0.5842) (xy -1.0668 -0.5842) (xy -1.0668 0.5842) (xy 1.1684 0.5842)
			)
			(stroke
				(width 0)
				(type default)
			)
			(fill yes)
			(layer "B.SilkS")
		)
		(fp_poly
			(pts
				(xy 1.778 2.54) (xy -1.778 2.54) (xy -1.778 -2.54) (xy 1.778 -2.54)
			)
			(stroke
				(width 0)
				(type default)
			)
			(fill no)
			(layer "B.CrtYd")
		)
		(fp_poly
			(pts
				(xy 1.778 -2.54) (xy -1.778 -2.54) (xy -1.778 2.54) (xy 1.778 2.54)
			)
			(stroke
				(width 0)
				(type default)
			)
			(fill no)
			(layer "B.Fab")
		)
		(pad "1" smd rect
			(at 0.97536 1.6256 90)
			(size 0.3556 1.524)
			(layers "B.Cu" "B.Mask" "B.Paste")
			(net "GND")
		)
		(pad "2" smd rect
			(at 0.32512 1.6256 90)
			(size 0.3556 1.524)
			(layers "B.Cu" "B.Mask" "B.Paste")
			(net "P3V3_STBY")
		)
		(pad "3" smd rect
			(at -0.32512 1.6256 90)
			(size 0.3556 1.524)
			(layers "B.Cu" "B.Mask" "B.Paste")
			(net "I2C_DEBUG_SCL")
		)
		(pad "4" smd rect
			(at -0.97536 1.6256 90)
			(size 0.3556 1.524)
			(layers "B.Cu" "B.Mask" "B.Paste")
			(net "I2C_DEBUG_SDA")
		)
		(pad "5" smd rect
			(at -0.97536 -1.6256 90)
			(size 0.3556 1.524)
			(layers "B.Cu" "B.Mask" "B.Paste")
			(net "I2C_DEBUG_SDA_L")
		)
		(pad "6" smd rect
			(at -0.32512 -1.6256 90)
			(size 0.3556 1.524)
			(layers "B.Cu" "B.Mask" "B.Paste")
			(net "I2C_DEBUG_SCL_L")
		)
		(pad "7" smd rect
			(at 0.32512 -1.6256 90)
			(size 0.3556 1.524)
			(layers "B.Cu" "B.Mask" "B.Paste")
			(net "P3V3_STBY")
		)
		(pad "8" smd rect
			(at 0.97536 -1.6256 90)
			(size 0.3556 1.524)
			(layers "B.Cu" "B.Mask" "B.Paste")
			(net "DEBUG_CARD_PRSNT")
		)
	)
	(footprint ""
		(layer "B.Cu")
		(at 45.466 -128.2192)
		(property "Reference" "R292"
			(at 0 0 0)
			(layer "B.SilkS")
			(hide yes)
			(effects
				(font
					(size 1.27 1.27)
				)
				(justify mirror)
			)
		)
		(property "Value" "0R2J-2-GP"
			(at -0.064008 -3.993896 0)
			(unlocked yes)
			(layer "B.Fab")
			(hide yes)
			(effects
				(font
					(size 1.016 1.016)
					(thickness 0.1524)
				)
				(justify mirror)
			)
		)
		(property "Device Type" "R402H16"
			(at -0.064008 -5.517896 0)
			(unlocked yes)
			(layer "B.Fab")
			(hide yes)
			(effects
				(font
					(size 1.016 1.016)
					(thickness 0.1524)
				)
				(justify mirror)
			)
		)
		(duplicate_pad_numbers_are_jumpers no)
		(fp_line
			(start -0.508 -0.9398)
			(end 0.508 -0.9398)
			(stroke
				(width 0.1524)
				(type default)
			)
			(layer "B.SilkS")
		)
		(fp_line
			(start 0.508 -0.9398)
			(end 0.508 0.9398)
			(stroke
				(width 0.1524)
				(type default)
			)
			(layer "B.SilkS")
		)
		(fp_rect
			(start 0.508 0.9398)
			(end -0.508 -0.9398)
			(stroke
				(width 0)
				(type default)
			)
			(fill no)
			(layer "B.CrtYd")
		)
		(fp_rect
			(start 0.508 0.9398)
			(end -0.508 -0.9398)
			(stroke
				(width 0)
				(type default)
			)
			(fill no)
			(layer "B.Fab")
		)
		(pad "1" smd custom
			(at 0 -0.4445 180)
			(size 0.1397 0.1397)
			(layers "B.Cu" "B.Mask" "B.Paste")
			(net "IOM_LOC_INS_N")
			(options
				(clearance outline)
				(anchor circle)
			)
			(primitives
				(gr_poly
					(pts
						(arc
							(start -0.1778 0.2794)
							(mid -0.249642 0.249642)
							(end -0.2794 0.1778)
						)
						(arc
							(start -0.2794 -0.1778)
							(mid -0.249642 -0.249642)
							(end -0.1778 -0.2794)
						)
						(arc
							(start 0.1778 -0.2794)
							(mid 0.249642 -0.249642)
							(end 0.2794 -0.1778)
						)
						(arc
							(start 0.2794 0.1778)
							(mid 0.249642 0.249642)
							(end 0.1778 0.2794)
						)
					)
					(width 0)
					(fill yes)
				)
			)
		)
		(pad "2" smd custom
			(at 0 0.4445 180)
			(size 0.1397 0.1397)
			(layers "B.Cu" "B.Mask" "B.Paste")
			(net "GND")
			(options
				(clearance outline)
				(anchor circle)
			)
			(primitives
				(gr_poly
					(pts
						(arc
							(start -0.1778 0.2794)
							(mid -0.249642 0.249642)
							(end -0.2794 0.1778)
						)
						(arc
							(start -0.2794 -0.1778)
							(mid -0.249642 -0.249642)
							(end -0.1778 -0.2794)
						)
						(arc
							(start 0.1778 -0.2794)
							(mid 0.249642 -0.249642)
							(end 0.2794 -0.1778)
						)
						(arc
							(start 0.2794 0.1778)
							(mid 0.249642 0.249642)
							(end 0.1778 0.2794)
						)
					)
					(width 0)
					(fill yes)
				)
			)
		)
	)
	(footprint ""
		(layer "B.Cu")
		(at 40.0812 -153.1366 -90)
		(property "Reference" "TP65"
			(at 0 0 90)
			(layer "B.SilkS")
			(hide yes)
			(effects
				(font
					(size 1.27 1.27)
				)
				(justify mirror)
			)
		)
		(property "Value" "TPAD28-2-GP"
			(at 0.0127 -1.6637 270)
			(unlocked yes)
			(layer "B.Fab")
			(hide yes)
			(effects
				(font
					(size 1.016 1.016)
					(thickness 0.1524)
				)
				(justify mirror)
			)
		)
		(property "Device Type" "TPAD28"
			(at 0.0127 -3.1877 270)
			(unlocked yes)
			(layer "B.Fab")
			(hide yes)
			(effects
				(font
					(size 1.016 1.016)
					(thickness 0.1524)
				)
				(justify mirror)
			)
		)
		(duplicate_pad_numbers_are_jumpers no)
		(fp_poly
			(pts
				(arc
					(start 0 -0.3556)
					(mid 0 0.3556)
					(end 0 -0.3556)
				)
			)
			(stroke
				(width 0)
				(type default)
			)
			(fill no)
			(layer "B.CrtYd")
		)
		(fp_poly
			(pts
				(arc
					(start 0 -0.6096)
					(mid 0 0.6096)
					(end 0 -0.6096)
				)
			)
			(stroke
				(width 0)
				(type default)
			)
			(fill no)
			(layer "B.Fab")
		)
		(pad "1" smd circle
			(at 0 0 90)
			(size 0.7112 0.7112)
			(layers "B.Cu" "B.Mask" "B.Paste")
			(net "TP_BMC_GPION6")
		)
	)
	(footprint ""
		(layer "B.Cu")
		(at 32.131 -155.067 90)
		(property "Reference" "R336"
			(at 0 0 90)
			(layer "B.SilkS")
			(hide yes)
			(effects
				(font
					(size 1.27 1.27)
				)
				(justify mirror)
			)
		)
		(property "Value" "4K7R2F-GP"
			(at -0.064008 -3.993896 90)
			(unlocked yes)
			(layer "B.Fab")
			(hide yes)
			(effects
				(font
					(size 1.016 1.016)
					(thickness 0.1524)
				)
				(justify mirror)
			)
		)
		(property "Device Type" "R402H16"
			(at -0.064008 -5.517896 90)
			(unlocked yes)
			(layer "B.Fab")
			(hide yes)
			(effects
				(font
					(size 1.016 1.016)
					(thickness 0.1524)
				)
				(justify mirror)
			)
		)
		(duplicate_pad_numbers_are_jumpers no)
		(fp_line
			(start 0.508 -0.9398)
			(end 0.508 0.9398)
			(stroke
				(width 0.1524)
				(type default)
			)
			(layer "B.SilkS")
		)
		(fp_line
			(start -0.508 -0.9398)
			(end 0.508 -0.9398)
			(stroke
				(width 0.1524)
				(type default)
			)
			(layer "B.SilkS")
		)
		(fp_rect
			(start 0.508 0.9398)
			(end -0.508 -0.9398)
			(stroke
				(width 0)
				(type default)
			)
			(fill no)
			(layer "B.CrtYd")
		)
		(fp_rect
			(start 0.508 0.9398)
			(end -0.508 -0.9398)
			(stroke
				(width 0)
				(type default)
			)
			(fill no)
			(layer "B.Fab")
		)
		(pad "1" smd custom
			(at 0 -0.4445 270)
			(size 0.1397 0.1397)
			(layers "B.Cu" "B.Mask" "B.Paste")
			(net "P3V3_STBY")
			(options
				(clearance outline)
				(anchor circle)
			)
			(primitives
				(gr_poly
					(pts
						(arc
							(start -0.1778 0.2794)
							(mid -0.249642 0.249642)
							(end -0.2794 0.1778)
						)
						(arc
							(start -0.2794 -0.1778)
							(mid -0.249642 -0.249642)
							(end -0.1778 -0.2794)
						)
						(arc
							(start 0.1778 -0.2794)
							(mid 0.249642 -0.249642)
							(end 0.2794 -0.1778)
						)
						(arc
							(start 0.2794 0.1778)
							(mid 0.249642 0.249642)
							(end 0.1778 0.2794)
						)
					)
					(width 0)
					(fill yes)
				)
			)
		)
		(pad "2" smd custom
			(at 0 0.4445 270)
			(size 0.1397 0.1397)
			(layers "B.Cu" "B.Mask" "B.Paste")
			(net "ENCL_FAULT_LED")
			(options
				(clearance outline)
				(anchor circle)
			)
			(primitives
				(gr_poly
					(pts
						(arc
							(start -0.1778 0.2794)
							(mid -0.249642 0.249642)
							(end -0.2794 0.1778)
						)
						(arc
							(start -0.2794 -0.1778)
							(mid -0.249642 -0.249642)
							(end -0.1778 -0.2794)
						)
						(arc
							(start 0.1778 -0.2794)
							(mid 0.249642 -0.249642)
							(end 0.2794 -0.1778)
						)
						(arc
							(start 0.2794 0.1778)
							(mid 0.249642 0.249642)
							(end 0.1778 0.2794)
						)
					)
					(width 0)
					(fill yes)
				)
			)
		)
	)
	(footprint ""
		(layer "B.Cu")
		(at 224.989644 -70.03923 90)
		(property "Reference" "C660"
			(at 0 0 90)
			(layer "B.SilkS")
			(hide yes)
			(effects
				(font
					(size 1.27 1.27)
				)
				(justify mirror)
			)
		)
		(property "Value" "SC10U6D3V5KX-4GP"
			(at 0.0762 -6.1214 90)
			(unlocked yes)
			(layer "B.Fab")
			(hide yes)
			(effects
				(font
					(size 1.016 1.016)
					(thickness 0.1524)
				)
				(justify mirror)
			)
		)
		(property "Device Type" "C805H58"
			(at 0.0762 -8.1534 90)
			(unlocked yes)
			(layer "B.Fab")
			(hide yes)
			(effects
				(font
					(size 1.016 1.016)
					(thickness 0.1524)
				)
				(justify mirror)
			)
		)
		(duplicate_pad_numbers_are_jumpers no)
		(fp_line
			(start -0.635 0)
			(end 0.635 0)
			(stroke
				(width 0.508)
				(type default)
			)
			(layer "B.SilkS")
		)
		(fp_rect
			(start 0.9652 1.778)
			(end -0.9652 -1.778)
			(stroke
				(width 0)
				(type default)
			)
			(fill no)
			(layer "B.CrtYd")
		)
		(fp_poly
			(pts
				(xy 0.9652 -1.778) (xy -0.9652 -1.778) (xy -0.9652 1.778) (xy 0.9652 1.778)
			)
			(stroke
				(width 0)
				(type default)
			)
			(fill no)
			(layer "B.Fab")
		)
		(pad "1" smd rect
			(at 0 -0.9652 270)
			(size 1.397 1.143)
			(layers "B.Cu" "B.Mask" "B.Paste")
			(net "P3V3_M2")
		)
		(pad "2" smd rect
			(at 0 0.9652 270)
			(size 1.397 1.143)
			(layers "B.Cu" "B.Mask" "B.Paste")
			(net "GND")
		)
	)
	(footprint ""
		(layer "B.Cu")
		(at 175.006 -124.614686 90)
		(property "Reference" "C621"
			(at 0 0 90)
			(layer "B.SilkS")
			(hide yes)
			(effects
				(font
					(size 1.27 1.27)
				)
				(justify mirror)
			)
		)
		(property "Value" "SC10U6D3V5KX-4GP"
			(at 0.0762 -6.1214 90)
			(unlocked yes)
			(layer "B.Fab")
			(hide yes)
			(effects
				(font
					(size 1.016 1.016)
					(thickness 0.1524)
				)
				(justify mirror)
			)
		)
		(property "Device Type" "C805H58"
			(at 0.0762 -8.1534 90)
			(unlocked yes)
			(layer "B.Fab")
			(hide yes)
			(effects
				(font
					(size 1.016 1.016)
					(thickness 0.1524)
				)
				(justify mirror)
			)
		)
		(duplicate_pad_numbers_are_jumpers no)
		(fp_line
			(start -0.635 0)
			(end 0.635 0)
			(stroke
				(width 0.508)
				(type default)
			)
			(layer "B.SilkS")
		)
		(fp_rect
			(start 0.9652 1.778)
			(end -0.9652 -1.778)
			(stroke
				(width 0)
				(type default)
			)
			(fill no)
			(layer "B.CrtYd")
		)
		(fp_poly
			(pts
				(xy 0.9652 -1.778) (xy -0.9652 -1.778) (xy -0.9652 1.778) (xy 0.9652 1.778)
			)
			(stroke
				(width 0)
				(type default)
			)
			(fill no)
			(layer "B.Fab")
		)
		(pad "1" smd rect
			(at 0 -0.9652 270)
			(size 1.397 1.143)
			(layers "B.Cu" "B.Mask" "B.Paste")
			(net "P3V3_M2")
		)
		(pad "2" smd rect
			(at 0 0.9652 270)
			(size 1.397 1.143)
			(layers "B.Cu" "B.Mask" "B.Paste")
			(net "GND")
		)
	)
	(footprint ""
		(layer "B.Cu")
		(at 38.757606 -123.896374 180)
		(property "Reference" "R350"
			(at 0 0 0)
			(layer "B.SilkS")
			(hide yes)
			(effects
				(font
					(size 1.27 1.27)
				)
				(justify mirror)
			)
		)
		(property "Value" "0R2J-2-GP"
			(at -0.064008 -3.993896 180)
			(unlocked yes)
			(layer "B.Fab")
			(hide yes)
			(effects
				(font
					(size 1.016 1.016)
					(thickness 0.1524)
				)
				(justify mirror)
			)
		)
		(property "Device Type" "R402H16"
			(at -0.064008 -5.517896 180)
			(unlocked yes)
			(layer "B.Fab")
			(hide yes)
			(effects
				(font
					(size 1.016 1.016)
					(thickness 0.1524)
				)
				(justify mirror)
			)
		)
		(duplicate_pad_numbers_are_jumpers no)
		(fp_line
			(start 0.508 -0.9398)
			(end 0.508 0.9398)
			(stroke
				(width 0.1524)
				(type default)
			)
			(layer "B.SilkS")
		)
		(fp_line
			(start -0.508 -0.9398)
			(end 0.508 -0.9398)
			(stroke
				(width 0.1524)
				(type default)
			)
			(layer "B.SilkS")
		)
		(fp_rect
			(start 0.508 0.9398)
			(end -0.508 -0.9398)
			(stroke
				(width 0)
				(type default)
			)
			(fill no)
			(layer "B.CrtYd")
		)
		(fp_rect
			(start 0.508 0.9398)
			(end -0.508 -0.9398)
			(stroke
				(width 0)
				(type default)
			)
			(fill no)
			(layer "B.Fab")
		)
		(pad "1" smd custom
			(at 0 -0.4445)
			(size 0.1397 0.1397)
			(layers "B.Cu" "B.Mask" "B.Paste")
			(net "FM_TPM_PRSNT_N")
			(options
				(clearance outline)
				(anchor circle)
			)
			(primitives
				(gr_poly
					(pts
						(arc
							(start -0.1778 0.2794)
							(mid -0.249642 0.249642)
							(end -0.2794 0.1778)
						)
						(arc
							(start -0.2794 -0.1778)
							(mid -0.249642 -0.249642)
							(end -0.1778 -0.2794)
						)
						(arc
							(start 0.1778 -0.2794)
							(mid 0.249642 -0.249642)
							(end 0.2794 -0.1778)
						)
						(arc
							(start 0.2794 0.1778)
							(mid 0.249642 0.249642)
							(end 0.1778 0.2794)
						)
					)
					(width 0)
					(fill yes)
				)
			)
		)
		(pad "2" smd custom
			(at 0 0.4445)
			(size 0.1397 0.1397)
			(layers "B.Cu" "B.Mask" "B.Paste")
			(net "TPM_PRSNT_N_R")
			(options
				(clearance outline)
				(anchor circle)
			)
			(primitives
				(gr_poly
					(pts
						(arc
							(start -0.1778 0.2794)
							(mid -0.249642 0.249642)
							(end -0.2794 0.1778)
						)
						(arc
							(start -0.2794 -0.1778)
							(mid -0.249642 -0.249642)
							(end -0.1778 -0.2794)
						)
						(arc
							(start 0.1778 -0.2794)
							(mid 0.249642 -0.249642)
							(end 0.2794 -0.1778)
						)
						(arc
							(start 0.2794 0.1778)
							(mid 0.249642 0.249642)
							(end 0.1778 0.2794)
						)
					)
					(width 0)
					(fill yes)
				)
			)
		)
	)
	(footprint ""
		(layer "B.Cu")
		(at 95.91421 -156.82595 -90)
		(property "Reference" "R22"
			(at 0 0 90)
			(layer "B.SilkS")
			(hide yes)
			(effects
				(font
					(size 1.27 1.27)
				)
				(justify mirror)
			)
		)
		(property "Value" "4K7R2F-GP"
			(at -0.064008 -3.993896 270)
			(unlocked yes)
			(layer "B.Fab")
			(hide yes)
			(effects
				(font
					(size 1.016 1.016)
					(thickness 0.1524)
				)
				(justify mirror)
			)
		)
		(property "Device Type" "R402H16"
			(at -0.064008 -5.517896 270)
			(unlocked yes)
			(layer "B.Fab")
			(hide yes)
			(effects
				(font
					(size 1.016 1.016)
					(thickness 0.1524)
				)
				(justify mirror)
			)
		)
		(duplicate_pad_numbers_are_jumpers no)
		(fp_line
			(start -0.508 -0.9398)
			(end 0.508 -0.9398)
			(stroke
				(width 0.1524)
				(type default)
			)
			(layer "B.SilkS")
		)
		(fp_line
			(start 0.508 -0.9398)
			(end 0.508 0.9398)
			(stroke
				(width 0.1524)
				(type default)
			)
			(layer "B.SilkS")
		)
		(fp_rect
			(start 0.508 0.9398)
			(end -0.508 -0.9398)
			(stroke
				(width 0)
				(type default)
			)
			(fill no)
			(layer "B.CrtYd")
		)
		(fp_rect
			(start 0.508 0.9398)
			(end -0.508 -0.9398)
			(stroke
				(width 0)
				(type default)
			)
			(fill no)
			(layer "B.Fab")
		)
		(pad "1" smd custom
			(at 0 -0.4445 90)
			(size 0.1397 0.1397)
			(layers "B.Cu" "B.Mask" "B.Paste")
			(net "CFG_SEL1")
			(options
				(clearance outline)
				(anchor circle)
			)
			(primitives
				(gr_poly
					(pts
						(arc
							(start -0.1778 0.2794)
							(mid -0.249642 0.249642)
							(end -0.2794 0.1778)
						)
						(arc
							(start -0.2794 -0.1778)
							(mid -0.249642 -0.249642)
							(end -0.1778 -0.2794)
						)
						(arc
							(start 0.1778 -0.2794)
							(mid 0.249642 -0.249642)
							(end 0.2794 -0.1778)
						)
						(arc
							(start 0.2794 0.1778)
							(mid 0.249642 0.249642)
							(end 0.1778 0.2794)
						)
					)
					(width 0)
					(fill yes)
				)
			)
		)
		(pad "2" smd custom
			(at 0 0.4445 90)
			(size 0.1397 0.1397)
			(layers "B.Cu" "B.Mask" "B.Paste")
			(net "GND")
			(options
				(clearance outline)
				(anchor circle)
			)
			(primitives
				(gr_poly
					(pts
						(arc
							(start -0.1778 0.2794)
							(mid -0.249642 0.249642)
							(end -0.2794 0.1778)
						)
						(arc
							(start -0.2794 -0.1778)
							(mid -0.249642 -0.249642)
							(end -0.1778 -0.2794)
						)
						(arc
							(start 0.1778 -0.2794)
							(mid 0.249642 -0.249642)
							(end 0.2794 -0.1778)
						)
						(arc
							(start 0.2794 0.1778)
							(mid 0.249642 0.249642)
							(end 0.1778 0.2794)
						)
					)
					(width 0)
					(fill yes)
				)
			)
		)
	)
	(footprint ""
		(layer "B.Cu")
		(at 51.3842 -154.6352 -90)
		(property "Reference" "R366"
			(at 0 0 90)
			(layer "B.SilkS")
			(hide yes)
			(effects
				(font
					(size 1.27 1.27)
				)
				(justify mirror)
			)
		)
		(property "Value" "49K9R2F-L-GP"
			(at -0.064008 -3.993896 270)
			(unlocked yes)
			(layer "B.Fab")
			(hide yes)
			(effects
				(font
					(size 1.016 1.016)
					(thickness 0.1524)
				)
				(justify mirror)
			)
		)
		(property "Device Type" "R402H16"
			(at -0.064008 -5.517896 270)
			(unlocked yes)
			(layer "B.Fab")
			(hide yes)
			(effects
				(font
					(size 1.016 1.016)
					(thickness 0.1524)
				)
				(justify mirror)
			)
		)
		(duplicate_pad_numbers_are_jumpers no)
		(fp_line
			(start -0.508 -0.9398)
			(end 0.508 -0.9398)
			(stroke
				(width 0.1524)
				(type default)
			)
			(layer "B.SilkS")
		)
		(fp_line
			(start 0.508 -0.9398)
			(end 0.508 0.9398)
			(stroke
				(width 0.1524)
				(type default)
			)
			(layer "B.SilkS")
		)
		(fp_rect
			(start 0.508 0.9398)
			(end -0.508 -0.9398)
			(stroke
				(width 0)
				(type default)
			)
			(fill no)
			(layer "B.CrtYd")
		)
		(fp_rect
			(start 0.508 0.9398)
			(end -0.508 -0.9398)
			(stroke
				(width 0)
				(type default)
			)
			(fill no)
			(layer "B.Fab")
		)
		(pad "1" smd custom
			(at 0 -0.4445 90)
			(size 0.1397 0.1397)
			(layers "B.Cu" "B.Mask" "B.Paste")
			(net "GND")
			(options
				(clearance outline)
				(anchor circle)
			)
			(primitives
				(gr_poly
					(pts
						(arc
							(start -0.1778 0.2794)
							(mid -0.249642 0.249642)
							(end -0.2794 0.1778)
						)
						(arc
							(start -0.2794 -0.1778)
							(mid -0.249642 -0.249642)
							(end -0.1778 -0.2794)
						)
						(arc
							(start 0.1778 -0.2794)
							(mid 0.249642 -0.249642)
							(end 0.2794 -0.1778)
						)
						(arc
							(start 0.2794 0.1778)
							(mid 0.249642 0.249642)
							(end 0.1778 0.2794)
						)
					)
					(width 0)
					(fill yes)
				)
			)
		)
		(pad "2" smd custom
			(at 0 0.4445 90)
			(size 0.1397 0.1397)
			(layers "B.Cu" "B.Mask" "B.Paste")
			(net "ADCVREXT")
			(options
				(clearance outline)
				(anchor circle)
			)
			(primitives
				(gr_poly
					(pts
						(arc
							(start -0.1778 0.2794)
							(mid -0.249642 0.249642)
							(end -0.2794 0.1778)
						)
						(arc
							(start -0.2794 -0.1778)
							(mid -0.249642 -0.249642)
							(end -0.1778 -0.2794)
						)
						(arc
							(start 0.1778 -0.2794)
							(mid 0.249642 -0.249642)
							(end 0.2794 -0.1778)
						)
						(arc
							(start 0.2794 0.1778)
							(mid 0.249642 0.249642)
							(end 0.1778 0.2794)
						)
					)
					(width 0)
					(fill yes)
				)
			)
		)
	)
	(footprint ""
		(layer "B.Cu")
		(at 95.939356 -158.69412 180)
		(property "Reference" "C8"
			(at 0 0 0)
			(layer "B.SilkS")
			(hide yes)
			(effects
				(font
					(size 1.27 1.27)
				)
				(justify mirror)
			)
		)
		(property "Value" "SC1U16V3KX-5GP"
			(at 0 -2.8194 180)
			(unlocked yes)
			(layer "B.Fab")
			(hide yes)
			(effects
				(font
					(size 1.016 1.016)
					(thickness 0.1524)
				)
				(justify mirror)
			)
		)
		(property "Device Type" "C603H36"
			(at 0 -4.3434 180)
			(unlocked yes)
			(layer "B.Fab")
			(hide yes)
			(effects
				(font
					(size 1.016 1.016)
					(thickness 0.1524)
				)
				(justify mirror)
			)
		)
		(duplicate_pad_numbers_are_jumpers no)
		(fp_line
			(start -0.508 0)
			(end 0.508 0)
			(stroke
				(width 0.2032)
				(type default)
			)
			(layer "B.SilkS")
		)
		(fp_rect
			(start 0.5842 1.3335)
			(end -0.5842 -1.3335)
			(stroke
				(width 0)
				(type default)
			)
			(fill no)
			(layer "B.CrtYd")
		)
		(fp_rect
			(start 0.5842 1.3335)
			(end -0.5842 -1.3335)
			(stroke
				(width 0)
				(type default)
			)
			(fill no)
			(layer "B.Fab")
		)
		(pad "1" smd custom
			(at 0 -0.762)
			(size 0.2159 0.2159)
			(layers "B.Cu" "B.Mask" "B.Paste")
			(net "USB_RESET_N")
			(options
				(clearance outline)
				(anchor circle)
			)
			(primitives
				(gr_poly
					(pts
						(arc
							(start -0.3302 0.4318)
							(mid -0.402042 0.402042)
							(end -0.4318 0.3302)
						)
						(arc
							(start -0.4318 -0.3302)
							(mid -0.402042 -0.402042)
							(end -0.3302 -0.4318)
						)
						(arc
							(start 0.3302 -0.4318)
							(mid 0.402042 -0.402042)
							(end 0.4318 -0.3302)
						)
						(arc
							(start 0.4318 0.3302)
							(mid 0.402042 0.402042)
							(end 0.3302 0.4318)
						)
					)
					(width 0)
					(fill yes)
				)
			)
		)
		(pad "2" smd custom
			(at 0 0.762)
			(size 0.2159 0.2159)
			(layers "B.Cu" "B.Mask" "B.Paste")
			(net "GND")
			(options
				(clearance outline)
				(anchor circle)
			)
			(primitives
				(gr_poly
					(pts
						(arc
							(start -0.3302 0.4318)
							(mid -0.402042 0.402042)
							(end -0.4318 0.3302)
						)
						(arc
							(start -0.4318 -0.3302)
							(mid -0.402042 -0.402042)
							(end -0.3302 -0.4318)
						)
						(arc
							(start 0.3302 -0.4318)
							(mid 0.402042 -0.402042)
							(end 0.4318 -0.3302)
						)
						(arc
							(start 0.4318 0.3302)
							(mid 0.402042 0.402042)
							(end 0.3302 0.4318)
						)
					)
					(width 0)
					(fill yes)
				)
			)
		)
	)
	(footprint ""
		(layer "B.Cu")
		(at 31.1404 -152.0444)
		(property "Reference" "L3"
			(at 0 0 0)
			(layer "B.SilkS")
			(hide yes)
			(effects
				(font
					(size 1.27 1.27)
				)
				(justify mirror)
			)
		)
		(property "Value" "MMZ2012S601ATA1N-GP"
			(at 0 -4.2418 0)
			(unlocked yes)
			(layer "B.Fab")
			(hide yes)
			(effects
				(font
					(size 1.016 1.016)
					(thickness 0.1524)
				)
				(justify mirror)
			)
		)
		(property "Device Type" "L805H42"
			(at 0 -5.7912 0)
			(unlocked yes)
			(layer "B.Fab")
			(hide yes)
			(effects
				(font
					(size 1.016 1.016)
					(thickness 0.1524)
				)
				(justify mirror)
			)
		)
		(duplicate_pad_numbers_are_jumpers no)
		(fp_line
			(start -0.889 -1.7018)
			(end -0.889 1.7018)
			(stroke
				(width 0.1524)
				(type default)
			)
			(layer "B.SilkS")
		)
		(fp_line
			(start -0.889 1.7018)
			(end 0.889 1.7018)
			(stroke
				(width 0.1524)
				(type default)
			)
			(layer "B.SilkS")
		)
		(fp_line
			(start 0.889 -1.7018)
			(end -0.889 -1.7018)
			(stroke
				(width 0.1524)
				(type default)
			)
			(layer "B.SilkS")
		)
		(fp_line
			(start 0.889 1.7018)
			(end 0.889 -1.7018)
			(stroke
				(width 0.1524)
				(type default)
			)
			(layer "B.SilkS")
		)
		(fp_rect
			(start 0.9652 1.778)
			(end -0.9652 -1.778)
			(stroke
				(width 0)
				(type default)
			)
			(fill no)
			(layer "B.CrtYd")
		)
		(fp_rect
			(start 0.9652 1.778)
			(end -0.9652 -1.778)
			(stroke
				(width 0)
				(type default)
			)
			(fill no)
			(layer "B.Fab")
		)
		(pad "1" smd rect
			(at 0 -0.9652 180)
			(size 1.397 1.143)
			(layers "B.Cu" "B.Mask" "B.Paste")
			(net "P3V3_STBY")
		)
		(pad "2" smd rect
			(at 0 0.9652 180)
			(size 1.397 1.143)
			(layers "B.Cu" "B.Mask" "B.Paste")
			(net "MPLLAV33")
		)
	)
	(footprint ""
		(layer "B.Cu")
		(at 20.582128 -131.007358 180)
		(property "Reference" "R253"
			(at 0 0 0)
			(layer "B.SilkS")
			(hide yes)
			(effects
				(font
					(size 1.27 1.27)
				)
				(justify mirror)
			)
		)
		(property "Value" "120R2F-GP"
			(at -0.064008 -3.993896 180)
			(unlocked yes)
			(layer "B.Fab")
			(hide yes)
			(effects
				(font
					(size 1.016 1.016)
					(thickness 0.1524)
				)
				(justify mirror)
			)
		)
		(property "Device Type" "R402H16"
			(at -0.064008 -5.517896 180)
			(unlocked yes)
			(layer "B.Fab")
			(hide yes)
			(effects
				(font
					(size 1.016 1.016)
					(thickness 0.1524)
				)
				(justify mirror)
			)
		)
		(duplicate_pad_numbers_are_jumpers no)
		(fp_line
			(start 0.508 -0.9398)
			(end 0.508 0.9398)
			(stroke
				(width 0.1524)
				(type default)
			)
			(layer "B.SilkS")
		)
		(fp_line
			(start -0.508 -0.9398)
			(end 0.508 -0.9398)
			(stroke
				(width 0.1524)
				(type default)
			)
			(layer "B.SilkS")
		)
		(fp_rect
			(start 0.508 0.9398)
			(end -0.508 -0.9398)
			(stroke
				(width 0)
				(type default)
			)
			(fill no)
			(layer "B.CrtYd")
		)
		(fp_rect
			(start 0.508 0.9398)
			(end -0.508 -0.9398)
			(stroke
				(width 0)
				(type default)
			)
			(fill no)
			(layer "B.Fab")
		)
		(pad "1" smd custom
			(at 0 -0.4445)
			(size 0.1397 0.1397)
			(layers "B.Cu" "B.Mask" "B.Paste")
			(net "MEMA_9")
			(options
				(clearance outline)
				(anchor circle)
			)
			(primitives
				(gr_poly
					(pts
						(arc
							(start -0.1778 0.2794)
							(mid -0.249642 0.249642)
							(end -0.2794 0.1778)
						)
						(arc
							(start -0.2794 -0.1778)
							(mid -0.249642 -0.249642)
							(end -0.1778 -0.2794)
						)
						(arc
							(start 0.1778 -0.2794)
							(mid 0.249642 -0.249642)
							(end 0.2794 -0.1778)
						)
						(arc
							(start 0.2794 0.1778)
							(mid 0.249642 0.249642)
							(end 0.1778 0.2794)
						)
					)
					(width 0)
					(fill yes)
				)
			)
		)
		(pad "2" smd custom
			(at 0 0.4445)
			(size 0.1397 0.1397)
			(layers "B.Cu" "B.Mask" "B.Paste")
			(net "P1V2_STBY")
			(options
				(clearance outline)
				(anchor circle)
			)
			(primitives
				(gr_poly
					(pts
						(arc
							(start -0.1778 0.2794)
							(mid -0.249642 0.249642)
							(end -0.2794 0.1778)
						)
						(arc
							(start -0.2794 -0.1778)
							(mid -0.249642 -0.249642)
							(end -0.1778 -0.2794)
						)
						(arc
							(start 0.1778 -0.2794)
							(mid 0.249642 -0.249642)
							(end 0.2794 -0.1778)
						)
						(arc
							(start 0.2794 0.1778)
							(mid 0.249642 0.249642)
							(end 0.1778 0.2794)
						)
					)
					(width 0)
					(fill yes)
				)
			)
		)
	)
	(footprint ""
		(layer "B.Cu")
		(at 44.4246 -128.2192 180)
		(property "Reference" "R371"
			(at 0 0 0)
			(layer "B.SilkS")
			(hide yes)
			(effects
				(font
					(size 1.27 1.27)
				)
				(justify mirror)
			)
		)
		(property "Value" "4K7R2F-GP"
			(at -0.064008 -3.993896 180)
			(unlocked yes)
			(layer "B.Fab")
			(hide yes)
			(effects
				(font
					(size 1.016 1.016)
					(thickness 0.1524)
				)
				(justify mirror)
			)
		)
		(property "Device Type" "R402H16"
			(at -0.064008 -5.517896 180)
			(unlocked yes)
			(layer "B.Fab")
			(hide yes)
			(effects
				(font
					(size 1.016 1.016)
					(thickness 0.1524)
				)
				(justify mirror)
			)
		)
		(duplicate_pad_numbers_are_jumpers no)
		(fp_line
			(start 0.508 -0.9398)
			(end 0.508 0.9398)
			(stroke
				(width 0.1524)
				(type default)
			)
			(layer "B.SilkS")
		)
		(fp_line
			(start -0.508 -0.9398)
			(end 0.508 -0.9398)
			(stroke
				(width 0.1524)
				(type default)
			)
			(layer "B.SilkS")
		)
		(fp_rect
			(start 0.508 0.9398)
			(end -0.508 -0.9398)
			(stroke
				(width 0)
				(type default)
			)
			(fill no)
			(layer "B.CrtYd")
		)
		(fp_rect
			(start 0.508 0.9398)
			(end -0.508 -0.9398)
			(stroke
				(width 0)
				(type default)
			)
			(fill no)
			(layer "B.Fab")
		)
		(pad "1" smd custom
			(at 0 -0.4445)
			(size 0.1397 0.1397)
			(layers "B.Cu" "B.Mask" "B.Paste")
			(net "P3V3_STBY")
			(options
				(clearance outline)
				(anchor circle)
			)
			(primitives
				(gr_poly
					(pts
						(arc
							(start -0.1778 0.2794)
							(mid -0.249642 0.249642)
							(end -0.2794 0.1778)
						)
						(arc
							(start -0.2794 -0.1778)
							(mid -0.249642 -0.249642)
							(end -0.1778 -0.2794)
						)
						(arc
							(start 0.1778 -0.2794)
							(mid 0.249642 -0.249642)
							(end 0.2794 -0.1778)
						)
						(arc
							(start 0.2794 0.1778)
							(mid 0.249642 0.249642)
							(end 0.1778 0.2794)
						)
					)
					(width 0)
					(fill yes)
				)
			)
		)
		(pad "2" smd custom
			(at 0 0.4445)
			(size 0.1397 0.1397)
			(layers "B.Cu" "B.Mask" "B.Paste")
			(net "BMC_SPI_MISO")
			(options
				(clearance outline)
				(anchor circle)
			)
			(primitives
				(gr_poly
					(pts
						(arc
							(start -0.1778 0.2794)
							(mid -0.249642 0.249642)
							(end -0.2794 0.1778)
						)
						(arc
							(start -0.2794 -0.1778)
							(mid -0.249642 -0.249642)
							(end -0.1778 -0.2794)
						)
						(arc
							(start 0.1778 -0.2794)
							(mid 0.249642 -0.249642)
							(end 0.2794 -0.1778)
						)
						(arc
							(start 0.2794 0.1778)
							(mid 0.249642 0.249642)
							(end 0.1778 0.2794)
						)
					)
					(width 0)
					(fill yes)
				)
			)
		)
	)
	(footprint ""
		(layer "B.Cu")
		(at 90.084148 -132.396484)
		(property "Reference" "C503"
			(at 0 0 0)
			(layer "B.SilkS")
			(hide yes)
			(effects
				(font
					(size 1.27 1.27)
				)
				(justify mirror)
			)
		)
		(property "Value" "SCD1U16V2KX-3GP"
			(at -1.1811 -2.7051 0)
			(unlocked yes)
			(layer "B.Fab")
			(hide yes)
			(effects
				(font
					(size 1.016 1.016)
					(thickness 0.1524)
				)
				(justify mirror)
			)
		)
		(property "Device Type" "C402H22"
			(at -1.181354 -4.2291 0)
			(unlocked yes)
			(layer "B.Fab")
			(hide yes)
			(effects
				(font
					(size 1.016 1.016)
					(thickness 0.1524)
				)
				(justify mirror)
			)
		)
		(duplicate_pad_numbers_are_jumpers no)
		(fp_rect
			(start 0.4318 0.9525)
			(end -0.4318 -0.9525)
			(stroke
				(width 0)
				(type default)
			)
			(fill no)
			(layer "B.CrtYd")
		)
		(fp_rect
			(start 0.4318 0.9525)
			(end -0.4318 -0.9525)
			(stroke
				(width 0)
				(type default)
			)
			(fill no)
			(layer "B.Fab")
		)
		(pad "1" smd custom
			(at 0 -0.4445 180)
			(size 0.1524 0.1524)
			(layers "B.Cu" "B.Mask" "B.Paste")
			(net "P3V3_STBY")
			(options
				(clearance outline)
				(anchor circle)
			)
			(primitives
				(gr_poly
					(pts
						(arc
							(start 0.3048 0.2032)
							(mid 0.275042 0.275042)
							(end 0.2032 0.3048)
						)
						(arc
							(start -0.2032 0.3048)
							(mid -0.275042 0.275042)
							(end -0.3048 0.2032)
						)
						(arc
							(start -0.3048 -0.2032)
							(mid -0.275042 -0.275042)
							(end -0.2032 -0.3048)
						)
						(arc
							(start 0.2032 -0.3048)
							(mid 0.275042 -0.275042)
							(end 0.3048 -0.2032)
						)
					)
					(width 0)
					(fill yes)
				)
			)
		)
		(pad "2" smd custom
			(at 0 0.4445 180)
			(size 0.1524 0.1524)
			(layers "B.Cu" "B.Mask" "B.Paste")
			(net "GND")
			(options
				(clearance outline)
				(anchor circle)
			)
			(primitives
				(gr_poly
					(pts
						(arc
							(start 0.3048 0.2032)
							(mid 0.275042 0.275042)
							(end 0.2032 0.3048)
						)
						(arc
							(start -0.2032 0.3048)
							(mid -0.275042 0.275042)
							(end -0.3048 0.2032)
						)
						(arc
							(start -0.3048 -0.2032)
							(mid -0.275042 -0.275042)
							(end -0.2032 -0.3048)
						)
						(arc
							(start 0.2032 -0.3048)
							(mid 0.275042 -0.275042)
							(end 0.3048 -0.2032)
						)
					)
					(width 0)
					(fill yes)
				)
			)
		)
	)
	(footprint ""
		(layer "B.Cu")
		(at 24.456898 -145.973546)
		(property "Reference" "C72"
			(at 0 0 0)
			(layer "B.SilkS")
			(hide yes)
			(effects
				(font
					(size 1.27 1.27)
				)
				(justify mirror)
			)
		)
		(property "Value" "SCD1U16V2KX-3GP"
			(at -1.1811 -2.7051 0)
			(unlocked yes)
			(layer "B.Fab")
			(hide yes)
			(effects
				(font
					(size 1.016 1.016)
					(thickness 0.1524)
				)
				(justify mirror)
			)
		)
		(property "Device Type" "C402H22"
			(at -1.1811 -4.2291 0)
			(unlocked yes)
			(layer "B.Fab")
			(hide yes)
			(effects
				(font
					(size 1.016 1.016)
					(thickness 0.1524)
				)
				(justify mirror)
			)
		)
		(duplicate_pad_numbers_are_jumpers no)
		(fp_rect
			(start 0.4318 0.9525)
			(end -0.4318 -0.9525)
			(stroke
				(width 0)
				(type default)
			)
			(fill no)
			(layer "B.CrtYd")
		)
		(fp_rect
			(start 0.4318 0.9525)
			(end -0.4318 -0.9525)
			(stroke
				(width 0)
				(type default)
			)
			(fill no)
			(layer "B.Fab")
		)
		(pad "1" smd custom
			(at 0 -0.4445 180)
			(size 0.1524 0.1524)
			(layers "B.Cu" "B.Mask" "B.Paste")
			(net "GND")
			(options
				(clearance outline)
				(anchor circle)
			)
			(primitives
				(gr_poly
					(pts
						(arc
							(start 0.3048 0.2032)
							(mid 0.275042 0.275042)
							(end 0.2032 0.3048)
						)
						(arc
							(start -0.2032 0.3048)
							(mid -0.275042 0.275042)
							(end -0.3048 0.2032)
						)
						(arc
							(start -0.3048 -0.2032)
							(mid -0.275042 -0.275042)
							(end -0.2032 -0.3048)
						)
						(arc
							(start 0.2032 -0.3048)
							(mid 0.275042 -0.275042)
							(end 0.3048 -0.2032)
						)
					)
					(width 0)
					(fill yes)
				)
			)
		)
		(pad "2" smd custom
			(at 0 0.4445 180)
			(size 0.1524 0.1524)
			(layers "B.Cu" "B.Mask" "B.Paste")
			(net "P1V2_STBY")
			(options
				(clearance outline)
				(anchor circle)
			)
			(primitives
				(gr_poly
					(pts
						(arc
							(start 0.3048 0.2032)
							(mid 0.275042 0.275042)
							(end 0.2032 0.3048)
						)
						(arc
							(start -0.2032 0.3048)
							(mid -0.275042 0.275042)
							(end -0.3048 0.2032)
						)
						(arc
							(start -0.3048 -0.2032)
							(mid -0.275042 -0.275042)
							(end -0.2032 -0.3048)
						)
						(arc
							(start 0.2032 -0.3048)
							(mid 0.275042 -0.275042)
							(end 0.3048 -0.2032)
						)
					)
					(width 0)
					(fill yes)
				)
			)
		)
	)
	(footprint ""
		(layer "B.Cu")
		(at 10.193528 -132.402834 90)
		(property "Reference" "R237"
			(at 0 0 90)
			(layer "B.SilkS")
			(hide yes)
			(effects
				(font
					(size 1.27 1.27)
				)
				(justify mirror)
			)
		)
		(property "Value" "120R2F-GP"
			(at -0.064008 -3.993896 90)
			(unlocked yes)
			(layer "B.Fab")
			(hide yes)
			(effects
				(font
					(size 1.016 1.016)
					(thickness 0.1524)
				)
				(justify mirror)
			)
		)
		(property "Device Type" "R402H16"
			(at -0.064008 -5.517896 90)
			(unlocked yes)
			(layer "B.Fab")
			(hide yes)
			(effects
				(font
					(size 1.016 1.016)
					(thickness 0.1524)
				)
				(justify mirror)
			)
		)
		(duplicate_pad_numbers_are_jumpers no)
		(fp_line
			(start 0.508 -0.9398)
			(end 0.508 0.9398)
			(stroke
				(width 0.1524)
				(type default)
			)
			(layer "B.SilkS")
		)
		(fp_line
			(start -0.508 -0.9398)
			(end 0.508 -0.9398)
			(stroke
				(width 0.1524)
				(type default)
			)
			(layer "B.SilkS")
		)
		(fp_rect
			(start 0.508 0.9398)
			(end -0.508 -0.9398)
			(stroke
				(width 0)
				(type default)
			)
			(fill no)
			(layer "B.CrtYd")
		)
		(fp_rect
			(start 0.508 0.9398)
			(end -0.508 -0.9398)
			(stroke
				(width 0)
				(type default)
			)
			(fill no)
			(layer "B.Fab")
		)
		(pad "1" smd custom
			(at 0 -0.4445 270)
			(size 0.1397 0.1397)
			(layers "B.Cu" "B.Mask" "B.Paste")
			(net "GND")
			(options
				(clearance outline)
				(anchor circle)
			)
			(primitives
				(gr_poly
					(pts
						(arc
							(start -0.1778 0.2794)
							(mid -0.249642 0.249642)
							(end -0.2794 0.1778)
						)
						(arc
							(start -0.2794 -0.1778)
							(mid -0.249642 -0.249642)
							(end -0.1778 -0.2794)
						)
						(arc
							(start 0.1778 -0.2794)
							(mid 0.249642 -0.249642)
							(end 0.2794 -0.1778)
						)
						(arc
							(start 0.2794 0.1778)
							(mid 0.249642 0.249642)
							(end 0.1778 0.2794)
						)
					)
					(width 0)
					(fill yes)
				)
			)
		)
		(pad "2" smd custom
			(at 0 0.4445 270)
			(size 0.1397 0.1397)
			(layers "B.Cu" "B.Mask" "B.Paste")
			(net "MEMA_2")
			(options
				(clearance outline)
				(anchor circle)
			)
			(primitives
				(gr_poly
					(pts
						(arc
							(start -0.1778 0.2794)
							(mid -0.249642 0.249642)
							(end -0.2794 0.1778)
						)
						(arc
							(start -0.2794 -0.1778)
							(mid -0.249642 -0.249642)
							(end -0.1778 -0.2794)
						)
						(arc
							(start 0.1778 -0.2794)
							(mid 0.249642 -0.249642)
							(end 0.2794 -0.1778)
						)
						(arc
							(start 0.2794 0.1778)
							(mid 0.249642 0.249642)
							(end 0.1778 0.2794)
						)
					)
					(width 0)
					(fill yes)
				)
			)
		)
	)
	(footprint ""
		(layer "B.Cu")
		(at 16.294354 -131.007358 180)
		(property "Reference" "R259"
			(at 0 0 0)
			(layer "B.SilkS")
			(hide yes)
			(effects
				(font
					(size 1.27 1.27)
				)
				(justify mirror)
			)
		)
		(property "Value" "120R2F-GP"
			(at -0.064008 -3.993896 180)
			(unlocked yes)
			(layer "B.Fab")
			(hide yes)
			(effects
				(font
					(size 1.016 1.016)
					(thickness 0.1524)
				)
				(justify mirror)
			)
		)
		(property "Device Type" "R402H16"
			(at -0.064008 -5.517896 180)
			(unlocked yes)
			(layer "B.Fab")
			(hide yes)
			(effects
				(font
					(size 1.016 1.016)
					(thickness 0.1524)
				)
				(justify mirror)
			)
		)
		(duplicate_pad_numbers_are_jumpers no)
		(fp_line
			(start 0.508 -0.9398)
			(end 0.508 0.9398)
			(stroke
				(width 0.1524)
				(type default)
			)
			(layer "B.SilkS")
		)
		(fp_line
			(start -0.508 -0.9398)
			(end 0.508 -0.9398)
			(stroke
				(width 0.1524)
				(type default)
			)
			(layer "B.SilkS")
		)
		(fp_rect
			(start 0.508 0.9398)
			(end -0.508 -0.9398)
			(stroke
				(width 0)
				(type default)
			)
			(fill no)
			(layer "B.CrtYd")
		)
		(fp_rect
			(start 0.508 0.9398)
			(end -0.508 -0.9398)
			(stroke
				(width 0)
				(type default)
			)
			(fill no)
			(layer "B.Fab")
		)
		(pad "1" smd custom
			(at 0 -0.4445)
			(size 0.1397 0.1397)
			(layers "B.Cu" "B.Mask" "B.Paste")
			(net "MEMA_12")
			(options
				(clearance outline)
				(anchor circle)
			)
			(primitives
				(gr_poly
					(pts
						(arc
							(start -0.1778 0.2794)
							(mid -0.249642 0.249642)
							(end -0.2794 0.1778)
						)
						(arc
							(start -0.2794 -0.1778)
							(mid -0.249642 -0.249642)
							(end -0.1778 -0.2794)
						)
						(arc
							(start 0.1778 -0.2794)
							(mid 0.249642 -0.249642)
							(end 0.2794 -0.1778)
						)
						(arc
							(start 0.2794 0.1778)
							(mid 0.249642 0.249642)
							(end 0.1778 0.2794)
						)
					)
					(width 0)
					(fill yes)
				)
			)
		)
		(pad "2" smd custom
			(at 0 0.4445)
			(size 0.1397 0.1397)
			(layers "B.Cu" "B.Mask" "B.Paste")
			(net "P1V2_STBY")
			(options
				(clearance outline)
				(anchor circle)
			)
			(primitives
				(gr_poly
					(pts
						(arc
							(start -0.1778 0.2794)
							(mid -0.249642 0.249642)
							(end -0.2794 0.1778)
						)
						(arc
							(start -0.2794 -0.1778)
							(mid -0.249642 -0.249642)
							(end -0.1778 -0.2794)
						)
						(arc
							(start 0.1778 -0.2794)
							(mid 0.249642 -0.249642)
							(end 0.2794 -0.1778)
						)
						(arc
							(start 0.2794 0.1778)
							(mid 0.249642 0.249642)
							(end 0.1778 0.2794)
						)
					)
					(width 0)
					(fill yes)
				)
			)
		)
	)
	(footprint ""
		(layer "B.Cu")
		(at 22.606 -172.0342 90)
		(property "Reference" "C998"
			(at 0 0 90)
			(layer "B.SilkS")
			(hide yes)
			(effects
				(font
					(size 1.27 1.27)
				)
				(justify mirror)
			)
		)
		(property "Value" "SC1U16V3KX-5GP"
			(at 0 -2.8194 90)
			(unlocked yes)
			(layer "B.Fab")
			(hide yes)
			(effects
				(font
					(size 1.016 1.016)
					(thickness 0.1524)
				)
				(justify mirror)
			)
		)
		(property "Device Type" "C603H36"
			(at 0 -4.3434 90)
			(unlocked yes)
			(layer "B.Fab")
			(hide yes)
			(effects
				(font
					(size 1.016 1.016)
					(thickness 0.1524)
				)
				(justify mirror)
			)
		)
		(duplicate_pad_numbers_are_jumpers no)
		(fp_line
			(start -0.508 0)
			(end 0.508 0)
			(stroke
				(width 0.2032)
				(type default)
			)
			(layer "B.SilkS")
		)
		(fp_rect
			(start 0.5842 1.3335)
			(end -0.5842 -1.3335)
			(stroke
				(width 0)
				(type default)
			)
			(fill no)
			(layer "B.CrtYd")
		)
		(fp_rect
			(start 0.5842 1.3335)
			(end -0.5842 -1.3335)
			(stroke
				(width 0)
				(type default)
			)
			(fill no)
			(layer "B.Fab")
		)
		(pad "1" smd custom
			(at 0 -0.762 270)
			(size 0.2159 0.2159)
			(layers "B.Cu" "B.Mask" "B.Paste")
			(net "P1V8_STBY")
			(options
				(clearance outline)
				(anchor circle)
			)
			(primitives
				(gr_poly
					(pts
						(arc
							(start -0.3302 0.4318)
							(mid -0.402042 0.402042)
							(end -0.4318 0.3302)
						)
						(arc
							(start -0.4318 -0.3302)
							(mid -0.402042 -0.402042)
							(end -0.3302 -0.4318)
						)
						(arc
							(start 0.3302 -0.4318)
							(mid 0.402042 -0.402042)
							(end 0.4318 -0.3302)
						)
						(arc
							(start 0.4318 0.3302)
							(mid 0.402042 0.402042)
							(end 0.3302 0.4318)
						)
					)
					(width 0)
					(fill yes)
				)
			)
		)
		(pad "2" smd custom
			(at 0 0.762 270)
			(size 0.2159 0.2159)
			(layers "B.Cu" "B.Mask" "B.Paste")
			(net "GND")
			(options
				(clearance outline)
				(anchor circle)
			)
			(primitives
				(gr_poly
					(pts
						(arc
							(start -0.3302 0.4318)
							(mid -0.402042 0.402042)
							(end -0.4318 0.3302)
						)
						(arc
							(start -0.4318 -0.3302)
							(mid -0.402042 -0.402042)
							(end -0.3302 -0.4318)
						)
						(arc
							(start 0.3302 -0.4318)
							(mid 0.402042 -0.402042)
							(end 0.4318 -0.3302)
						)
						(arc
							(start 0.4318 0.3302)
							(mid 0.402042 0.402042)
							(end 0.3302 0.4318)
						)
					)
					(width 0)
					(fill yes)
				)
			)
		)
	)
	(footprint ""
		(layer "B.Cu")
		(at 81.89595 -141.750542 -90)
		(property "Reference" "R128"
			(at 0 0 90)
			(layer "B.SilkS")
			(hide yes)
			(effects
				(font
					(size 1.27 1.27)
				)
				(justify mirror)
			)
		)
		(property "Value" "0R2J-2-GP"
			(at -0.064008 -3.993896 270)
			(unlocked yes)
			(layer "B.Fab")
			(hide yes)
			(effects
				(font
					(size 1.016 1.016)
					(thickness 0.1524)
				)
				(justify mirror)
			)
		)
		(property "Device Type" "R402H16"
			(at -0.064008 -5.517896 270)
			(unlocked yes)
			(layer "B.Fab")
			(hide yes)
			(effects
				(font
					(size 1.016 1.016)
					(thickness 0.1524)
				)
				(justify mirror)
			)
		)
		(duplicate_pad_numbers_are_jumpers no)
		(fp_line
			(start -0.508 -0.9398)
			(end 0.508 -0.9398)
			(stroke
				(width 0.1524)
				(type default)
			)
			(layer "B.SilkS")
		)
		(fp_line
			(start 0.508 -0.9398)
			(end 0.508 0.9398)
			(stroke
				(width 0.1524)
				(type default)
			)
			(layer "B.SilkS")
		)
		(fp_rect
			(start 0.508 0.9398)
			(end -0.508 -0.9398)
			(stroke
				(width 0)
				(type default)
			)
			(fill no)
			(layer "B.CrtYd")
		)
		(fp_rect
			(start 0.508 0.9398)
			(end -0.508 -0.9398)
			(stroke
				(width 0)
				(type default)
			)
			(fill no)
			(layer "B.Fab")
		)
		(pad "1" smd custom
			(at 0 -0.4445 90)
			(size 0.1397 0.1397)
			(layers "B.Cu" "B.Mask" "B.Paste")
			(net "I2C_EXP_LOC_SDA")
			(options
				(clearance outline)
				(anchor circle)
			)
			(primitives
				(gr_poly
					(pts
						(arc
							(start -0.1778 0.2794)
							(mid -0.249642 0.249642)
							(end -0.2794 0.1778)
						)
						(arc
							(start -0.2794 -0.1778)
							(mid -0.249642 -0.249642)
							(end -0.1778 -0.2794)
						)
						(arc
							(start 0.1778 -0.2794)
							(mid 0.249642 -0.249642)
							(end 0.2794 -0.1778)
						)
						(arc
							(start 0.2794 0.1778)
							(mid 0.249642 0.249642)
							(end 0.1778 0.2794)
						)
					)
					(width 0)
					(fill yes)
				)
			)
		)
		(pad "2" smd custom
			(at 0 0.4445 90)
			(size 0.1397 0.1397)
			(layers "B.Cu" "B.Mask" "B.Paste")
			(net "I2C_EXP_LOC_SDA_R")
			(options
				(clearance outline)
				(anchor circle)
			)
			(primitives
				(gr_poly
					(pts
						(arc
							(start -0.1778 0.2794)
							(mid -0.249642 0.249642)
							(end -0.2794 0.1778)
						)
						(arc
							(start -0.2794 -0.1778)
							(mid -0.249642 -0.249642)
							(end -0.1778 -0.2794)
						)
						(arc
							(start 0.1778 -0.2794)
							(mid 0.249642 -0.249642)
							(end 0.2794 -0.1778)
						)
						(arc
							(start 0.2794 0.1778)
							(mid 0.249642 0.249642)
							(end 0.1778 0.2794)
						)
					)
					(width 0)
					(fill yes)
				)
			)
		)
	)
	(footprint ""
		(layer "B.Cu")
		(at 38.055296 -137.869676)
		(property "Reference" "TP17"
			(at 0 0 0)
			(layer "B.SilkS")
			(hide yes)
			(effects
				(font
					(size 1.27 1.27)
				)
				(justify mirror)
			)
		)
		(property "Value" "TPAD28-2-GP"
			(at 0.0127 -1.6637 0)
			(unlocked yes)
			(layer "B.Fab")
			(hide yes)
			(effects
				(font
					(size 1.016 1.016)
					(thickness 0.1524)
				)
				(justify mirror)
			)
		)
		(property "Device Type" "TPAD28"
			(at 0.0127 -3.1877 0)
			(unlocked yes)
			(layer "B.Fab")
			(hide yes)
			(effects
				(font
					(size 1.016 1.016)
					(thickness 0.1524)
				)
				(justify mirror)
			)
		)
		(duplicate_pad_numbers_are_jumpers no)
		(fp_poly
			(pts
				(arc
					(start 0.3556 0)
					(mid -0.3556 0)
					(end 0.3556 0)
				)
			)
			(stroke
				(width 0)
				(type default)
			)
			(fill no)
			(layer "B.CrtYd")
		)
		(fp_poly
			(pts
				(arc
					(start 0.6096 0)
					(mid -0.6096 0)
					(end 0.6096 0)
				)
			)
			(stroke
				(width 0)
				(type default)
			)
			(fill no)
			(layer "B.Fab")
		)
		(pad "1" smd circle
			(at 0 0 180)
			(size 0.7112 0.7112)
			(layers "B.Cu" "B.Mask" "B.Paste")
			(net "TP_BMC_GPIOR3")
		)
	)
	(footprint ""
		(layer "B.Cu")
		(at 12.091924 -138.144504 90)
		(property "Reference" "R247"
			(at 0 0 90)
			(layer "B.SilkS")
			(hide yes)
			(effects
				(font
					(size 1.27 1.27)
				)
				(justify mirror)
			)
		)
		(property "Value" "120R2F-GP"
			(at -0.064008 -3.993896 90)
			(unlocked yes)
			(layer "B.Fab")
			(hide yes)
			(effects
				(font
					(size 1.016 1.016)
					(thickness 0.1524)
				)
				(justify mirror)
			)
		)
		(property "Device Type" "R402H16"
			(at -0.064008 -5.517896 90)
			(unlocked yes)
			(layer "B.Fab")
			(hide yes)
			(effects
				(font
					(size 1.016 1.016)
					(thickness 0.1524)
				)
				(justify mirror)
			)
		)
		(duplicate_pad_numbers_are_jumpers no)
		(fp_line
			(start 0.508 -0.9398)
			(end 0.508 0.9398)
			(stroke
				(width 0.1524)
				(type default)
			)
			(layer "B.SilkS")
		)
		(fp_line
			(start -0.508 -0.9398)
			(end 0.508 -0.9398)
			(stroke
				(width 0.1524)
				(type default)
			)
			(layer "B.SilkS")
		)
		(fp_rect
			(start 0.508 0.9398)
			(end -0.508 -0.9398)
			(stroke
				(width 0)
				(type default)
			)
			(fill no)
			(layer "B.CrtYd")
		)
		(fp_rect
			(start 0.508 0.9398)
			(end -0.508 -0.9398)
			(stroke
				(width 0)
				(type default)
			)
			(fill no)
			(layer "B.Fab")
		)
		(pad "1" smd custom
			(at 0 -0.4445 270)
			(size 0.1397 0.1397)
			(layers "B.Cu" "B.Mask" "B.Paste")
			(net "MEMA_6")
			(options
				(clearance outline)
				(anchor circle)
			)
			(primitives
				(gr_poly
					(pts
						(arc
							(start -0.1778 0.2794)
							(mid -0.249642 0.249642)
							(end -0.2794 0.1778)
						)
						(arc
							(start -0.2794 -0.1778)
							(mid -0.249642 -0.249642)
							(end -0.1778 -0.2794)
						)
						(arc
							(start 0.1778 -0.2794)
							(mid 0.249642 -0.249642)
							(end 0.2794 -0.1778)
						)
						(arc
							(start 0.2794 0.1778)
							(mid 0.249642 0.249642)
							(end 0.1778 0.2794)
						)
					)
					(width 0)
					(fill yes)
				)
			)
		)
		(pad "2" smd custom
			(at 0 0.4445 270)
			(size 0.1397 0.1397)
			(layers "B.Cu" "B.Mask" "B.Paste")
			(net "P1V2_STBY")
			(options
				(clearance outline)
				(anchor circle)
			)
			(primitives
				(gr_poly
					(pts
						(arc
							(start -0.1778 0.2794)
							(mid -0.249642 0.249642)
							(end -0.2794 0.1778)
						)
						(arc
							(start -0.2794 -0.1778)
							(mid -0.249642 -0.249642)
							(end -0.1778 -0.2794)
						)
						(arc
							(start 0.1778 -0.2794)
							(mid 0.249642 -0.249642)
							(end 0.2794 -0.1778)
						)
						(arc
							(start 0.2794 0.1778)
							(mid 0.249642 0.249642)
							(end 0.1778 0.2794)
						)
					)
					(width 0)
					(fill yes)
				)
			)
		)
	)
	(footprint ""
		(layer "B.Cu")
		(at 40.206676 -127.978916)
		(property "Reference" "R348"
			(at 0 0 0)
			(layer "B.SilkS")
			(hide yes)
			(effects
				(font
					(size 1.27 1.27)
				)
				(justify mirror)
			)
		)
		(property "Value" "0R2J-2-GP"
			(at -0.064008 -3.993896 0)
			(unlocked yes)
			(layer "B.Fab")
			(hide yes)
			(effects
				(font
					(size 1.016 1.016)
					(thickness 0.1524)
				)
				(justify mirror)
			)
		)
		(property "Device Type" "R402H16"
			(at -0.064008 -5.517896 0)
			(unlocked yes)
			(layer "B.Fab")
			(hide yes)
			(effects
				(font
					(size 1.016 1.016)
					(thickness 0.1524)
				)
				(justify mirror)
			)
		)
		(duplicate_pad_numbers_are_jumpers no)
		(fp_line
			(start -0.508 -0.9398)
			(end 0.508 -0.9398)
			(stroke
				(width 0.1524)
				(type default)
			)
			(layer "B.SilkS")
		)
		(fp_line
			(start 0.508 -0.9398)
			(end 0.508 0.9398)
			(stroke
				(width 0.1524)
				(type default)
			)
			(layer "B.SilkS")
		)
		(fp_rect
			(start 0.508 0.9398)
			(end -0.508 -0.9398)
			(stroke
				(width 0)
				(type default)
			)
			(fill no)
			(layer "B.CrtYd")
		)
		(fp_rect
			(start 0.508 0.9398)
			(end -0.508 -0.9398)
			(stroke
				(width 0)
				(type default)
			)
			(fill no)
			(layer "B.Fab")
		)
		(pad "1" smd custom
			(at 0 -0.4445 180)
			(size 0.1397 0.1397)
			(layers "B.Cu" "B.Mask" "B.Paste")
			(net "BMC_EXTRST_N")
			(options
				(clearance outline)
				(anchor circle)
			)
			(primitives
				(gr_poly
					(pts
						(arc
							(start -0.1778 0.2794)
							(mid -0.249642 0.249642)
							(end -0.2794 0.1778)
						)
						(arc
							(start -0.2794 -0.1778)
							(mid -0.249642 -0.249642)
							(end -0.1778 -0.2794)
						)
						(arc
							(start 0.1778 -0.2794)
							(mid 0.249642 -0.249642)
							(end 0.2794 -0.1778)
						)
						(arc
							(start 0.2794 0.1778)
							(mid 0.249642 0.249642)
							(end 0.1778 0.2794)
						)
					)
					(width 0)
					(fill yes)
				)
			)
		)
		(pad "2" smd custom
			(at 0 0.4445 180)
			(size 0.1397 0.1397)
			(layers "B.Cu" "B.Mask" "B.Paste")
			(net "RST_BMC_EXTRST_N_1")
			(options
				(clearance outline)
				(anchor circle)
			)
			(primitives
				(gr_poly
					(pts
						(arc
							(start -0.1778 0.2794)
							(mid -0.249642 0.249642)
							(end -0.2794 0.1778)
						)
						(arc
							(start -0.2794 -0.1778)
							(mid -0.249642 -0.249642)
							(end -0.1778 -0.2794)
						)
						(arc
							(start 0.1778 -0.2794)
							(mid 0.249642 -0.249642)
							(end 0.2794 -0.1778)
						)
						(arc
							(start 0.2794 0.1778)
							(mid 0.249642 0.249642)
							(end 0.1778 0.2794)
						)
					)
					(width 0)
					(fill yes)
				)
			)
		)
	)
	(footprint ""
		(layer "B.Cu")
		(at 37.795962 -129.384806 90)
		(property "Reference" "R501"
			(at 0 0 90)
			(layer "B.SilkS")
			(hide yes)
			(effects
				(font
					(size 1.27 1.27)
				)
				(justify mirror)
			)
		)
		(property "Value" "4K7R2F-GP"
			(at -0.064008 -3.993896 90)
			(unlocked yes)
			(layer "B.Fab")
			(hide yes)
			(effects
				(font
					(size 1.016 1.016)
					(thickness 0.1524)
				)
				(justify mirror)
			)
		)
		(property "Device Type" "R402H16"
			(at -0.064008 -5.517896 90)
			(unlocked yes)
			(layer "B.Fab")
			(hide yes)
			(effects
				(font
					(size 1.016 1.016)
					(thickness 0.1524)
				)
				(justify mirror)
			)
		)
		(duplicate_pad_numbers_are_jumpers no)
		(fp_line
			(start 0.508 -0.9398)
			(end 0.508 0.9398)
			(stroke
				(width 0.1524)
				(type default)
			)
			(layer "B.SilkS")
		)
		(fp_line
			(start -0.508 -0.9398)
			(end 0.508 -0.9398)
			(stroke
				(width 0.1524)
				(type default)
			)
			(layer "B.SilkS")
		)
		(fp_rect
			(start 0.508 0.9398)
			(end -0.508 -0.9398)
			(stroke
				(width 0)
				(type default)
			)
			(fill no)
			(layer "B.CrtYd")
		)
		(fp_rect
			(start 0.508 0.9398)
			(end -0.508 -0.9398)
			(stroke
				(width 0)
				(type default)
			)
			(fill no)
			(layer "B.Fab")
		)
		(pad "1" smd custom
			(at 0 -0.4445 270)
			(size 0.1397 0.1397)
			(layers "B.Cu" "B.Mask" "B.Paste")
			(net "P3V3_STBY")
			(options
				(clearance outline)
				(anchor circle)
			)
			(primitives
				(gr_poly
					(pts
						(arc
							(start -0.1778 0.2794)
							(mid -0.249642 0.249642)
							(end -0.2794 0.1778)
						)
						(arc
							(start -0.2794 -0.1778)
							(mid -0.249642 -0.249642)
							(end -0.1778 -0.2794)
						)
						(arc
							(start 0.1778 -0.2794)
							(mid 0.249642 -0.249642)
							(end 0.2794 -0.1778)
						)
						(arc
							(start 0.2794 0.1778)
							(mid 0.249642 0.249642)
							(end 0.1778 0.2794)
						)
					)
					(width 0)
					(fill yes)
				)
			)
		)
		(pad "2" smd custom
			(at 0 0.4445 270)
			(size 0.1397 0.1397)
			(layers "B.Cu" "B.Mask" "B.Paste")
			(net "BMC_ML_PWR_BLUE_LED")
			(options
				(clearance outline)
				(anchor circle)
			)
			(primitives
				(gr_poly
					(pts
						(arc
							(start -0.1778 0.2794)
							(mid -0.249642 0.249642)
							(end -0.2794 0.1778)
						)
						(arc
							(start -0.2794 -0.1778)
							(mid -0.249642 -0.249642)
							(end -0.1778 -0.2794)
						)
						(arc
							(start 0.1778 -0.2794)
							(mid 0.249642 -0.249642)
							(end 0.2794 -0.1778)
						)
						(arc
							(start 0.2794 0.1778)
							(mid 0.249642 0.249642)
							(end 0.1778 0.2794)
						)
					)
					(width 0)
					(fill yes)
				)
			)
		)
	)
	(footprint ""
		(layer "B.Cu")
		(at 50.807874 -135.761476)
		(property "Reference" "R607"
			(at 0 0 0)
			(layer "B.SilkS")
			(hide yes)
			(effects
				(font
					(size 1.27 1.27)
				)
				(justify mirror)
			)
		)
		(property "Value" "0R2J-2-GP"
			(at -0.064008 -3.993896 0)
			(unlocked yes)
			(layer "B.Fab")
			(hide yes)
			(effects
				(font
					(size 1.016 1.016)
					(thickness 0.1524)
				)
				(justify mirror)
			)
		)
		(property "Device Type" "R402H16"
			(at -0.064008 -5.517896 0)
			(unlocked yes)
			(layer "B.Fab")
			(hide yes)
			(effects
				(font
					(size 1.016 1.016)
					(thickness 0.1524)
				)
				(justify mirror)
			)
		)
		(duplicate_pad_numbers_are_jumpers no)
		(fp_line
			(start -0.508 -0.9398)
			(end 0.508 -0.9398)
			(stroke
				(width 0.1524)
				(type default)
			)
			(layer "B.SilkS")
		)
		(fp_line
			(start 0.508 -0.9398)
			(end 0.508 0.9398)
			(stroke
				(width 0.1524)
				(type default)
			)
			(layer "B.SilkS")
		)
		(fp_rect
			(start 0.508 0.9398)
			(end -0.508 -0.9398)
			(stroke
				(width 0)
				(type default)
			)
			(fill no)
			(layer "B.CrtYd")
		)
		(fp_rect
			(start 0.508 0.9398)
			(end -0.508 -0.9398)
			(stroke
				(width 0)
				(type default)
			)
			(fill no)
			(layer "B.Fab")
		)
		(pad "1" smd custom
			(at 0 -0.4445 180)
			(size 0.1397 0.1397)
			(layers "B.Cu" "B.Mask" "B.Paste")
			(net "SYS_RESET_N_OUT_R")
			(options
				(clearance outline)
				(anchor circle)
			)
			(primitives
				(gr_poly
					(pts
						(arc
							(start -0.1778 0.2794)
							(mid -0.249642 0.249642)
							(end -0.2794 0.1778)
						)
						(arc
							(start -0.2794 -0.1778)
							(mid -0.249642 -0.249642)
							(end -0.1778 -0.2794)
						)
						(arc
							(start 0.1778 -0.2794)
							(mid 0.249642 -0.249642)
							(end 0.2794 -0.1778)
						)
						(arc
							(start 0.2794 0.1778)
							(mid 0.249642 0.249642)
							(end 0.1778 0.2794)
						)
					)
					(width 0)
					(fill yes)
				)
			)
		)
		(pad "2" smd custom
			(at 0 0.4445 180)
			(size 0.1397 0.1397)
			(layers "B.Cu" "B.Mask" "B.Paste")
			(net "SYS_RESET_N_OUT")
			(options
				(clearance outline)
				(anchor circle)
			)
			(primitives
				(gr_poly
					(pts
						(arc
							(start -0.1778 0.2794)
							(mid -0.249642 0.249642)
							(end -0.2794 0.1778)
						)
						(arc
							(start -0.2794 -0.1778)
							(mid -0.249642 -0.249642)
							(end -0.1778 -0.2794)
						)
						(arc
							(start 0.1778 -0.2794)
							(mid 0.249642 -0.249642)
							(end 0.2794 -0.1778)
						)
						(arc
							(start 0.2794 0.1778)
							(mid 0.249642 0.249642)
							(end 0.1778 0.2794)
						)
					)
					(width 0)
					(fill yes)
				)
			)
		)
	)
	(footprint ""
		(layer "B.Cu")
		(at 148.957538 -14.987778)
		(property "Reference" "C212"
			(at 0 0 0)
			(layer "B.SilkS")
			(hide yes)
			(effects
				(font
					(size 1.27 1.27)
				)
				(justify mirror)
			)
		)
		(property "Value" "SC1KP50V2KX-1GP"
			(at -1.1811 -2.7051 0)
			(unlocked yes)
			(layer "B.Fab")
			(hide yes)
			(effects
				(font
					(size 1.016 1.016)
					(thickness 0.1524)
				)
				(justify mirror)
			)
		)
		(property "Device Type" "C402H22"
			(at -1.1811 -4.2291 0)
			(unlocked yes)
			(layer "B.Fab")
			(hide yes)
			(effects
				(font
					(size 1.016 1.016)
					(thickness 0.1524)
				)
				(justify mirror)
			)
		)
		(duplicate_pad_numbers_are_jumpers no)
		(fp_rect
			(start 0.4318 0.9525)
			(end -0.4318 -0.9525)
			(stroke
				(width 0)
				(type default)
			)
			(fill no)
			(layer "B.CrtYd")
		)
		(fp_rect
			(start 0.4318 0.9525)
			(end -0.4318 -0.9525)
			(stroke
				(width 0)
				(type default)
			)
			(fill no)
			(layer "B.Fab")
		)
		(pad "1" smd custom
			(at 0 -0.4445 180)
			(size 0.1524 0.1524)
			(layers "B.Cu" "B.Mask" "B.Paste")
			(net "P1V8_STBY_VFB_R")
			(options
				(clearance outline)
				(anchor circle)
			)
			(primitives
				(gr_poly
					(pts
						(arc
							(start 0.3048 0.2032)
							(mid 0.275042 0.275042)
							(end 0.2032 0.3048)
						)
						(arc
							(start -0.2032 0.3048)
							(mid -0.275042 0.275042)
							(end -0.3048 0.2032)
						)
						(arc
							(start -0.3048 -0.2032)
							(mid -0.275042 -0.275042)
							(end -0.2032 -0.3048)
						)
						(arc
							(start 0.2032 -0.3048)
							(mid 0.275042 -0.275042)
							(end 0.3048 -0.2032)
						)
					)
					(width 0)
					(fill yes)
				)
			)
		)
		(pad "2" smd custom
			(at 0 0.4445 180)
			(size 0.1524 0.1524)
			(layers "B.Cu" "B.Mask" "B.Paste")
			(net "P1V8_STBY_VFB")
			(options
				(clearance outline)
				(anchor circle)
			)
			(primitives
				(gr_poly
					(pts
						(arc
							(start 0.3048 0.2032)
							(mid 0.275042 0.275042)
							(end 0.2032 0.3048)
						)
						(arc
							(start -0.2032 0.3048)
							(mid -0.275042 0.275042)
							(end -0.3048 0.2032)
						)
						(arc
							(start -0.3048 -0.2032)
							(mid -0.275042 -0.275042)
							(end -0.2032 -0.3048)
						)
						(arc
							(start 0.2032 -0.3048)
							(mid 0.275042 -0.275042)
							(end 0.3048 -0.2032)
						)
					)
					(width 0)
					(fill yes)
				)
			)
		)
	)
	(footprint ""
		(layer "B.Cu")
		(at 42.987468 -153.189178)
		(property "Reference" "TP63"
			(at 0 0 0)
			(layer "B.SilkS")
			(hide yes)
			(effects
				(font
					(size 1.27 1.27)
				)
				(justify mirror)
			)
		)
		(property "Value" "TPAD28-2-GP"
			(at 0.0127 -1.6637 0)
			(unlocked yes)
			(layer "B.Fab")
			(hide yes)
			(effects
				(font
					(size 1.016 1.016)
					(thickness 0.1524)
				)
				(justify mirror)
			)
		)
		(property "Device Type" "TPAD28"
			(at 0.0127 -3.1877 0)
			(unlocked yes)
			(layer "B.Fab")
			(hide yes)
			(effects
				(font
					(size 1.016 1.016)
					(thickness 0.1524)
				)
				(justify mirror)
			)
		)
		(duplicate_pad_numbers_are_jumpers no)
		(fp_poly
			(pts
				(arc
					(start 0.3556 0)
					(mid -0.3556 0)
					(end 0.3556 0)
				)
			)
			(stroke
				(width 0)
				(type default)
			)
			(fill no)
			(layer "B.CrtYd")
		)
		(fp_poly
			(pts
				(arc
					(start 0.6096 0)
					(mid -0.6096 0)
					(end 0.6096 0)
				)
			)
			(stroke
				(width 0)
				(type default)
			)
			(fill no)
			(layer "B.Fab")
		)
		(pad "1" smd circle
			(at 0 0 180)
			(size 0.7112 0.7112)
			(layers "B.Cu" "B.Mask" "B.Paste")
			(net "TP_BMC_GPION3")
		)
	)
	(footprint ""
		(layer "B.Cu")
		(at 61.83122 -145.042128 90)
		(property "Reference" "R165"
			(at 0 0 90)
			(layer "B.SilkS")
			(hide yes)
			(effects
				(font
					(size 1.27 1.27)
				)
				(justify mirror)
			)
		)
		(property "Value" "0R2J-2-GP"
			(at -0.064008 -3.993896 90)
			(unlocked yes)
			(layer "B.Fab")
			(hide yes)
			(effects
				(font
					(size 1.016 1.016)
					(thickness 0.1524)
				)
				(justify mirror)
			)
		)
		(property "Device Type" "R402H16"
			(at -0.064008 -5.517896 90)
			(unlocked yes)
			(layer "B.Fab")
			(hide yes)
			(effects
				(font
					(size 1.016 1.016)
					(thickness 0.1524)
				)
				(justify mirror)
			)
		)
		(duplicate_pad_numbers_are_jumpers no)
		(fp_line
			(start 0.508 -0.9398)
			(end 0.508 0.9398)
			(stroke
				(width 0.1524)
				(type default)
			)
			(layer "B.SilkS")
		)
		(fp_line
			(start -0.508 -0.9398)
			(end 0.508 -0.9398)
			(stroke
				(width 0.1524)
				(type default)
			)
			(layer "B.SilkS")
		)
		(fp_rect
			(start 0.508 0.9398)
			(end -0.508 -0.9398)
			(stroke
				(width 0)
				(type default)
			)
			(fill no)
			(layer "B.CrtYd")
		)
		(fp_rect
			(start 0.508 0.9398)
			(end -0.508 -0.9398)
			(stroke
				(width 0)
				(type default)
			)
			(fill no)
			(layer "B.Fab")
		)
		(pad "1" smd custom
			(at 0 -0.4445 270)
			(size 0.1397 0.1397)
			(layers "B.Cu" "B.Mask" "B.Paste")
			(net "BMC_SMB13_DAT")
			(options
				(clearance outline)
				(anchor circle)
			)
			(primitives
				(gr_poly
					(pts
						(arc
							(start -0.1778 0.2794)
							(mid -0.249642 0.249642)
							(end -0.2794 0.1778)
						)
						(arc
							(start -0.2794 -0.1778)
							(mid -0.249642 -0.249642)
							(end -0.1778 -0.2794)
						)
						(arc
							(start 0.1778 -0.2794)
							(mid 0.249642 -0.249642)
							(end 0.2794 -0.1778)
						)
						(arc
							(start 0.2794 0.1778)
							(mid 0.249642 0.249642)
							(end 0.1778 0.2794)
						)
					)
					(width 0)
					(fill yes)
				)
			)
		)
		(pad "2" smd custom
			(at 0 0.4445 270)
			(size 0.1397 0.1397)
			(layers "B.Cu" "B.Mask" "B.Paste")
			(net "I2C_MEZZ_FRU_SENSOR_SDA")
			(options
				(clearance outline)
				(anchor circle)
			)
			(primitives
				(gr_poly
					(pts
						(arc
							(start -0.1778 0.2794)
							(mid -0.249642 0.249642)
							(end -0.2794 0.1778)
						)
						(arc
							(start -0.2794 -0.1778)
							(mid -0.249642 -0.249642)
							(end -0.1778 -0.2794)
						)
						(arc
							(start 0.1778 -0.2794)
							(mid 0.249642 -0.249642)
							(end 0.2794 -0.1778)
						)
						(arc
							(start 0.2794 0.1778)
							(mid 0.249642 0.249642)
							(end 0.1778 0.2794)
						)
					)
					(width 0)
					(fill yes)
				)
			)
		)
	)
	(footprint ""
		(layer "B.Cu")
		(at 61.6204 -146.5072)
		(property "Reference" "R163"
			(at 0 0 0)
			(layer "B.SilkS")
			(hide yes)
			(effects
				(font
					(size 1.27 1.27)
				)
				(justify mirror)
			)
		)
		(property "Value" "0R2J-2-GP"
			(at -0.064008 -3.993896 0)
			(unlocked yes)
			(layer "B.Fab")
			(hide yes)
			(effects
				(font
					(size 1.016 1.016)
					(thickness 0.1524)
				)
				(justify mirror)
			)
		)
		(property "Device Type" "R402H16"
			(at -0.064008 -5.517896 0)
			(unlocked yes)
			(layer "B.Fab")
			(hide yes)
			(effects
				(font
					(size 1.016 1.016)
					(thickness 0.1524)
				)
				(justify mirror)
			)
		)
		(duplicate_pad_numbers_are_jumpers no)
		(fp_line
			(start -0.508 -0.9398)
			(end 0.508 -0.9398)
			(stroke
				(width 0.1524)
				(type default)
			)
			(layer "B.SilkS")
		)
		(fp_line
			(start 0.508 -0.9398)
			(end 0.508 0.9398)
			(stroke
				(width 0.1524)
				(type default)
			)
			(layer "B.SilkS")
		)
		(fp_rect
			(start 0.508 0.9398)
			(end -0.508 -0.9398)
			(stroke
				(width 0)
				(type default)
			)
			(fill no)
			(layer "B.CrtYd")
		)
		(fp_rect
			(start 0.508 0.9398)
			(end -0.508 -0.9398)
			(stroke
				(width 0)
				(type default)
			)
			(fill no)
			(layer "B.Fab")
		)
		(pad "1" smd custom
			(at 0 -0.4445 180)
			(size 0.1397 0.1397)
			(layers "B.Cu" "B.Mask" "B.Paste")
			(net "BMC_SMB13_CLK")
			(options
				(clearance outline)
				(anchor circle)
			)
			(primitives
				(gr_poly
					(pts
						(arc
							(start -0.1778 0.2794)
							(mid -0.249642 0.249642)
							(end -0.2794 0.1778)
						)
						(arc
							(start -0.2794 -0.1778)
							(mid -0.249642 -0.249642)
							(end -0.1778 -0.2794)
						)
						(arc
							(start 0.1778 -0.2794)
							(mid 0.249642 -0.249642)
							(end 0.2794 -0.1778)
						)
						(arc
							(start 0.2794 0.1778)
							(mid 0.249642 0.249642)
							(end 0.1778 0.2794)
						)
					)
					(width 0)
					(fill yes)
				)
			)
		)
		(pad "2" smd custom
			(at 0 0.4445 180)
			(size 0.1397 0.1397)
			(layers "B.Cu" "B.Mask" "B.Paste")
			(net "I2C_MEZZ_FRU_SENSOR_SCL")
			(options
				(clearance outline)
				(anchor circle)
			)
			(primitives
				(gr_poly
					(pts
						(arc
							(start -0.1778 0.2794)
							(mid -0.249642 0.249642)
							(end -0.2794 0.1778)
						)
						(arc
							(start -0.2794 -0.1778)
							(mid -0.249642 -0.249642)
							(end -0.1778 -0.2794)
						)
						(arc
							(start 0.1778 -0.2794)
							(mid 0.249642 -0.249642)
							(end 0.2794 -0.1778)
						)
						(arc
							(start 0.2794 0.1778)
							(mid 0.249642 0.249642)
							(end 0.1778 0.2794)
						)
					)
					(width 0)
					(fill yes)
				)
			)
		)
	)
	(footprint ""
		(layer "B.Cu")
		(at 224.989644 -76.13523 90)
		(property "Reference" "C640"
			(at 0 0 90)
			(layer "B.SilkS")
			(hide yes)
			(effects
				(font
					(size 1.27 1.27)
				)
				(justify mirror)
			)
		)
		(property "Value" "SC10U6D3V5KX-4GP"
			(at 0.0762 -6.1214 90)
			(unlocked yes)
			(layer "B.Fab")
			(hide yes)
			(effects
				(font
					(size 1.016 1.016)
					(thickness 0.1524)
				)
				(justify mirror)
			)
		)
		(property "Device Type" "C805H58"
			(at 0.0762 -8.1534 90)
			(unlocked yes)
			(layer "B.Fab")
			(hide yes)
			(effects
				(font
					(size 1.016 1.016)
					(thickness 0.1524)
				)
				(justify mirror)
			)
		)
		(duplicate_pad_numbers_are_jumpers no)
		(fp_line
			(start -0.635 0)
			(end 0.635 0)
			(stroke
				(width 0.508)
				(type default)
			)
			(layer "B.SilkS")
		)
		(fp_rect
			(start 0.9652 1.778)
			(end -0.9652 -1.778)
			(stroke
				(width 0)
				(type default)
			)
			(fill no)
			(layer "B.CrtYd")
		)
		(fp_poly
			(pts
				(xy 0.9652 -1.778) (xy -0.9652 -1.778) (xy -0.9652 1.778) (xy 0.9652 1.778)
			)
			(stroke
				(width 0)
				(type default)
			)
			(fill no)
			(layer "B.Fab")
		)
		(pad "1" smd rect
			(at 0 -0.9652 270)
			(size 1.397 1.143)
			(layers "B.Cu" "B.Mask" "B.Paste")
			(net "P3V3_M2")
		)
		(pad "2" smd rect
			(at 0 0.9652 270)
			(size 1.397 1.143)
			(layers "B.Cu" "B.Mask" "B.Paste")
			(net "GND")
		)
	)
	(footprint ""
		(layer "B.Cu")
		(at 58.392568 -158.191708 -90)
		(property "Reference" "R394"
			(at 0 0 90)
			(layer "B.SilkS")
			(hide yes)
			(effects
				(font
					(size 1.27 1.27)
				)
				(justify mirror)
			)
		)
		(property "Value" "4K7R2F-GP"
			(at -0.064008 -3.993896 270)
			(unlocked yes)
			(layer "B.Fab")
			(hide yes)
			(effects
				(font
					(size 1.016 1.016)
					(thickness 0.1524)
				)
				(justify mirror)
			)
		)
		(property "Device Type" "R402H16"
			(at -0.064008 -5.517896 270)
			(unlocked yes)
			(layer "B.Fab")
			(hide yes)
			(effects
				(font
					(size 1.016 1.016)
					(thickness 0.1524)
				)
				(justify mirror)
			)
		)
		(duplicate_pad_numbers_are_jumpers no)
		(fp_line
			(start -0.508 -0.9398)
			(end 0.508 -0.9398)
			(stroke
				(width 0.1524)
				(type default)
			)
			(layer "B.SilkS")
		)
		(fp_line
			(start 0.508 -0.9398)
			(end 0.508 0.9398)
			(stroke
				(width 0.1524)
				(type default)
			)
			(layer "B.SilkS")
		)
		(fp_rect
			(start 0.508 0.9398)
			(end -0.508 -0.9398)
			(stroke
				(width 0)
				(type default)
			)
			(fill no)
			(layer "B.CrtYd")
		)
		(fp_rect
			(start 0.508 0.9398)
			(end -0.508 -0.9398)
			(stroke
				(width 0)
				(type default)
			)
			(fill no)
			(layer "B.Fab")
		)
		(pad "1" smd custom
			(at 0 -0.4445 90)
			(size 0.1397 0.1397)
			(layers "B.Cu" "B.Mask" "B.Paste")
			(net "P3V3_STBY")
			(options
				(clearance outline)
				(anchor circle)
			)
			(primitives
				(gr_poly
					(pts
						(arc
							(start -0.1778 0.2794)
							(mid -0.249642 0.249642)
							(end -0.2794 0.1778)
						)
						(arc
							(start -0.2794 -0.1778)
							(mid -0.249642 -0.249642)
							(end -0.1778 -0.2794)
						)
						(arc
							(start 0.1778 -0.2794)
							(mid 0.249642 -0.249642)
							(end 0.2794 -0.1778)
						)
						(arc
							(start 0.2794 0.1778)
							(mid 0.249642 0.249642)
							(end 0.1778 0.2794)
						)
					)
					(width 0)
					(fill yes)
				)
			)
		)
		(pad "2" smd custom
			(at 0 0.4445 90)
			(size 0.1397 0.1397)
			(layers "B.Cu" "B.Mask" "B.Paste")
			(net "MAC2_TXD3")
			(options
				(clearance outline)
				(anchor circle)
			)
			(primitives
				(gr_poly
					(pts
						(arc
							(start -0.1778 0.2794)
							(mid -0.249642 0.249642)
							(end -0.2794 0.1778)
						)
						(arc
							(start -0.2794 -0.1778)
							(mid -0.249642 -0.249642)
							(end -0.1778 -0.2794)
						)
						(arc
							(start 0.1778 -0.2794)
							(mid 0.249642 -0.249642)
							(end 0.2794 -0.1778)
						)
						(arc
							(start 0.2794 0.1778)
							(mid 0.249642 0.249642)
							(end 0.1778 0.2794)
						)
					)
					(width 0)
					(fill yes)
				)
			)
		)
	)
	(footprint ""
		(layer "B.Cu")
		(at 177.8 -112.2934 -90)
		(property "Reference" "R527"
			(at 0 0 90)
			(layer "B.SilkS")
			(hide yes)
			(effects
				(font
					(size 1.27 1.27)
				)
				(justify mirror)
			)
		)
		(property "Value" "0R2J-2-GP"
			(at -0.064008 -3.993896 270)
			(unlocked yes)
			(layer "B.Fab")
			(hide yes)
			(effects
				(font
					(size 1.016 1.016)
					(thickness 0.1524)
				)
				(justify mirror)
			)
		)
		(property "Device Type" "R402H16"
			(at -0.064008 -5.517896 270)
			(unlocked yes)
			(layer "B.Fab")
			(hide yes)
			(effects
				(font
					(size 1.016 1.016)
					(thickness 0.1524)
				)
				(justify mirror)
			)
		)
		(duplicate_pad_numbers_are_jumpers no)
		(fp_line
			(start -0.508 -0.9398)
			(end 0.508 -0.9398)
			(stroke
				(width 0.1524)
				(type default)
			)
			(layer "B.SilkS")
		)
		(fp_line
			(start 0.508 -0.9398)
			(end 0.508 0.9398)
			(stroke
				(width 0.1524)
				(type default)
			)
			(layer "B.SilkS")
		)
		(fp_rect
			(start 0.508 0.9398)
			(end -0.508 -0.9398)
			(stroke
				(width 0)
				(type default)
			)
			(fill no)
			(layer "B.CrtYd")
		)
		(fp_rect
			(start 0.508 0.9398)
			(end -0.508 -0.9398)
			(stroke
				(width 0)
				(type default)
			)
			(fill no)
			(layer "B.Fab")
		)
		(pad "1" smd custom
			(at 0 -0.4445 90)
			(size 0.1397 0.1397)
			(layers "B.Cu" "B.Mask" "B.Paste")
			(net "IOM_FULL_PGOOD")
			(options
				(clearance outline)
				(anchor circle)
			)
			(primitives
				(gr_poly
					(pts
						(arc
							(start -0.1778 0.2794)
							(mid -0.249642 0.249642)
							(end -0.2794 0.1778)
						)
						(arc
							(start -0.2794 -0.1778)
							(mid -0.249642 -0.249642)
							(end -0.1778 -0.2794)
						)
						(arc
							(start 0.1778 -0.2794)
							(mid 0.249642 -0.249642)
							(end 0.2794 -0.1778)
						)
						(arc
							(start 0.2794 0.1778)
							(mid 0.249642 0.249642)
							(end 0.1778 0.2794)
						)
					)
					(width 0)
					(fill yes)
				)
			)
		)
		(pad "2" smd custom
			(at 0 0.4445 90)
			(size 0.1397 0.1397)
			(layers "B.Cu" "B.Mask" "B.Paste")
			(net "U83_VREF2")
			(options
				(clearance outline)
				(anchor circle)
			)
			(primitives
				(gr_poly
					(pts
						(arc
							(start -0.1778 0.2794)
							(mid -0.249642 0.249642)
							(end -0.2794 0.1778)
						)
						(arc
							(start -0.2794 -0.1778)
							(mid -0.249642 -0.249642)
							(end -0.1778 -0.2794)
						)
						(arc
							(start 0.1778 -0.2794)
							(mid 0.249642 -0.249642)
							(end 0.2794 -0.1778)
						)
						(arc
							(start 0.2794 0.1778)
							(mid 0.249642 0.249642)
							(end 0.1778 0.2794)
						)
					)
					(width 0)
					(fill yes)
				)
			)
		)
	)
	(footprint ""
		(layer "B.Cu")
		(at 23.437342 -129.1082 180)
		(property "Reference" "R248"
			(at 0 0 0)
			(layer "B.SilkS")
			(hide yes)
			(effects
				(font
					(size 1.27 1.27)
				)
				(justify mirror)
			)
		)
		(property "Value" "120R2F-GP"
			(at -0.064008 -3.993896 180)
			(unlocked yes)
			(layer "B.Fab")
			(hide yes)
			(effects
				(font
					(size 1.016 1.016)
					(thickness 0.1524)
				)
				(justify mirror)
			)
		)
		(property "Device Type" "R402H16"
			(at -0.064008 -5.517896 180)
			(unlocked yes)
			(layer "B.Fab")
			(hide yes)
			(effects
				(font
					(size 1.016 1.016)
					(thickness 0.1524)
				)
				(justify mirror)
			)
		)
		(duplicate_pad_numbers_are_jumpers no)
		(fp_line
			(start 0.508 -0.9398)
			(end 0.508 0.9398)
			(stroke
				(width 0.1524)
				(type default)
			)
			(layer "B.SilkS")
		)
		(fp_line
			(start -0.508 -0.9398)
			(end 0.508 -0.9398)
			(stroke
				(width 0.1524)
				(type default)
			)
			(layer "B.SilkS")
		)
		(fp_rect
			(start 0.508 0.9398)
			(end -0.508 -0.9398)
			(stroke
				(width 0)
				(type default)
			)
			(fill no)
			(layer "B.CrtYd")
		)
		(fp_rect
			(start 0.508 0.9398)
			(end -0.508 -0.9398)
			(stroke
				(width 0)
				(type default)
			)
			(fill no)
			(layer "B.Fab")
		)
		(pad "1" smd custom
			(at 0 -0.4445)
			(size 0.1397 0.1397)
			(layers "B.Cu" "B.Mask" "B.Paste")
			(net "GND")
			(options
				(clearance outline)
				(anchor circle)
			)
			(primitives
				(gr_poly
					(pts
						(arc
							(start -0.1778 0.2794)
							(mid -0.249642 0.249642)
							(end -0.2794 0.1778)
						)
						(arc
							(start -0.2794 -0.1778)
							(mid -0.249642 -0.249642)
							(end -0.1778 -0.2794)
						)
						(arc
							(start 0.1778 -0.2794)
							(mid 0.249642 -0.249642)
							(end 0.2794 -0.1778)
						)
						(arc
							(start 0.2794 0.1778)
							(mid 0.249642 0.249642)
							(end 0.1778 0.2794)
						)
					)
					(width 0)
					(fill yes)
				)
			)
		)
		(pad "2" smd custom
			(at 0 0.4445)
			(size 0.1397 0.1397)
			(layers "B.Cu" "B.Mask" "B.Paste")
			(net "MEMA_7")
			(options
				(clearance outline)
				(anchor circle)
			)
			(primitives
				(gr_poly
					(pts
						(arc
							(start -0.1778 0.2794)
							(mid -0.249642 0.249642)
							(end -0.2794 0.1778)
						)
						(arc
							(start -0.2794 -0.1778)
							(mid -0.249642 -0.249642)
							(end -0.1778 -0.2794)
						)
						(arc
							(start 0.1778 -0.2794)
							(mid 0.249642 -0.249642)
							(end 0.2794 -0.1778)
						)
						(arc
							(start 0.2794 0.1778)
							(mid 0.249642 0.249642)
							(end 0.1778 0.2794)
						)
					)
					(width 0)
					(fill yes)
				)
			)
		)
	)
	(footprint ""
		(layer "B.Cu")
		(at 40.679878 -136.439656)
		(property "Reference" "TP18"
			(at 0 0 0)
			(layer "B.SilkS")
			(hide yes)
			(effects
				(font
					(size 1.27 1.27)
				)
				(justify mirror)
			)
		)
		(property "Value" "TPAD28-2-GP"
			(at 0.0127 -1.6637 0)
			(unlocked yes)
			(layer "B.Fab")
			(hide yes)
			(effects
				(font
					(size 1.016 1.016)
					(thickness 0.1524)
				)
				(justify mirror)
			)
		)
		(property "Device Type" "TPAD28"
			(at 0.0127 -3.1877 0)
			(unlocked yes)
			(layer "B.Fab")
			(hide yes)
			(effects
				(font
					(size 1.016 1.016)
					(thickness 0.1524)
				)
				(justify mirror)
			)
		)
		(duplicate_pad_numbers_are_jumpers no)
		(fp_poly
			(pts
				(arc
					(start 0.3556 0)
					(mid -0.3556 0)
					(end 0.3556 0)
				)
			)
			(stroke
				(width 0)
				(type default)
			)
			(fill no)
			(layer "B.CrtYd")
		)
		(fp_poly
			(pts
				(arc
					(start 0.6096 0)
					(mid -0.6096 0)
					(end 0.6096 0)
				)
			)
			(stroke
				(width 0)
				(type default)
			)
			(fill no)
			(layer "B.Fab")
		)
		(pad "1" smd circle
			(at 0 0 180)
			(size 0.7112 0.7112)
			(layers "B.Cu" "B.Mask" "B.Paste")
			(net "TP_BMC_GPIOR4")
		)
	)
	(footprint ""
		(layer "B.Cu")
		(at 57.404 -148.8186 -90)
		(property "Reference" "R359"
			(at 0 0 90)
			(layer "B.SilkS")
			(hide yes)
			(effects
				(font
					(size 1.27 1.27)
				)
				(justify mirror)
			)
		)
		(property "Value" "10KR2F-2-GP"
			(at -0.064008 -3.993896 270)
			(unlocked yes)
			(layer "B.Fab")
			(hide yes)
			(effects
				(font
					(size 1.016 1.016)
					(thickness 0.1524)
				)
				(justify mirror)
			)
		)
		(property "Device Type" "R402H16"
			(at -0.064008 -5.517896 270)
			(unlocked yes)
			(layer "B.Fab")
			(hide yes)
			(effects
				(font
					(size 1.016 1.016)
					(thickness 0.1524)
				)
				(justify mirror)
			)
		)
		(duplicate_pad_numbers_are_jumpers no)
		(fp_line
			(start -0.508 -0.9398)
			(end 0.508 -0.9398)
			(stroke
				(width 0.1524)
				(type default)
			)
			(layer "B.SilkS")
		)
		(fp_line
			(start 0.508 -0.9398)
			(end 0.508 0.9398)
			(stroke
				(width 0.1524)
				(type default)
			)
			(layer "B.SilkS")
		)
		(fp_rect
			(start 0.508 0.9398)
			(end -0.508 -0.9398)
			(stroke
				(width 0)
				(type default)
			)
			(fill no)
			(layer "B.CrtYd")
		)
		(fp_rect
			(start 0.508 0.9398)
			(end -0.508 -0.9398)
			(stroke
				(width 0)
				(type default)
			)
			(fill no)
			(layer "B.Fab")
		)
		(pad "1" smd custom
			(at 0 -0.4445 90)
			(size 0.1397 0.1397)
			(layers "B.Cu" "B.Mask" "B.Paste")
			(net "P3V3_STBY")
			(options
				(clearance outline)
				(anchor circle)
			)
			(primitives
				(gr_poly
					(pts
						(arc
							(start -0.1778 0.2794)
							(mid -0.249642 0.249642)
							(end -0.2794 0.1778)
						)
						(arc
							(start -0.2794 -0.1778)
							(mid -0.249642 -0.249642)
							(end -0.1778 -0.2794)
						)
						(arc
							(start 0.1778 -0.2794)
							(mid 0.249642 -0.249642)
							(end 0.2794 -0.1778)
						)
						(arc
							(start 0.2794 0.1778)
							(mid 0.249642 0.249642)
							(end 0.1778 0.2794)
						)
					)
					(width 0)
					(fill yes)
				)
			)
		)
		(pad "2" smd custom
			(at 0 0.4445 90)
			(size 0.1397 0.1397)
			(layers "B.Cu" "B.Mask" "B.Paste")
			(net "JTAG_BMC_TMS")
			(options
				(clearance outline)
				(anchor circle)
			)
			(primitives
				(gr_poly
					(pts
						(arc
							(start -0.1778 0.2794)
							(mid -0.249642 0.249642)
							(end -0.2794 0.1778)
						)
						(arc
							(start -0.2794 -0.1778)
							(mid -0.249642 -0.249642)
							(end -0.1778 -0.2794)
						)
						(arc
							(start 0.1778 -0.2794)
							(mid 0.249642 -0.249642)
							(end 0.2794 -0.1778)
						)
						(arc
							(start 0.2794 0.1778)
							(mid 0.249642 0.249642)
							(end 0.1778 0.2794)
						)
					)
					(width 0)
					(fill yes)
				)
			)
		)
	)
	(footprint ""
		(layer "B.Cu")
		(at 73.224644 -146.81708 180)
		(property "Reference" "R53"
			(at 0 0 0)
			(layer "B.SilkS")
			(hide yes)
			(effects
				(font
					(size 1.27 1.27)
				)
				(justify mirror)
			)
		)
		(property "Value" "4K7R2F-GP"
			(at -0.064008 -3.993896 180)
			(unlocked yes)
			(layer "B.Fab")
			(hide yes)
			(effects
				(font
					(size 1.016 1.016)
					(thickness 0.1524)
				)
				(justify mirror)
			)
		)
		(property "Device Type" "R402H16"
			(at -0.064008 -5.517896 180)
			(unlocked yes)
			(layer "B.Fab")
			(hide yes)
			(effects
				(font
					(size 1.016 1.016)
					(thickness 0.1524)
				)
				(justify mirror)
			)
		)
		(duplicate_pad_numbers_are_jumpers no)
		(fp_line
			(start 0.508 -0.9398)
			(end 0.508 0.9398)
			(stroke
				(width 0.1524)
				(type default)
			)
			(layer "B.SilkS")
		)
		(fp_line
			(start -0.508 -0.9398)
			(end 0.508 -0.9398)
			(stroke
				(width 0.1524)
				(type default)
			)
			(layer "B.SilkS")
		)
		(fp_rect
			(start 0.508 0.9398)
			(end -0.508 -0.9398)
			(stroke
				(width 0)
				(type default)
			)
			(fill no)
			(layer "B.CrtYd")
		)
		(fp_rect
			(start 0.508 0.9398)
			(end -0.508 -0.9398)
			(stroke
				(width 0)
				(type default)
			)
			(fill no)
			(layer "B.Fab")
		)
		(pad "1" smd custom
			(at 0 -0.4445)
			(size 0.1397 0.1397)
			(layers "B.Cu" "B.Mask" "B.Paste")
			(net "P3V3_STBY")
			(options
				(clearance outline)
				(anchor circle)
			)
			(primitives
				(gr_poly
					(pts
						(arc
							(start -0.1778 0.2794)
							(mid -0.249642 0.249642)
							(end -0.2794 0.1778)
						)
						(arc
							(start -0.2794 -0.1778)
							(mid -0.249642 -0.249642)
							(end -0.1778 -0.2794)
						)
						(arc
							(start 0.1778 -0.2794)
							(mid 0.249642 -0.249642)
							(end 0.2794 -0.1778)
						)
						(arc
							(start 0.2794 0.1778)
							(mid 0.249642 0.249642)
							(end 0.1778 0.2794)
						)
					)
					(width 0)
					(fill yes)
				)
			)
		)
		(pad "2" smd custom
			(at 0 0.4445)
			(size 0.1397 0.1397)
			(layers "B.Cu" "B.Mask" "B.Paste")
			(net "I2C_DEBUG_SCL")
			(options
				(clearance outline)
				(anchor circle)
			)
			(primitives
				(gr_poly
					(pts
						(arc
							(start -0.1778 0.2794)
							(mid -0.249642 0.249642)
							(end -0.2794 0.1778)
						)
						(arc
							(start -0.2794 -0.1778)
							(mid -0.249642 -0.249642)
							(end -0.1778 -0.2794)
						)
						(arc
							(start 0.1778 -0.2794)
							(mid 0.249642 -0.249642)
							(end 0.2794 -0.1778)
						)
						(arc
							(start 0.2794 0.1778)
							(mid 0.249642 0.249642)
							(end 0.1778 0.2794)
						)
					)
					(width 0)
					(fill yes)
				)
			)
		)
	)
	(footprint ""
		(layer "B.Cu")
		(at 37.400738 -127.885698)
		(property "Reference" "R734"
			(at 0 0 0)
			(layer "B.SilkS")
			(hide yes)
			(effects
				(font
					(size 1.27 1.27)
				)
				(justify mirror)
			)
		)
		(property "Value" "0R2J-2-GP"
			(at -0.064008 -3.993896 0)
			(unlocked yes)
			(layer "B.Fab")
			(hide yes)
			(effects
				(font
					(size 1.016 1.016)
					(thickness 0.1524)
				)
				(justify mirror)
			)
		)
		(property "Device Type" "R402H16"
			(at -0.064008 -5.517896 0)
			(unlocked yes)
			(layer "B.Fab")
			(hide yes)
			(effects
				(font
					(size 1.016 1.016)
					(thickness 0.1524)
				)
				(justify mirror)
			)
		)
		(duplicate_pad_numbers_are_jumpers no)
		(fp_line
			(start -0.508 -0.9398)
			(end 0.508 -0.9398)
			(stroke
				(width 0.1524)
				(type default)
			)
			(layer "B.SilkS")
		)
		(fp_line
			(start 0.508 -0.9398)
			(end 0.508 0.9398)
			(stroke
				(width 0.1524)
				(type default)
			)
			(layer "B.SilkS")
		)
		(fp_rect
			(start 0.508 0.9398)
			(end -0.508 -0.9398)
			(stroke
				(width 0)
				(type default)
			)
			(fill no)
			(layer "B.CrtYd")
		)
		(fp_rect
			(start 0.508 0.9398)
			(end -0.508 -0.9398)
			(stroke
				(width 0)
				(type default)
			)
			(fill no)
			(layer "B.Fab")
		)
		(pad "1" smd custom
			(at 0 -0.4445 180)
			(size 0.1397 0.1397)
			(layers "B.Cu" "B.Mask" "B.Paste")
			(net "U104_EN")
			(options
				(clearance outline)
				(anchor circle)
			)
			(primitives
				(gr_poly
					(pts
						(arc
							(start -0.1778 0.2794)
							(mid -0.249642 0.249642)
							(end -0.2794 0.1778)
						)
						(arc
							(start -0.2794 -0.1778)
							(mid -0.249642 -0.249642)
							(end -0.1778 -0.2794)
						)
						(arc
							(start 0.1778 -0.2794)
							(mid 0.249642 -0.249642)
							(end 0.2794 -0.1778)
						)
						(arc
							(start 0.2794 0.1778)
							(mid 0.249642 0.249642)
							(end 0.1778 0.2794)
						)
					)
					(width 0)
					(fill yes)
				)
			)
		)
		(pad "2" smd custom
			(at 0 0.4445 180)
			(size 0.1397 0.1397)
			(layers "B.Cu" "B.Mask" "B.Paste")
			(net "SYS_RST_EN")
			(options
				(clearance outline)
				(anchor circle)
			)
			(primitives
				(gr_poly
					(pts
						(arc
							(start -0.1778 0.2794)
							(mid -0.249642 0.249642)
							(end -0.2794 0.1778)
						)
						(arc
							(start -0.2794 -0.1778)
							(mid -0.249642 -0.249642)
							(end -0.1778 -0.2794)
						)
						(arc
							(start 0.1778 -0.2794)
							(mid 0.249642 -0.249642)
							(end 0.2794 -0.1778)
						)
						(arc
							(start 0.2794 0.1778)
							(mid 0.249642 0.249642)
							(end 0.1778 0.2794)
						)
					)
					(width 0)
					(fill yes)
				)
			)
		)
	)
	(footprint ""
		(layer "B.Cu")
		(at 79.9592 -172.6438)
		(property "Reference" "R327"
			(at 0 0 0)
			(layer "B.SilkS")
			(hide yes)
			(effects
				(font
					(size 1.27 1.27)
				)
				(justify mirror)
			)
		)
		(property "Value" "4K7R2F-GP"
			(at -0.064008 -3.993896 0)
			(unlocked yes)
			(layer "B.Fab")
			(hide yes)
			(effects
				(font
					(size 1.016 1.016)
					(thickness 0.1524)
				)
				(justify mirror)
			)
		)
		(property "Device Type" "R402H16"
			(at -0.064008 -5.517896 0)
			(unlocked yes)
			(layer "B.Fab")
			(hide yes)
			(effects
				(font
					(size 1.016 1.016)
					(thickness 0.1524)
				)
				(justify mirror)
			)
		)
		(duplicate_pad_numbers_are_jumpers no)
		(fp_line
			(start -0.508 -0.9398)
			(end 0.508 -0.9398)
			(stroke
				(width 0.1524)
				(type default)
			)
			(layer "B.SilkS")
		)
		(fp_line
			(start 0.508 -0.9398)
			(end 0.508 0.9398)
			(stroke
				(width 0.1524)
				(type default)
			)
			(layer "B.SilkS")
		)
		(fp_rect
			(start 0.508 0.9398)
			(end -0.508 -0.9398)
			(stroke
				(width 0)
				(type default)
			)
			(fill no)
			(layer "B.CrtYd")
		)
		(fp_rect
			(start 0.508 0.9398)
			(end -0.508 -0.9398)
			(stroke
				(width 0)
				(type default)
			)
			(fill no)
			(layer "B.Fab")
		)
		(pad "1" smd custom
			(at 0 -0.4445 180)
			(size 0.1397 0.1397)
			(layers "B.Cu" "B.Mask" "B.Paste")
			(net "P3V3_STBY")
			(options
				(clearance outline)
				(anchor circle)
			)
			(primitives
				(gr_poly
					(pts
						(arc
							(start -0.1778 0.2794)
							(mid -0.249642 0.249642)
							(end -0.2794 0.1778)
						)
						(arc
							(start -0.2794 -0.1778)
							(mid -0.249642 -0.249642)
							(end -0.1778 -0.2794)
						)
						(arc
							(start 0.1778 -0.2794)
							(mid 0.249642 -0.249642)
							(end 0.2794 -0.1778)
						)
						(arc
							(start 0.2794 0.1778)
							(mid 0.249642 0.249642)
							(end 0.1778 0.2794)
						)
					)
					(width 0)
					(fill yes)
				)
			)
		)
		(pad "2" smd custom
			(at 0 0.4445 180)
			(size 0.1397 0.1397)
			(layers "B.Cu" "B.Mask" "B.Paste")
			(net "UART_EXP_BMC_RX")
			(options
				(clearance outline)
				(anchor circle)
			)
			(primitives
				(gr_poly
					(pts
						(arc
							(start -0.1778 0.2794)
							(mid -0.249642 0.249642)
							(end -0.2794 0.1778)
						)
						(arc
							(start -0.2794 -0.1778)
							(mid -0.249642 -0.249642)
							(end -0.1778 -0.2794)
						)
						(arc
							(start 0.1778 -0.2794)
							(mid 0.249642 -0.249642)
							(end 0.2794 -0.1778)
						)
						(arc
							(start 0.2794 0.1778)
							(mid 0.249642 0.249642)
							(end 0.1778 0.2794)
						)
					)
					(width 0)
					(fill yes)
				)
			)
		)
	)
	(footprint ""
		(layer "B.Cu")
		(at 192.11925 -133.831584 180)
		(property "Reference" "C613"
			(at 0 0 0)
			(layer "B.SilkS")
			(hide yes)
			(effects
				(font
					(size 1.27 1.27)
				)
				(justify mirror)
			)
		)
		(property "Value" "SCD1U16V2KX-3GP"
			(at -1.1811 -2.7051 180)
			(unlocked yes)
			(layer "B.Fab")
			(hide yes)
			(effects
				(font
					(size 1.016 1.016)
					(thickness 0.1524)
				)
				(justify mirror)
			)
		)
		(property "Device Type" "C402H22"
			(at -1.1811 -4.2291 180)
			(unlocked yes)
			(layer "B.Fab")
			(hide yes)
			(effects
				(font
					(size 1.016 1.016)
					(thickness 0.1524)
				)
				(justify mirror)
			)
		)
		(duplicate_pad_numbers_are_jumpers no)
		(fp_rect
			(start 0.4318 0.9525)
			(end -0.4318 -0.9525)
			(stroke
				(width 0)
				(type default)
			)
			(fill no)
			(layer "B.CrtYd")
		)
		(fp_rect
			(start 0.4318 0.9525)
			(end -0.4318 -0.9525)
			(stroke
				(width 0)
				(type default)
			)
			(fill no)
			(layer "B.Fab")
		)
		(pad "1" smd custom
			(at 0 -0.4445)
			(size 0.1524 0.1524)
			(layers "B.Cu" "B.Mask" "B.Paste")
			(net "P3V3_M2")
			(options
				(clearance outline)
				(anchor circle)
			)
			(primitives
				(gr_poly
					(pts
						(arc
							(start 0.3048 0.2032)
							(mid 0.275042 0.275042)
							(end 0.2032 0.3048)
						)
						(arc
							(start -0.2032 0.3048)
							(mid -0.275042 0.275042)
							(end -0.3048 0.2032)
						)
						(arc
							(start -0.3048 -0.2032)
							(mid -0.275042 -0.275042)
							(end -0.2032 -0.3048)
						)
						(arc
							(start 0.2032 -0.3048)
							(mid 0.275042 -0.275042)
							(end 0.3048 -0.2032)
						)
					)
					(width 0)
					(fill yes)
				)
			)
		)
		(pad "2" smd custom
			(at 0 0.4445)
			(size 0.1524 0.1524)
			(layers "B.Cu" "B.Mask" "B.Paste")
			(net "GND")
			(options
				(clearance outline)
				(anchor circle)
			)
			(primitives
				(gr_poly
					(pts
						(arc
							(start 0.3048 0.2032)
							(mid 0.275042 0.275042)
							(end 0.2032 0.3048)
						)
						(arc
							(start -0.2032 0.3048)
							(mid -0.275042 0.275042)
							(end -0.3048 0.2032)
						)
						(arc
							(start -0.3048 -0.2032)
							(mid -0.275042 -0.275042)
							(end -0.2032 -0.3048)
						)
						(arc
							(start 0.2032 -0.3048)
							(mid 0.275042 -0.275042)
							(end 0.3048 -0.2032)
						)
					)
					(width 0)
					(fill yes)
				)
			)
		)
	)
	(footprint ""
		(layer "B.Cu")
		(at 56.847232 -162.025076 90)
		(property "Reference" "R415"
			(at 0 0 90)
			(layer "B.SilkS")
			(hide yes)
			(effects
				(font
					(size 1.27 1.27)
				)
				(justify mirror)
			)
		)
		(property "Value" "1KR2F-3-GP"
			(at -0.064008 -3.993896 90)
			(unlocked yes)
			(layer "B.Fab")
			(hide yes)
			(effects
				(font
					(size 1.016 1.016)
					(thickness 0.1524)
				)
				(justify mirror)
			)
		)
		(property "Device Type" "R402H16"
			(at -0.064008 -5.517896 90)
			(unlocked yes)
			(layer "B.Fab")
			(hide yes)
			(effects
				(font
					(size 1.016 1.016)
					(thickness 0.1524)
				)
				(justify mirror)
			)
		)
		(duplicate_pad_numbers_are_jumpers no)
		(fp_line
			(start 0.508 -0.9398)
			(end 0.508 0.9398)
			(stroke
				(width 0.1524)
				(type default)
			)
			(layer "B.SilkS")
		)
		(fp_line
			(start -0.508 -0.9398)
			(end 0.508 -0.9398)
			(stroke
				(width 0.1524)
				(type default)
			)
			(layer "B.SilkS")
		)
		(fp_rect
			(start 0.508 0.9398)
			(end -0.508 -0.9398)
			(stroke
				(width 0)
				(type default)
			)
			(fill no)
			(layer "B.CrtYd")
		)
		(fp_rect
			(start 0.508 0.9398)
			(end -0.508 -0.9398)
			(stroke
				(width 0)
				(type default)
			)
			(fill no)
			(layer "B.Fab")
		)
		(pad "1" smd custom
			(at 0 -0.4445 270)
			(size 0.1397 0.1397)
			(layers "B.Cu" "B.Mask" "B.Paste")
			(net "ADC_P5V_STBY")
			(options
				(clearance outline)
				(anchor circle)
			)
			(primitives
				(gr_poly
					(pts
						(arc
							(start -0.1778 0.2794)
							(mid -0.249642 0.249642)
							(end -0.2794 0.1778)
						)
						(arc
							(start -0.2794 -0.1778)
							(mid -0.249642 -0.249642)
							(end -0.1778 -0.2794)
						)
						(arc
							(start 0.1778 -0.2794)
							(mid 0.249642 -0.249642)
							(end 0.2794 -0.1778)
						)
						(arc
							(start 0.2794 0.1778)
							(mid 0.249642 0.249642)
							(end 0.1778 0.2794)
						)
					)
					(width 0)
					(fill yes)
				)
			)
		)
		(pad "2" smd custom
			(at 0 0.4445 270)
			(size 0.1397 0.1397)
			(layers "B.Cu" "B.Mask" "B.Paste")
			(net "GND")
			(options
				(clearance outline)
				(anchor circle)
			)
			(primitives
				(gr_poly
					(pts
						(arc
							(start -0.1778 0.2794)
							(mid -0.249642 0.249642)
							(end -0.2794 0.1778)
						)
						(arc
							(start -0.2794 -0.1778)
							(mid -0.249642 -0.249642)
							(end -0.1778 -0.2794)
						)
						(arc
							(start 0.1778 -0.2794)
							(mid 0.249642 -0.249642)
							(end 0.2794 -0.1778)
						)
						(arc
							(start 0.2794 0.1778)
							(mid 0.249642 0.249642)
							(end 0.1778 0.2794)
						)
					)
					(width 0)
					(fill yes)
				)
			)
		)
	)
	(footprint ""
		(layer "B.Cu")
		(at 95.4024 -152.7556 180)
		(property "Reference" "C13"
			(at 0 0 0)
			(layer "B.SilkS")
			(hide yes)
			(effects
				(font
					(size 1.27 1.27)
				)
				(justify mirror)
			)
		)
		(property "Value" "SC1U16V3KX-5GP"
			(at 0 -2.8194 180)
			(unlocked yes)
			(layer "B.Fab")
			(hide yes)
			(effects
				(font
					(size 1.016 1.016)
					(thickness 0.1524)
				)
				(justify mirror)
			)
		)
		(property "Device Type" "C603H36"
			(at 0 -4.3434 180)
			(unlocked yes)
			(layer "B.Fab")
			(hide yes)
			(effects
				(font
					(size 1.016 1.016)
					(thickness 0.1524)
				)
				(justify mirror)
			)
		)
		(duplicate_pad_numbers_are_jumpers no)
		(fp_line
			(start -0.508 0)
			(end 0.508 0)
			(stroke
				(width 0.2032)
				(type default)
			)
			(layer "B.SilkS")
		)
		(fp_rect
			(start 0.5842 1.3335)
			(end -0.5842 -1.3335)
			(stroke
				(width 0)
				(type default)
			)
			(fill no)
			(layer "B.CrtYd")
		)
		(fp_rect
			(start 0.5842 1.3335)
			(end -0.5842 -1.3335)
			(stroke
				(width 0)
				(type default)
			)
			(fill no)
			(layer "B.Fab")
		)
		(pad "1" smd custom
			(at 0 -0.762)
			(size 0.2159 0.2159)
			(layers "B.Cu" "B.Mask" "B.Paste")
			(net "P3V3_STBY")
			(options
				(clearance outline)
				(anchor circle)
			)
			(primitives
				(gr_poly
					(pts
						(arc
							(start -0.3302 0.4318)
							(mid -0.402042 0.402042)
							(end -0.4318 0.3302)
						)
						(arc
							(start -0.4318 -0.3302)
							(mid -0.402042 -0.402042)
							(end -0.3302 -0.4318)
						)
						(arc
							(start 0.3302 -0.4318)
							(mid 0.402042 -0.402042)
							(end 0.4318 -0.3302)
						)
						(arc
							(start 0.4318 0.3302)
							(mid 0.402042 0.402042)
							(end 0.3302 0.4318)
						)
					)
					(width 0)
					(fill yes)
				)
			)
		)
		(pad "2" smd custom
			(at 0 0.762)
			(size 0.2159 0.2159)
			(layers "B.Cu" "B.Mask" "B.Paste")
			(net "GND")
			(options
				(clearance outline)
				(anchor circle)
			)
			(primitives
				(gr_poly
					(pts
						(arc
							(start -0.3302 0.4318)
							(mid -0.402042 0.402042)
							(end -0.4318 0.3302)
						)
						(arc
							(start -0.4318 -0.3302)
							(mid -0.402042 -0.402042)
							(end -0.3302 -0.4318)
						)
						(arc
							(start 0.3302 -0.4318)
							(mid 0.402042 -0.402042)
							(end 0.4318 -0.3302)
						)
						(arc
							(start 0.4318 0.3302)
							(mid 0.402042 0.402042)
							(end 0.3302 0.4318)
						)
					)
					(width 0)
					(fill yes)
				)
			)
		)
	)
	(footprint ""
		(layer "B.Cu")
		(at 52.832 -132.08)
		(property "Reference" "C109"
			(at 0 0 0)
			(layer "B.SilkS")
			(hide yes)
			(effects
				(font
					(size 1.27 1.27)
				)
				(justify mirror)
			)
		)
		(property "Value" "SC1U16V3KX-5GP"
			(at 0 -2.8194 0)
			(unlocked yes)
			(layer "B.Fab")
			(hide yes)
			(effects
				(font
					(size 1.016 1.016)
					(thickness 0.1524)
				)
				(justify mirror)
			)
		)
		(property "Device Type" "C603H36"
			(at 0 -4.3434 0)
			(unlocked yes)
			(layer "B.Fab")
			(hide yes)
			(effects
				(font
					(size 1.016 1.016)
					(thickness 0.1524)
				)
				(justify mirror)
			)
		)
		(duplicate_pad_numbers_are_jumpers no)
		(fp_line
			(start -0.508 0)
			(end 0.508 0)
			(stroke
				(width 0.2032)
				(type default)
			)
			(layer "B.SilkS")
		)
		(fp_rect
			(start 0.5842 1.3335)
			(end -0.5842 -1.3335)
			(stroke
				(width 0)
				(type default)
			)
			(fill no)
			(layer "B.CrtYd")
		)
		(fp_rect
			(start 0.5842 1.3335)
			(end -0.5842 -1.3335)
			(stroke
				(width 0)
				(type default)
			)
			(fill no)
			(layer "B.Fab")
		)
		(pad "1" smd custom
			(at 0 -0.762 180)
			(size 0.2159 0.2159)
			(layers "B.Cu" "B.Mask" "B.Paste")
			(net "P1V15_STBY")
			(options
				(clearance outline)
				(anchor circle)
			)
			(primitives
				(gr_poly
					(pts
						(arc
							(start -0.3302 0.4318)
							(mid -0.402042 0.402042)
							(end -0.4318 0.3302)
						)
						(arc
							(start -0.4318 -0.3302)
							(mid -0.402042 -0.402042)
							(end -0.3302 -0.4318)
						)
						(arc
							(start 0.3302 -0.4318)
							(mid 0.402042 -0.402042)
							(end 0.4318 -0.3302)
						)
						(arc
							(start 0.4318 0.3302)
							(mid 0.402042 0.402042)
							(end 0.3302 0.4318)
						)
					)
					(width 0)
					(fill yes)
				)
			)
		)
		(pad "2" smd custom
			(at 0 0.762 180)
			(size 0.2159 0.2159)
			(layers "B.Cu" "B.Mask" "B.Paste")
			(net "GND")
			(options
				(clearance outline)
				(anchor circle)
			)
			(primitives
				(gr_poly
					(pts
						(arc
							(start -0.3302 0.4318)
							(mid -0.402042 0.402042)
							(end -0.4318 0.3302)
						)
						(arc
							(start -0.4318 -0.3302)
							(mid -0.402042 -0.402042)
							(end -0.3302 -0.4318)
						)
						(arc
							(start 0.3302 -0.4318)
							(mid 0.402042 -0.402042)
							(end 0.4318 -0.3302)
						)
						(arc
							(start 0.4318 0.3302)
							(mid 0.402042 0.402042)
							(end 0.3302 0.4318)
						)
					)
					(width 0)
					(fill yes)
				)
			)
		)
	)
	(footprint ""
		(layer "B.Cu")
		(at 81.744566 -46.659292 -90)
		(property "Reference" "C511"
			(at 0 0 90)
			(layer "B.SilkS")
			(hide yes)
			(effects
				(font
					(size 1.27 1.27)
				)
				(justify mirror)
			)
		)
		(property "Value" "SC10U16V5KX-7-GP-U"
			(at 0.0762 -6.1214 270)
			(unlocked yes)
			(layer "B.Fab")
			(hide yes)
			(effects
				(font
					(size 1.016 1.016)
					(thickness 0.1524)
				)
				(justify mirror)
			)
		)
		(property "Device Type" "C805H58"
			(at 0.0762 -8.1534 270)
			(unlocked yes)
			(layer "B.Fab")
			(hide yes)
			(effects
				(font
					(size 1.016 1.016)
					(thickness 0.1524)
				)
				(justify mirror)
			)
		)
		(duplicate_pad_numbers_are_jumpers no)
		(fp_line
			(start -0.635 0)
			(end 0.635 0)
			(stroke
				(width 0.508)
				(type default)
			)
			(layer "B.SilkS")
		)
		(fp_rect
			(start 0.9652 1.778)
			(end -0.9652 -1.778)
			(stroke
				(width 0)
				(type default)
			)
			(fill no)
			(layer "B.CrtYd")
		)
		(fp_poly
			(pts
				(xy 0.9652 -1.778) (xy -0.9652 -1.778) (xy -0.9652 1.778) (xy 0.9652 1.778)
			)
			(stroke
				(width 0)
				(type default)
			)
			(fill no)
			(layer "B.Fab")
		)
		(pad "1" smd rect
			(at 0 -0.9652 90)
			(size 1.397 1.143)
			(layers "B.Cu" "B.Mask" "B.Paste")
			(net "P5V_STBY")
		)
		(pad "2" smd rect
			(at 0 0.9652 90)
			(size 1.397 1.143)
			(layers "B.Cu" "B.Mask" "B.Paste")
			(net "GND")
		)
	)
	(footprint ""
		(layer "B.Cu")
		(at 63.5762 -160.4772)
		(property "Reference" "C88"
			(at 0 0 0)
			(layer "B.SilkS")
			(hide yes)
			(effects
				(font
					(size 1.27 1.27)
				)
				(justify mirror)
			)
		)
		(property "Value" "SC100P50V2JN-3GP"
			(at -1.1811 -2.7051 0)
			(unlocked yes)
			(layer "B.Fab")
			(hide yes)
			(effects
				(font
					(size 1.016 1.016)
					(thickness 0.1524)
				)
				(justify mirror)
			)
		)
		(property "Device Type" "C402H22"
			(at -1.1811 -4.2291 0)
			(unlocked yes)
			(layer "B.Fab")
			(hide yes)
			(effects
				(font
					(size 1.016 1.016)
					(thickness 0.1524)
				)
				(justify mirror)
			)
		)
		(duplicate_pad_numbers_are_jumpers no)
		(fp_rect
			(start 0.4318 0.9525)
			(end -0.4318 -0.9525)
			(stroke
				(width 0)
				(type default)
			)
			(fill no)
			(layer "B.CrtYd")
		)
		(fp_rect
			(start 0.4318 0.9525)
			(end -0.4318 -0.9525)
			(stroke
				(width 0)
				(type default)
			)
			(fill no)
			(layer "B.Fab")
		)
		(pad "1" smd custom
			(at 0 -0.4445 180)
			(size 0.1524 0.1524)
			(layers "B.Cu" "B.Mask" "B.Paste")
			(net "ADCAV33")
			(options
				(clearance outline)
				(anchor circle)
			)
			(primitives
				(gr_poly
					(pts
						(arc
							(start 0.3048 0.2032)
							(mid 0.275042 0.275042)
							(end 0.2032 0.3048)
						)
						(arc
							(start -0.2032 0.3048)
							(mid -0.275042 0.275042)
							(end -0.3048 0.2032)
						)
						(arc
							(start -0.3048 -0.2032)
							(mid -0.275042 -0.275042)
							(end -0.2032 -0.3048)
						)
						(arc
							(start 0.2032 -0.3048)
							(mid 0.275042 -0.275042)
							(end 0.3048 -0.2032)
						)
					)
					(width 0)
					(fill yes)
				)
			)
		)
		(pad "2" smd custom
			(at 0 0.4445 180)
			(size 0.1524 0.1524)
			(layers "B.Cu" "B.Mask" "B.Paste")
			(net "GND")
			(options
				(clearance outline)
				(anchor circle)
			)
			(primitives
				(gr_poly
					(pts
						(arc
							(start 0.3048 0.2032)
							(mid 0.275042 0.275042)
							(end 0.2032 0.3048)
						)
						(arc
							(start -0.2032 0.3048)
							(mid -0.275042 0.275042)
							(end -0.3048 0.2032)
						)
						(arc
							(start -0.3048 -0.2032)
							(mid -0.275042 -0.275042)
							(end -0.2032 -0.3048)
						)
						(arc
							(start 0.2032 -0.3048)
							(mid 0.275042 -0.275042)
							(end 0.3048 -0.2032)
						)
					)
					(width 0)
					(fill yes)
				)
			)
		)
	)
	(footprint ""
		(layer "B.Cu")
		(at 90.84437 -172.57903 180)
		(property "Reference" "R417"
			(at 0 0 0)
			(layer "B.SilkS")
			(hide yes)
			(effects
				(font
					(size 1.27 1.27)
				)
				(justify mirror)
			)
		)
		(property "Value" "0R2J-2-GP"
			(at -0.064008 -3.993896 180)
			(unlocked yes)
			(layer "B.Fab")
			(hide yes)
			(effects
				(font
					(size 1.016 1.016)
					(thickness 0.1524)
				)
				(justify mirror)
			)
		)
		(property "Device Type" "R402H16"
			(at -0.064008 -5.517896 180)
			(unlocked yes)
			(layer "B.Fab")
			(hide yes)
			(effects
				(font
					(size 1.016 1.016)
					(thickness 0.1524)
				)
				(justify mirror)
			)
		)
		(duplicate_pad_numbers_are_jumpers no)
		(fp_line
			(start 0.508 -0.9398)
			(end 0.508 0.9398)
			(stroke
				(width 0.1524)
				(type default)
			)
			(layer "B.SilkS")
		)
		(fp_line
			(start -0.508 -0.9398)
			(end 0.508 -0.9398)
			(stroke
				(width 0.1524)
				(type default)
			)
			(layer "B.SilkS")
		)
		(fp_rect
			(start 0.508 0.9398)
			(end -0.508 -0.9398)
			(stroke
				(width 0)
				(type default)
			)
			(fill no)
			(layer "B.CrtYd")
		)
		(fp_rect
			(start 0.508 0.9398)
			(end -0.508 -0.9398)
			(stroke
				(width 0)
				(type default)
			)
			(fill no)
			(layer "B.Fab")
		)
		(pad "1" smd custom
			(at 0 -0.4445)
			(size 0.1397 0.1397)
			(layers "B.Cu" "B.Mask" "B.Paste")
			(net "PCIE_RST_R_N")
			(options
				(clearance outline)
				(anchor circle)
			)
			(primitives
				(gr_poly
					(pts
						(arc
							(start -0.1778 0.2794)
							(mid -0.249642 0.249642)
							(end -0.2794 0.1778)
						)
						(arc
							(start -0.2794 -0.1778)
							(mid -0.249642 -0.249642)
							(end -0.1778 -0.2794)
						)
						(arc
							(start 0.1778 -0.2794)
							(mid 0.249642 -0.249642)
							(end 0.2794 -0.1778)
						)
						(arc
							(start 0.2794 0.1778)
							(mid 0.249642 0.249642)
							(end 0.1778 0.2794)
						)
					)
					(width 0)
					(fill yes)
				)
			)
		)
		(pad "2" smd custom
			(at 0 0.4445)
			(size 0.1397 0.1397)
			(layers "B.Cu" "B.Mask" "B.Paste")
			(net "PCIE_COMP_TO_IOM_RST_4")
			(options
				(clearance outline)
				(anchor circle)
			)
			(primitives
				(gr_poly
					(pts
						(arc
							(start -0.1778 0.2794)
							(mid -0.249642 0.249642)
							(end -0.2794 0.1778)
						)
						(arc
							(start -0.2794 -0.1778)
							(mid -0.249642 -0.249642)
							(end -0.1778 -0.2794)
						)
						(arc
							(start 0.1778 -0.2794)
							(mid 0.249642 -0.249642)
							(end 0.2794 -0.1778)
						)
						(arc
							(start 0.2794 0.1778)
							(mid 0.249642 0.249642)
							(end 0.1778 0.2794)
						)
					)
					(width 0)
					(fill yes)
				)
			)
		)
	)
	(footprint ""
		(layer "B.Cu")
		(at 54.2036 -163.1188 -90)
		(property "Reference" "R401"
			(at 0 0 90)
			(layer "B.SilkS")
			(hide yes)
			(effects
				(font
					(size 1.27 1.27)
				)
				(justify mirror)
			)
		)
		(property "Value" "7K87R2F-GP"
			(at -0.064008 -3.993896 270)
			(unlocked yes)
			(layer "B.Fab")
			(hide yes)
			(effects
				(font
					(size 1.016 1.016)
					(thickness 0.1524)
				)
				(justify mirror)
			)
		)
		(property "Device Type" "R402H16"
			(at -0.064008 -5.517896 270)
			(unlocked yes)
			(layer "B.Fab")
			(hide yes)
			(effects
				(font
					(size 1.016 1.016)
					(thickness 0.1524)
				)
				(justify mirror)
			)
		)
		(duplicate_pad_numbers_are_jumpers no)
		(fp_line
			(start -0.508 -0.9398)
			(end 0.508 -0.9398)
			(stroke
				(width 0.1524)
				(type default)
			)
			(layer "B.SilkS")
		)
		(fp_line
			(start 0.508 -0.9398)
			(end 0.508 0.9398)
			(stroke
				(width 0.1524)
				(type default)
			)
			(layer "B.SilkS")
		)
		(fp_rect
			(start 0.508 0.9398)
			(end -0.508 -0.9398)
			(stroke
				(width 0)
				(type default)
			)
			(fill no)
			(layer "B.CrtYd")
		)
		(fp_rect
			(start 0.508 0.9398)
			(end -0.508 -0.9398)
			(stroke
				(width 0)
				(type default)
			)
			(fill no)
			(layer "B.Fab")
		)
		(pad "1" smd custom
			(at 0 -0.4445 90)
			(size 0.1397 0.1397)
			(layers "B.Cu" "B.Mask" "B.Paste")
			(net "P12V_STBY")
			(options
				(clearance outline)
				(anchor circle)
			)
			(primitives
				(gr_poly
					(pts
						(arc
							(start -0.1778 0.2794)
							(mid -0.249642 0.249642)
							(end -0.2794 0.1778)
						)
						(arc
							(start -0.2794 -0.1778)
							(mid -0.249642 -0.249642)
							(end -0.1778 -0.2794)
						)
						(arc
							(start 0.1778 -0.2794)
							(mid 0.249642 -0.249642)
							(end 0.2794 -0.1778)
						)
						(arc
							(start 0.2794 0.1778)
							(mid 0.249642 0.249642)
							(end 0.1778 0.2794)
						)
					)
					(width 0)
					(fill yes)
				)
			)
		)
		(pad "2" smd custom
			(at 0 0.4445 90)
			(size 0.1397 0.1397)
			(layers "B.Cu" "B.Mask" "B.Paste")
			(net "ADC_12V")
			(options
				(clearance outline)
				(anchor circle)
			)
			(primitives
				(gr_poly
					(pts
						(arc
							(start -0.1778 0.2794)
							(mid -0.249642 0.249642)
							(end -0.2794 0.1778)
						)
						(arc
							(start -0.2794 -0.1778)
							(mid -0.249642 -0.249642)
							(end -0.1778 -0.2794)
						)
						(arc
							(start 0.1778 -0.2794)
							(mid 0.249642 -0.249642)
							(end 0.2794 -0.1778)
						)
						(arc
							(start 0.2794 0.1778)
							(mid 0.249642 0.249642)
							(end 0.1778 0.2794)
						)
					)
					(width 0)
					(fill yes)
				)
			)
		)
	)
	(footprint ""
		(layer "B.Cu")
		(at 16.319754 -129.076958 180)
		(property "Reference" "R258"
			(at 0 0 0)
			(layer "B.SilkS")
			(hide yes)
			(effects
				(font
					(size 1.27 1.27)
				)
				(justify mirror)
			)
		)
		(property "Value" "120R2F-GP"
			(at -0.064008 -3.993896 180)
			(unlocked yes)
			(layer "B.Fab")
			(hide yes)
			(effects
				(font
					(size 1.016 1.016)
					(thickness 0.1524)
				)
				(justify mirror)
			)
		)
		(property "Device Type" "R402H16"
			(at -0.064008 -5.517896 180)
			(unlocked yes)
			(layer "B.Fab")
			(hide yes)
			(effects
				(font
					(size 1.016 1.016)
					(thickness 0.1524)
				)
				(justify mirror)
			)
		)
		(duplicate_pad_numbers_are_jumpers no)
		(fp_line
			(start 0.508 -0.9398)
			(end 0.508 0.9398)
			(stroke
				(width 0.1524)
				(type default)
			)
			(layer "B.SilkS")
		)
		(fp_line
			(start -0.508 -0.9398)
			(end 0.508 -0.9398)
			(stroke
				(width 0.1524)
				(type default)
			)
			(layer "B.SilkS")
		)
		(fp_rect
			(start 0.508 0.9398)
			(end -0.508 -0.9398)
			(stroke
				(width 0)
				(type default)
			)
			(fill no)
			(layer "B.CrtYd")
		)
		(fp_rect
			(start 0.508 0.9398)
			(end -0.508 -0.9398)
			(stroke
				(width 0)
				(type default)
			)
			(fill no)
			(layer "B.Fab")
		)
		(pad "1" smd custom
			(at 0 -0.4445)
			(size 0.1397 0.1397)
			(layers "B.Cu" "B.Mask" "B.Paste")
			(net "GND")
			(options
				(clearance outline)
				(anchor circle)
			)
			(primitives
				(gr_poly
					(pts
						(arc
							(start -0.1778 0.2794)
							(mid -0.249642 0.249642)
							(end -0.2794 0.1778)
						)
						(arc
							(start -0.2794 -0.1778)
							(mid -0.249642 -0.249642)
							(end -0.1778 -0.2794)
						)
						(arc
							(start 0.1778 -0.2794)
							(mid 0.249642 -0.249642)
							(end 0.2794 -0.1778)
						)
						(arc
							(start 0.2794 0.1778)
							(mid 0.249642 0.249642)
							(end 0.1778 0.2794)
						)
					)
					(width 0)
					(fill yes)
				)
			)
		)
		(pad "2" smd custom
			(at 0 0.4445)
			(size 0.1397 0.1397)
			(layers "B.Cu" "B.Mask" "B.Paste")
			(net "MEMA_12")
			(options
				(clearance outline)
				(anchor circle)
			)
			(primitives
				(gr_poly
					(pts
						(arc
							(start -0.1778 0.2794)
							(mid -0.249642 0.249642)
							(end -0.2794 0.1778)
						)
						(arc
							(start -0.2794 -0.1778)
							(mid -0.249642 -0.249642)
							(end -0.1778 -0.2794)
						)
						(arc
							(start 0.1778 -0.2794)
							(mid 0.249642 -0.249642)
							(end 0.2794 -0.1778)
						)
						(arc
							(start 0.2794 0.1778)
							(mid 0.249642 0.249642)
							(end 0.1778 0.2794)
						)
					)
					(width 0)
					(fill yes)
				)
			)
		)
	)
	(footprint ""
		(layer "B.Cu")
		(at 174.369984 -130.720338 180)
		(property "Reference" "C615"
			(at 0 0 0)
			(layer "B.SilkS")
			(hide yes)
			(effects
				(font
					(size 1.27 1.27)
				)
				(justify mirror)
			)
		)
		(property "Value" "SCD1U16V2KX-3GP"
			(at -1.1811 -2.7051 180)
			(unlocked yes)
			(layer "B.Fab")
			(hide yes)
			(effects
				(font
					(size 1.016 1.016)
					(thickness 0.1524)
				)
				(justify mirror)
			)
		)
		(property "Device Type" "C402H22"
			(at -1.1811 -4.2291 180)
			(unlocked yes)
			(layer "B.Fab")
			(hide yes)
			(effects
				(font
					(size 1.016 1.016)
					(thickness 0.1524)
				)
				(justify mirror)
			)
		)
		(duplicate_pad_numbers_are_jumpers no)
		(fp_rect
			(start 0.4318 0.9525)
			(end -0.4318 -0.9525)
			(stroke
				(width 0)
				(type default)
			)
			(fill no)
			(layer "B.CrtYd")
		)
		(fp_rect
			(start 0.4318 0.9525)
			(end -0.4318 -0.9525)
			(stroke
				(width 0)
				(type default)
			)
			(fill no)
			(layer "B.Fab")
		)
		(pad "1" smd custom
			(at 0 -0.4445)
			(size 0.1524 0.1524)
			(layers "B.Cu" "B.Mask" "B.Paste")
			(net "P3V3_M2")
			(options
				(clearance outline)
				(anchor circle)
			)
			(primitives
				(gr_poly
					(pts
						(arc
							(start 0.3048 0.2032)
							(mid 0.275042 0.275042)
							(end 0.2032 0.3048)
						)
						(arc
							(start -0.2032 0.3048)
							(mid -0.275042 0.275042)
							(end -0.3048 0.2032)
						)
						(arc
							(start -0.3048 -0.2032)
							(mid -0.275042 -0.275042)
							(end -0.2032 -0.3048)
						)
						(arc
							(start 0.2032 -0.3048)
							(mid 0.275042 -0.275042)
							(end 0.3048 -0.2032)
						)
					)
					(width 0)
					(fill yes)
				)
			)
		)
		(pad "2" smd custom
			(at 0 0.4445)
			(size 0.1524 0.1524)
			(layers "B.Cu" "B.Mask" "B.Paste")
			(net "GND")
			(options
				(clearance outline)
				(anchor circle)
			)
			(primitives
				(gr_poly
					(pts
						(arc
							(start 0.3048 0.2032)
							(mid 0.275042 0.275042)
							(end 0.2032 0.3048)
						)
						(arc
							(start -0.2032 0.3048)
							(mid -0.275042 0.275042)
							(end -0.3048 0.2032)
						)
						(arc
							(start -0.3048 -0.2032)
							(mid -0.275042 -0.275042)
							(end -0.2032 -0.3048)
						)
						(arc
							(start 0.2032 -0.3048)
							(mid 0.275042 -0.275042)
							(end 0.3048 -0.2032)
						)
					)
					(width 0)
					(fill yes)
				)
			)
		)
	)
	(footprint ""
		(layer "B.Cu")
		(at 69.56933 -144.691608)
		(property "Reference" "R194"
			(at 0 0 0)
			(layer "B.SilkS")
			(hide yes)
			(effects
				(font
					(size 1.27 1.27)
				)
				(justify mirror)
			)
		)
		(property "Value" "20KR2F-L-GP"
			(at -0.064008 -3.993896 0)
			(unlocked yes)
			(layer "B.Fab")
			(hide yes)
			(effects
				(font
					(size 1.016 1.016)
					(thickness 0.1524)
				)
				(justify mirror)
			)
		)
		(property "Device Type" "R402H16"
			(at -0.064008 -5.517896 0)
			(unlocked yes)
			(layer "B.Fab")
			(hide yes)
			(effects
				(font
					(size 1.016 1.016)
					(thickness 0.1524)
				)
				(justify mirror)
			)
		)
		(duplicate_pad_numbers_are_jumpers no)
		(fp_line
			(start -0.508 -0.9398)
			(end 0.508 -0.9398)
			(stroke
				(width 0.1524)
				(type default)
			)
			(layer "B.SilkS")
		)
		(fp_line
			(start 0.508 -0.9398)
			(end 0.508 0.9398)
			(stroke
				(width 0.1524)
				(type default)
			)
			(layer "B.SilkS")
		)
		(fp_rect
			(start 0.508 0.9398)
			(end -0.508 -0.9398)
			(stroke
				(width 0)
				(type default)
			)
			(fill no)
			(layer "B.CrtYd")
		)
		(fp_rect
			(start 0.508 0.9398)
			(end -0.508 -0.9398)
			(stroke
				(width 0)
				(type default)
			)
			(fill no)
			(layer "B.Fab")
		)
		(pad "1" smd custom
			(at 0 -0.4445 180)
			(size 0.1397 0.1397)
			(layers "B.Cu" "B.Mask" "B.Paste")
			(net "P3V3_STBY")
			(options
				(clearance outline)
				(anchor circle)
			)
			(primitives
				(gr_poly
					(pts
						(arc
							(start -0.1778 0.2794)
							(mid -0.249642 0.249642)
							(end -0.2794 0.1778)
						)
						(arc
							(start -0.2794 -0.1778)
							(mid -0.249642 -0.249642)
							(end -0.1778 -0.2794)
						)
						(arc
							(start 0.1778 -0.2794)
							(mid 0.249642 -0.249642)
							(end 0.2794 -0.1778)
						)
						(arc
							(start 0.2794 0.1778)
							(mid 0.249642 0.249642)
							(end 0.1778 0.2794)
						)
					)
					(width 0)
					(fill yes)
				)
			)
		)
		(pad "2" smd custom
			(at 0 0.4445 180)
			(size 0.1397 0.1397)
			(layers "B.Cu" "B.Mask" "B.Paste")
			(net "I2C_DEBUG_SDA_L")
			(options
				(clearance outline)
				(anchor circle)
			)
			(primitives
				(gr_poly
					(pts
						(arc
							(start -0.1778 0.2794)
							(mid -0.249642 0.249642)
							(end -0.2794 0.1778)
						)
						(arc
							(start -0.2794 -0.1778)
							(mid -0.249642 -0.249642)
							(end -0.1778 -0.2794)
						)
						(arc
							(start 0.1778 -0.2794)
							(mid 0.249642 -0.249642)
							(end 0.2794 -0.1778)
						)
						(arc
							(start 0.2794 0.1778)
							(mid 0.249642 0.249642)
							(end 0.1778 0.2794)
						)
					)
					(width 0)
					(fill yes)
				)
			)
		)
	)
	(footprint ""
		(layer "B.Cu")
		(at 78.4098 -130.4798)
		(property "Reference" "C502"
			(at 0 0 0)
			(layer "B.SilkS")
			(hide yes)
			(effects
				(font
					(size 1.27 1.27)
				)
				(justify mirror)
			)
		)
		(property "Value" "SCD1U16V2KX-3GP"
			(at -1.1811 -2.7051 0)
			(unlocked yes)
			(layer "B.Fab")
			(hide yes)
			(effects
				(font
					(size 1.016 1.016)
					(thickness 0.1524)
				)
				(justify mirror)
			)
		)
		(property "Device Type" "C402H22"
			(at -1.1811 -4.2291 0)
			(unlocked yes)
			(layer "B.Fab")
			(hide yes)
			(effects
				(font
					(size 1.016 1.016)
					(thickness 0.1524)
				)
				(justify mirror)
			)
		)
		(duplicate_pad_numbers_are_jumpers no)
		(fp_rect
			(start 0.4318 0.9525)
			(end -0.4318 -0.9525)
			(stroke
				(width 0)
				(type default)
			)
			(fill no)
			(layer "B.CrtYd")
		)
		(fp_rect
			(start 0.4318 0.9525)
			(end -0.4318 -0.9525)
			(stroke
				(width 0)
				(type default)
			)
			(fill no)
			(layer "B.Fab")
		)
		(pad "1" smd custom
			(at 0 -0.4445 180)
			(size 0.1524 0.1524)
			(layers "B.Cu" "B.Mask" "B.Paste")
			(net "P3V3_STBY")
			(options
				(clearance outline)
				(anchor circle)
			)
			(primitives
				(gr_poly
					(pts
						(arc
							(start 0.3048 0.2032)
							(mid 0.275042 0.275042)
							(end 0.2032 0.3048)
						)
						(arc
							(start -0.2032 0.3048)
							(mid -0.275042 0.275042)
							(end -0.3048 0.2032)
						)
						(arc
							(start -0.3048 -0.2032)
							(mid -0.275042 -0.275042)
							(end -0.2032 -0.3048)
						)
						(arc
							(start 0.2032 -0.3048)
							(mid 0.275042 -0.275042)
							(end 0.3048 -0.2032)
						)
					)
					(width 0)
					(fill yes)
				)
			)
		)
		(pad "2" smd custom
			(at 0 0.4445 180)
			(size 0.1524 0.1524)
			(layers "B.Cu" "B.Mask" "B.Paste")
			(net "GND")
			(options
				(clearance outline)
				(anchor circle)
			)
			(primitives
				(gr_poly
					(pts
						(arc
							(start 0.3048 0.2032)
							(mid 0.275042 0.275042)
							(end 0.2032 0.3048)
						)
						(arc
							(start -0.2032 0.3048)
							(mid -0.275042 0.275042)
							(end -0.3048 0.2032)
						)
						(arc
							(start -0.3048 -0.2032)
							(mid -0.275042 -0.275042)
							(end -0.2032 -0.3048)
						)
						(arc
							(start 0.2032 -0.3048)
							(mid 0.275042 -0.275042)
							(end 0.3048 -0.2032)
						)
					)
					(width 0)
					(fill yes)
				)
			)
		)
	)
	(footprint ""
		(layer "B.Cu")
		(at 42.357294 -125.48108)
		(property "Reference" "R364"
			(at 0 0 0)
			(layer "B.SilkS")
			(hide yes)
			(effects
				(font
					(size 1.27 1.27)
				)
				(justify mirror)
			)
		)
		(property "Value" "4K7R2F-GP"
			(at -0.064008 -3.993896 0)
			(unlocked yes)
			(layer "B.Fab")
			(hide yes)
			(effects
				(font
					(size 1.016 1.016)
					(thickness 0.1524)
				)
				(justify mirror)
			)
		)
		(property "Device Type" "R402H16"
			(at -0.064008 -5.517896 0)
			(unlocked yes)
			(layer "B.Fab")
			(hide yes)
			(effects
				(font
					(size 1.016 1.016)
					(thickness 0.1524)
				)
				(justify mirror)
			)
		)
		(duplicate_pad_numbers_are_jumpers no)
		(fp_line
			(start -0.508 -0.9398)
			(end 0.508 -0.9398)
			(stroke
				(width 0.1524)
				(type default)
			)
			(layer "B.SilkS")
		)
		(fp_line
			(start 0.508 -0.9398)
			(end 0.508 0.9398)
			(stroke
				(width 0.1524)
				(type default)
			)
			(layer "B.SilkS")
		)
		(fp_rect
			(start 0.508 0.9398)
			(end -0.508 -0.9398)
			(stroke
				(width 0)
				(type default)
			)
			(fill no)
			(layer "B.CrtYd")
		)
		(fp_rect
			(start 0.508 0.9398)
			(end -0.508 -0.9398)
			(stroke
				(width 0)
				(type default)
			)
			(fill no)
			(layer "B.Fab")
		)
		(pad "1" smd custom
			(at 0 -0.4445 180)
			(size 0.1397 0.1397)
			(layers "B.Cu" "B.Mask" "B.Paste")
			(net "FM_BMC_RESET_N")
			(options
				(clearance outline)
				(anchor circle)
			)
			(primitives
				(gr_poly
					(pts
						(arc
							(start -0.1778 0.2794)
							(mid -0.249642 0.249642)
							(end -0.2794 0.1778)
						)
						(arc
							(start -0.2794 -0.1778)
							(mid -0.249642 -0.249642)
							(end -0.1778 -0.2794)
						)
						(arc
							(start 0.1778 -0.2794)
							(mid 0.249642 -0.249642)
							(end 0.2794 -0.1778)
						)
						(arc
							(start 0.2794 0.1778)
							(mid 0.249642 0.249642)
							(end 0.1778 0.2794)
						)
					)
					(width 0)
					(fill yes)
				)
			)
		)
		(pad "2" smd custom
			(at 0 0.4445 180)
			(size 0.1397 0.1397)
			(layers "B.Cu" "B.Mask" "B.Paste")
			(net "GND")
			(options
				(clearance outline)
				(anchor circle)
			)
			(primitives
				(gr_poly
					(pts
						(arc
							(start -0.1778 0.2794)
							(mid -0.249642 0.249642)
							(end -0.2794 0.1778)
						)
						(arc
							(start -0.2794 -0.1778)
							(mid -0.249642 -0.249642)
							(end -0.1778 -0.2794)
						)
						(arc
							(start 0.1778 -0.2794)
							(mid 0.249642 -0.249642)
							(end 0.2794 -0.1778)
						)
						(arc
							(start 0.2794 0.1778)
							(mid 0.249642 0.249642)
							(end 0.1778 0.2794)
						)
					)
					(width 0)
					(fill yes)
				)
			)
		)
	)
	(footprint ""
		(layer "B.Cu")
		(at 34.8742 -127.2794 -90)
		(property "Reference" "U104"
			(at 0 0 90)
			(layer "B.SilkS")
			(hide yes)
			(effects
				(font
					(size 1.27 1.27)
				)
				(justify mirror)
			)
		)
		(property "Value" "SNLVC1G126DCKR-GP"
			(at 2.3368 -8.6868 270)
			(unlocked yes)
			(layer "B.Fab")
			(hide yes)
			(effects
				(font
					(size 1.016 1.016)
					(thickness 0.1524)
				)
				(justify mirror)
			)
		)
		(property "Device Type" "SC70-5H44"
			(at 2.3114 -10.414 270)
			(unlocked yes)
			(layer "B.Fab")
			(hide yes)
			(effects
				(font
					(size 1.016 1.016)
					(thickness 0.1524)
				)
				(justify mirror)
			)
		)
		(duplicate_pad_numbers_are_jumpers no)
		(fp_line
			(start -1.27 1.7018)
			(end 1.27 1.7018)
			(stroke
				(width 0.1524)
				(type default)
			)
			(layer "B.SilkS")
		)
		(fp_line
			(start 1.27 1.7018)
			(end 1.27 -1.7018)
			(stroke
				(width 0.1524)
				(type default)
			)
			(layer "B.SilkS")
		)
		(fp_line
			(start -1.27 -1.7018)
			(end -1.27 1.7018)
			(stroke
				(width 0.1524)
				(type default)
			)
			(layer "B.SilkS")
		)
		(fp_line
			(start 1.27 -1.7018)
			(end -1.27 -1.7018)
			(stroke
				(width 0.1524)
				(type default)
			)
			(layer "B.SilkS")
		)
		(fp_line
			(start -1.3843 -1.8034)
			(end -1.3843 -1.1176)
			(stroke
				(width 0.3302)
				(type default)
			)
			(layer "B.SilkS")
		)
		(fp_line
			(start -0.6604 -1.8034)
			(end -1.3843 -1.8034)
			(stroke
				(width 0.3302)
				(type default)
			)
			(layer "B.SilkS")
		)
		(fp_rect
			(start 1.524 1.9558)
			(end -1.524 -1.9558)
			(stroke
				(width 0)
				(type default)
			)
			(fill no)
			(layer "B.CrtYd")
		)
		(fp_poly
			(pts
				(xy 1.524 -1.9558) (xy -1.524 -1.9558) (xy -1.524 1.9558) (xy 1.524 1.9558)
			)
			(stroke
				(width 0)
				(type default)
			)
			(fill no)
			(layer "B.Fab")
		)
		(pad "1" smd rect
			(at -0.65024 -0.8255 90)
			(size 0.4064 1.2192)
			(layers "B.Cu" "B.Mask" "B.Paste")
			(net "U104_EN")
		)
		(pad "2" smd rect
			(at 0 -0.8255 90)
			(size 0.4064 1.2192)
			(layers "B.Cu" "B.Mask" "B.Paste")
			(net "SYS_RESET_N_OUT")
		)
		(pad "3" smd rect
			(at 0.65024 -0.8255 90)
			(size 0.4064 1.2192)
			(layers "B.Cu" "B.Mask" "B.Paste")
			(net "GND")
		)
		(pad "4" smd rect
			(at 0.65024 0.8255 90)
			(size 0.4064 1.2192)
			(layers "B.Cu" "B.Mask" "B.Paste")
			(net "SYS_RESET_N")
		)
		(pad "5" smd rect
			(at -0.65024 0.8255 90)
			(size 0.4064 1.2192)
			(layers "B.Cu" "B.Mask" "B.Paste")
			(net "P3V3_STBY")
		)
	)
	(footprint ""
		(layer "B.Cu")
		(at 191.332866 -136.834372 90)
		(property "Reference" "R803"
			(at 0 0 90)
			(layer "B.SilkS")
			(hide yes)
			(effects
				(font
					(size 1.27 1.27)
				)
				(justify mirror)
			)
		)
		(property "Value" "4K7R2F-GP"
			(at -0.064008 -3.993896 90)
			(unlocked yes)
			(layer "B.Fab")
			(hide yes)
			(effects
				(font
					(size 1.016 1.016)
					(thickness 0.1524)
				)
				(justify mirror)
			)
		)
		(property "Device Type" "R402H16"
			(at -0.064008 -5.517896 90)
			(unlocked yes)
			(layer "B.Fab")
			(hide yes)
			(effects
				(font
					(size 1.016 1.016)
					(thickness 0.1524)
				)
				(justify mirror)
			)
		)
		(duplicate_pad_numbers_are_jumpers no)
		(fp_line
			(start 0.508 -0.9398)
			(end 0.508 0.9398)
			(stroke
				(width 0.1524)
				(type default)
			)
			(layer "B.SilkS")
		)
		(fp_line
			(start -0.508 -0.9398)
			(end 0.508 -0.9398)
			(stroke
				(width 0.1524)
				(type default)
			)
			(layer "B.SilkS")
		)
		(fp_rect
			(start 0.508 0.9398)
			(end -0.508 -0.9398)
			(stroke
				(width 0)
				(type default)
			)
			(fill no)
			(layer "B.CrtYd")
		)
		(fp_rect
			(start 0.508 0.9398)
			(end -0.508 -0.9398)
			(stroke
				(width 0)
				(type default)
			)
			(fill no)
			(layer "B.Fab")
		)
		(pad "1" smd custom
			(at 0 -0.4445 270)
			(size 0.1397 0.1397)
			(layers "B.Cu" "B.Mask" "B.Paste")
			(net "P3V3_STBY")
			(options
				(clearance outline)
				(anchor circle)
			)
			(primitives
				(gr_poly
					(pts
						(arc
							(start -0.1778 0.2794)
							(mid -0.249642 0.249642)
							(end -0.2794 0.1778)
						)
						(arc
							(start -0.2794 -0.1778)
							(mid -0.249642 -0.249642)
							(end -0.1778 -0.2794)
						)
						(arc
							(start 0.1778 -0.2794)
							(mid 0.249642 -0.249642)
							(end 0.2794 -0.1778)
						)
						(arc
							(start 0.2794 0.1778)
							(mid 0.249642 0.249642)
							(end 0.1778 0.2794)
						)
					)
					(width 0)
					(fill yes)
				)
			)
		)
		(pad "2" smd custom
			(at 0 0.4445 270)
			(size 0.1397 0.1397)
			(layers "B.Cu" "B.Mask" "B.Paste")
			(net "M2_1_PRESENT_N")
			(options
				(clearance outline)
				(anchor circle)
			)
			(primitives
				(gr_poly
					(pts
						(arc
							(start -0.1778 0.2794)
							(mid -0.249642 0.249642)
							(end -0.2794 0.1778)
						)
						(arc
							(start -0.2794 -0.1778)
							(mid -0.249642 -0.249642)
							(end -0.1778 -0.2794)
						)
						(arc
							(start 0.1778 -0.2794)
							(mid 0.249642 -0.249642)
							(end 0.2794 -0.1778)
						)
						(arc
							(start 0.2794 0.1778)
							(mid 0.249642 0.249642)
							(end 0.1778 0.2794)
						)
					)
					(width 0)
					(fill yes)
				)
			)
		)
	)
	(footprint ""
		(layer "B.Cu")
		(at 37.465 -151.5618 -90)
		(property "Reference" "R318"
			(at 0 0 90)
			(layer "B.SilkS")
			(hide yes)
			(effects
				(font
					(size 1.27 1.27)
				)
				(justify mirror)
			)
		)
		(property "Value" "0R2J-2-GP"
			(at -0.064008 -3.993896 270)
			(unlocked yes)
			(layer "B.Fab")
			(hide yes)
			(effects
				(font
					(size 1.016 1.016)
					(thickness 0.1524)
				)
				(justify mirror)
			)
		)
		(property "Device Type" "R402H16"
			(at -0.064008 -5.517896 270)
			(unlocked yes)
			(layer "B.Fab")
			(hide yes)
			(effects
				(font
					(size 1.016 1.016)
					(thickness 0.1524)
				)
				(justify mirror)
			)
		)
		(duplicate_pad_numbers_are_jumpers no)
		(fp_line
			(start -0.508 -0.9398)
			(end 0.508 -0.9398)
			(stroke
				(width 0.1524)
				(type default)
			)
			(layer "B.SilkS")
		)
		(fp_line
			(start 0.508 -0.9398)
			(end 0.508 0.9398)
			(stroke
				(width 0.1524)
				(type default)
			)
			(layer "B.SilkS")
		)
		(fp_rect
			(start 0.508 0.9398)
			(end -0.508 -0.9398)
			(stroke
				(width 0)
				(type default)
			)
			(fill no)
			(layer "B.CrtYd")
		)
		(fp_rect
			(start 0.508 0.9398)
			(end -0.508 -0.9398)
			(stroke
				(width 0)
				(type default)
			)
			(fill no)
			(layer "B.Fab")
		)
		(pad "1" smd custom
			(at 0 -0.4445 90)
			(size 0.1397 0.1397)
			(layers "B.Cu" "B.Mask" "B.Paste")
			(net "COMP_PWR_EN_R")
			(options
				(clearance outline)
				(anchor circle)
			)
			(primitives
				(gr_poly
					(pts
						(arc
							(start -0.1778 0.2794)
							(mid -0.249642 0.249642)
							(end -0.2794 0.1778)
						)
						(arc
							(start -0.2794 -0.1778)
							(mid -0.249642 -0.249642)
							(end -0.1778 -0.2794)
						)
						(arc
							(start 0.1778 -0.2794)
							(mid 0.249642 -0.249642)
							(end 0.2794 -0.1778)
						)
						(arc
							(start 0.2794 0.1778)
							(mid 0.249642 0.249642)
							(end 0.1778 0.2794)
						)
					)
					(width 0)
					(fill yes)
				)
			)
		)
		(pad "2" smd custom
			(at 0 0.4445 90)
			(size 0.1397 0.1397)
			(layers "B.Cu" "B.Mask" "B.Paste")
			(net "COMP_PWR_EN")
			(options
				(clearance outline)
				(anchor circle)
			)
			(primitives
				(gr_poly
					(pts
						(arc
							(start -0.1778 0.2794)
							(mid -0.249642 0.249642)
							(end -0.2794 0.1778)
						)
						(arc
							(start -0.2794 -0.1778)
							(mid -0.249642 -0.249642)
							(end -0.1778 -0.2794)
						)
						(arc
							(start 0.1778 -0.2794)
							(mid 0.249642 -0.249642)
							(end 0.2794 -0.1778)
						)
						(arc
							(start 0.2794 0.1778)
							(mid 0.249642 0.249642)
							(end 0.1778 0.2794)
						)
					)
					(width 0)
					(fill yes)
				)
			)
		)
	)
	(footprint ""
		(layer "B.Cu")
		(at 43.9928 -133.7818 -90)
		(property "Reference" "R184"
			(at 0 0 90)
			(layer "B.SilkS")
			(hide yes)
			(effects
				(font
					(size 1.27 1.27)
				)
				(justify mirror)
			)
		)
		(property "Value" "2K2R2F-GP"
			(at -0.064008 -3.993896 270)
			(unlocked yes)
			(layer "B.Fab")
			(hide yes)
			(effects
				(font
					(size 1.016 1.016)
					(thickness 0.1524)
				)
				(justify mirror)
			)
		)
		(property "Device Type" "R402H16"
			(at -0.064008 -5.517896 270)
			(unlocked yes)
			(layer "B.Fab")
			(hide yes)
			(effects
				(font
					(size 1.016 1.016)
					(thickness 0.1524)
				)
				(justify mirror)
			)
		)
		(duplicate_pad_numbers_are_jumpers no)
		(fp_line
			(start -0.508 -0.9398)
			(end 0.508 -0.9398)
			(stroke
				(width 0.1524)
				(type default)
			)
			(layer "B.SilkS")
		)
		(fp_line
			(start 0.508 -0.9398)
			(end 0.508 0.9398)
			(stroke
				(width 0.1524)
				(type default)
			)
			(layer "B.SilkS")
		)
		(fp_rect
			(start 0.508 0.9398)
			(end -0.508 -0.9398)
			(stroke
				(width 0)
				(type default)
			)
			(fill no)
			(layer "B.CrtYd")
		)
		(fp_rect
			(start 0.508 0.9398)
			(end -0.508 -0.9398)
			(stroke
				(width 0)
				(type default)
			)
			(fill no)
			(layer "B.Fab")
		)
		(pad "1" smd custom
			(at 0 -0.4445 90)
			(size 0.1397 0.1397)
			(layers "B.Cu" "B.Mask" "B.Paste")
			(net "I2C_IOM_SDA")
			(options
				(clearance outline)
				(anchor circle)
			)
			(primitives
				(gr_poly
					(pts
						(arc
							(start -0.1778 0.2794)
							(mid -0.249642 0.249642)
							(end -0.2794 0.1778)
						)
						(arc
							(start -0.2794 -0.1778)
							(mid -0.249642 -0.249642)
							(end -0.1778 -0.2794)
						)
						(arc
							(start 0.1778 -0.2794)
							(mid 0.249642 -0.249642)
							(end 0.2794 -0.1778)
						)
						(arc
							(start 0.2794 0.1778)
							(mid 0.249642 0.249642)
							(end 0.1778 0.2794)
						)
					)
					(width 0)
					(fill yes)
				)
			)
		)
		(pad "2" smd custom
			(at 0 0.4445 90)
			(size 0.1397 0.1397)
			(layers "B.Cu" "B.Mask" "B.Paste")
			(net "P3V3_STBY")
			(options
				(clearance outline)
				(anchor circle)
			)
			(primitives
				(gr_poly
					(pts
						(arc
							(start -0.1778 0.2794)
							(mid -0.249642 0.249642)
							(end -0.2794 0.1778)
						)
						(arc
							(start -0.2794 -0.1778)
							(mid -0.249642 -0.249642)
							(end -0.1778 -0.2794)
						)
						(arc
							(start 0.1778 -0.2794)
							(mid 0.249642 -0.249642)
							(end 0.2794 -0.1778)
						)
						(arc
							(start 0.2794 0.1778)
							(mid 0.249642 0.249642)
							(end 0.1778 0.2794)
						)
					)
					(width 0)
					(fill yes)
				)
			)
		)
	)
	(footprint ""
		(layer "B.Cu")
		(at 208.0514 -99.5426 180)
		(property "Reference" "R526"
			(at 0 0 0)
			(layer "B.SilkS")
			(hide yes)
			(effects
				(font
					(size 1.27 1.27)
				)
				(justify mirror)
			)
		)
		(property "Value" "0R2J-2-GP"
			(at -0.064008 -3.993896 180)
			(unlocked yes)
			(layer "B.Fab")
			(hide yes)
			(effects
				(font
					(size 1.016 1.016)
					(thickness 0.1524)
				)
				(justify mirror)
			)
		)
		(property "Device Type" "R402H16"
			(at -0.064008 -5.517896 180)
			(unlocked yes)
			(layer "B.Fab")
			(hide yes)
			(effects
				(font
					(size 1.016 1.016)
					(thickness 0.1524)
				)
				(justify mirror)
			)
		)
		(duplicate_pad_numbers_are_jumpers no)
		(fp_line
			(start 0.508 -0.9398)
			(end 0.508 0.9398)
			(stroke
				(width 0.1524)
				(type default)
			)
			(layer "B.SilkS")
		)
		(fp_line
			(start -0.508 -0.9398)
			(end 0.508 -0.9398)
			(stroke
				(width 0.1524)
				(type default)
			)
			(layer "B.SilkS")
		)
		(fp_rect
			(start 0.508 0.9398)
			(end -0.508 -0.9398)
			(stroke
				(width 0)
				(type default)
			)
			(fill no)
			(layer "B.CrtYd")
		)
		(fp_rect
			(start 0.508 0.9398)
			(end -0.508 -0.9398)
			(stroke
				(width 0)
				(type default)
			)
			(fill no)
			(layer "B.Fab")
		)
		(pad "1" smd custom
			(at 0 -0.4445)
			(size 0.1397 0.1397)
			(layers "B.Cu" "B.Mask" "B.Paste")
			(net "IOM_FULL_PGOOD")
			(options
				(clearance outline)
				(anchor circle)
			)
			(primitives
				(gr_poly
					(pts
						(arc
							(start -0.1778 0.2794)
							(mid -0.249642 0.249642)
							(end -0.2794 0.1778)
						)
						(arc
							(start -0.2794 -0.1778)
							(mid -0.249642 -0.249642)
							(end -0.1778 -0.2794)
						)
						(arc
							(start 0.1778 -0.2794)
							(mid 0.249642 -0.249642)
							(end 0.2794 -0.1778)
						)
						(arc
							(start 0.2794 0.1778)
							(mid 0.249642 0.249642)
							(end 0.1778 0.2794)
						)
					)
					(width 0)
					(fill yes)
				)
			)
		)
		(pad "2" smd custom
			(at 0 0.4445)
			(size 0.1397 0.1397)
			(layers "B.Cu" "B.Mask" "B.Paste")
			(net "U82_VREF2")
			(options
				(clearance outline)
				(anchor circle)
			)
			(primitives
				(gr_poly
					(pts
						(arc
							(start -0.1778 0.2794)
							(mid -0.249642 0.249642)
							(end -0.2794 0.1778)
						)
						(arc
							(start -0.2794 -0.1778)
							(mid -0.249642 -0.249642)
							(end -0.1778 -0.2794)
						)
						(arc
							(start 0.1778 -0.2794)
							(mid 0.249642 -0.249642)
							(end 0.2794 -0.1778)
						)
						(arc
							(start 0.2794 0.1778)
							(mid 0.249642 0.249642)
							(end 0.1778 0.2794)
						)
					)
					(width 0)
					(fill yes)
				)
			)
		)
	)
	(footprint ""
		(layer "B.Cu")
		(at 38.0238 -182.6768 180)
		(property "Reference" "R484"
			(at 0 0 0)
			(layer "B.SilkS")
			(hide yes)
			(effects
				(font
					(size 1.27 1.27)
				)
				(justify mirror)
			)
		)
		(property "Value" "3D01R5F-GP"
			(at 0 -8.9535 180)
			(unlocked yes)
			(layer "B.Fab")
			(hide yes)
			(effects
				(font
					(size 1.27 1.016)
					(thickness 0.1524)
				)
				(justify mirror)
			)
		)
		(property "Device Type" "R805H24"
			(at 0 -10.6299 180)
			(unlocked yes)
			(layer "B.Fab")
			(hide yes)
			(effects
				(font
					(size 1.27 1.016)
					(thickness 0.1524)
				)
				(justify mirror)
			)
		)
		(duplicate_pad_numbers_are_jumpers no)
		(fp_line
			(start 0.889 1.7018)
			(end -0.889 1.7018)
			(stroke
				(width 0.1524)
				(type default)
			)
			(layer "B.SilkS")
		)
		(fp_line
			(start 0.889 0.0762)
			(end 0.889 1.7018)
			(stroke
				(width 0.1524)
				(type default)
			)
			(layer "B.SilkS")
		)
		(fp_line
			(start 0.889 -1.7018)
			(end 0.889 0.2794)
			(stroke
				(width 0.1524)
				(type default)
			)
			(layer "B.SilkS")
		)
		(fp_line
			(start -0.889 1.7018)
			(end -0.889 -0.508)
			(stroke
				(width 0.1524)
				(type default)
			)
			(layer "B.SilkS")
		)
		(fp_line
			(start -0.889 -1.7018)
			(end 0.889 -1.7018)
			(stroke
				(width 0.1524)
				(type default)
			)
			(layer "B.SilkS")
		)
		(fp_line
			(start -0.889 -1.7018)
			(end -0.889 -0.381)
			(stroke
				(width 0.1524)
				(type default)
			)
			(layer "B.SilkS")
		)
		(fp_poly
			(pts
				(xy -0.9652 -1.778) (xy -0.9652 1.778) (xy 0.9652 1.778) (xy 0.9652 -1.778)
			)
			(stroke
				(width 0)
				(type default)
			)
			(fill no)
			(layer "B.CrtYd")
		)
		(fp_rect
			(start 0.9652 1.778)
			(end -0.9652 -1.778)
			(stroke
				(width 0)
				(type default)
			)
			(fill no)
			(layer "B.Fab")
		)
		(pad "1" smd rect
			(at 0 -0.9652)
			(size 1.397 1.143)
			(layers "B.Cu" "B.Mask" "B.Paste")
			(net "P3V3_VBST")
		)
		(pad "2" smd rect
			(at 0 0.9652)
			(size 1.397 1.143)
			(layers "B.Cu" "B.Mask" "B.Paste")
			(net "P3V3_VBST_RC")
		)
	)
	(footprint ""
		(layer "B.Cu")
		(at 34.8234 -152.0952 180)
		(property "Reference" "C94"
			(at 0 0 0)
			(layer "B.SilkS")
			(hide yes)
			(effects
				(font
					(size 1.27 1.27)
				)
				(justify mirror)
			)
		)
		(property "Value" "SC100P50V2JN-3GP"
			(at -1.1811 -2.7051 180)
			(unlocked yes)
			(layer "B.Fab")
			(hide yes)
			(effects
				(font
					(size 1.016 1.016)
					(thickness 0.1524)
				)
				(justify mirror)
			)
		)
		(property "Device Type" "C402H22"
			(at -1.1811 -4.2291 180)
			(unlocked yes)
			(layer "B.Fab")
			(hide yes)
			(effects
				(font
					(size 1.016 1.016)
					(thickness 0.1524)
				)
				(justify mirror)
			)
		)
		(duplicate_pad_numbers_are_jumpers no)
		(fp_rect
			(start 0.4318 0.9525)
			(end -0.4318 -0.9525)
			(stroke
				(width 0)
				(type default)
			)
			(fill no)
			(layer "B.CrtYd")
		)
		(fp_rect
			(start 0.4318 0.9525)
			(end -0.4318 -0.9525)
			(stroke
				(width 0)
				(type default)
			)
			(fill no)
			(layer "B.Fab")
		)
		(pad "1" smd custom
			(at 0 -0.4445)
			(size 0.1524 0.1524)
			(layers "B.Cu" "B.Mask" "B.Paste")
			(net "MPLLAV33")
			(options
				(clearance outline)
				(anchor circle)
			)
			(primitives
				(gr_poly
					(pts
						(arc
							(start 0.3048 0.2032)
							(mid 0.275042 0.275042)
							(end 0.2032 0.3048)
						)
						(arc
							(start -0.2032 0.3048)
							(mid -0.275042 0.275042)
							(end -0.3048 0.2032)
						)
						(arc
							(start -0.3048 -0.2032)
							(mid -0.275042 -0.275042)
							(end -0.2032 -0.3048)
						)
						(arc
							(start 0.2032 -0.3048)
							(mid 0.275042 -0.275042)
							(end 0.3048 -0.2032)
						)
					)
					(width 0)
					(fill yes)
				)
			)
		)
		(pad "2" smd custom
			(at 0 0.4445)
			(size 0.1524 0.1524)
			(layers "B.Cu" "B.Mask" "B.Paste")
			(net "GND")
			(options
				(clearance outline)
				(anchor circle)
			)
			(primitives
				(gr_poly
					(pts
						(arc
							(start 0.3048 0.2032)
							(mid 0.275042 0.275042)
							(end 0.2032 0.3048)
						)
						(arc
							(start -0.2032 0.3048)
							(mid -0.275042 0.275042)
							(end -0.3048 0.2032)
						)
						(arc
							(start -0.3048 -0.2032)
							(mid -0.275042 -0.275042)
							(end -0.2032 -0.3048)
						)
						(arc
							(start 0.2032 -0.3048)
							(mid 0.275042 -0.275042)
							(end 0.3048 -0.2032)
						)
					)
					(width 0)
					(fill yes)
				)
			)
		)
	)
	(footprint ""
		(layer "B.Cu")
		(at 87.8586 -146.0246 90)
		(property "Reference" "R424"
			(at 0 0 90)
			(layer "B.SilkS")
			(hide yes)
			(effects
				(font
					(size 1.27 1.27)
				)
				(justify mirror)
			)
		)
		(property "Value" "4K7R2F-GP"
			(at -0.064008 -3.993896 90)
			(unlocked yes)
			(layer "B.Fab")
			(hide yes)
			(effects
				(font
					(size 1.016 1.016)
					(thickness 0.1524)
				)
				(justify mirror)
			)
		)
		(property "Device Type" "R402H16"
			(at -0.064008 -5.517896 90)
			(unlocked yes)
			(layer "B.Fab")
			(hide yes)
			(effects
				(font
					(size 1.016 1.016)
					(thickness 0.1524)
				)
				(justify mirror)
			)
		)
		(duplicate_pad_numbers_are_jumpers no)
		(fp_line
			(start 0.508 -0.9398)
			(end 0.508 0.9398)
			(stroke
				(width 0.1524)
				(type default)
			)
			(layer "B.SilkS")
		)
		(fp_line
			(start -0.508 -0.9398)
			(end 0.508 -0.9398)
			(stroke
				(width 0.1524)
				(type default)
			)
			(layer "B.SilkS")
		)
		(fp_rect
			(start 0.508 0.9398)
			(end -0.508 -0.9398)
			(stroke
				(width 0)
				(type default)
			)
			(fill no)
			(layer "B.CrtYd")
		)
		(fp_rect
			(start 0.508 0.9398)
			(end -0.508 -0.9398)
			(stroke
				(width 0)
				(type default)
			)
			(fill no)
			(layer "B.Fab")
		)
		(pad "1" smd custom
			(at 0 -0.4445 270)
			(size 0.1397 0.1397)
			(layers "B.Cu" "B.Mask" "B.Paste")
			(net "P3V3_STBY")
			(options
				(clearance outline)
				(anchor circle)
			)
			(primitives
				(gr_poly
					(pts
						(arc
							(start -0.1778 0.2794)
							(mid -0.249642 0.249642)
							(end -0.2794 0.1778)
						)
						(arc
							(start -0.2794 -0.1778)
							(mid -0.249642 -0.249642)
							(end -0.1778 -0.2794)
						)
						(arc
							(start 0.1778 -0.2794)
							(mid 0.249642 -0.249642)
							(end 0.2794 -0.1778)
						)
						(arc
							(start 0.2794 0.1778)
							(mid 0.249642 0.249642)
							(end 0.1778 0.2794)
						)
					)
					(width 0)
					(fill yes)
				)
			)
		)
		(pad "2" smd custom
			(at 0 0.4445 270)
			(size 0.1397 0.1397)
			(layers "B.Cu" "B.Mask" "B.Paste")
			(net "TCA9555_A1")
			(options
				(clearance outline)
				(anchor circle)
			)
			(primitives
				(gr_poly
					(pts
						(arc
							(start -0.1778 0.2794)
							(mid -0.249642 0.249642)
							(end -0.2794 0.1778)
						)
						(arc
							(start -0.2794 -0.1778)
							(mid -0.249642 -0.249642)
							(end -0.1778 -0.2794)
						)
						(arc
							(start 0.1778 -0.2794)
							(mid 0.249642 -0.249642)
							(end 0.2794 -0.1778)
						)
						(arc
							(start 0.2794 0.1778)
							(mid 0.249642 0.249642)
							(end 0.1778 0.2794)
						)
					)
					(width 0)
					(fill yes)
				)
			)
		)
	)
	(footprint ""
		(layer "B.Cu")
		(at 37.228018 -143.050514)
		(property "Reference" "C59"
			(at 0 0 0)
			(layer "B.SilkS")
			(hide yes)
			(effects
				(font
					(size 1.27 1.27)
				)
				(justify mirror)
			)
		)
		(property "Value" "SC1U16V3KX-5GP"
			(at 0 -2.8194 0)
			(unlocked yes)
			(layer "B.Fab")
			(hide yes)
			(effects
				(font
					(size 1.016 1.016)
					(thickness 0.1524)
				)
				(justify mirror)
			)
		)
		(property "Device Type" "C603H36"
			(at 0 -4.3434 0)
			(unlocked yes)
			(layer "B.Fab")
			(hide yes)
			(effects
				(font
					(size 1.016 1.016)
					(thickness 0.1524)
				)
				(justify mirror)
			)
		)
		(duplicate_pad_numbers_are_jumpers no)
		(fp_line
			(start -0.508 0)
			(end 0.508 0)
			(stroke
				(width 0.2032)
				(type default)
			)
			(layer "B.SilkS")
		)
		(fp_rect
			(start 0.5842 1.3335)
			(end -0.5842 -1.3335)
			(stroke
				(width 0)
				(type default)
			)
			(fill no)
			(layer "B.CrtYd")
		)
		(fp_rect
			(start 0.5842 1.3335)
			(end -0.5842 -1.3335)
			(stroke
				(width 0)
				(type default)
			)
			(fill no)
			(layer "B.Fab")
		)
		(pad "1" smd custom
			(at 0 -0.762 180)
			(size 0.2159 0.2159)
			(layers "B.Cu" "B.Mask" "B.Paste")
			(net "P1V2_STBY")
			(options
				(clearance outline)
				(anchor circle)
			)
			(primitives
				(gr_poly
					(pts
						(arc
							(start -0.3302 0.4318)
							(mid -0.402042 0.402042)
							(end -0.4318 0.3302)
						)
						(arc
							(start -0.4318 -0.3302)
							(mid -0.402042 -0.402042)
							(end -0.3302 -0.4318)
						)
						(arc
							(start 0.3302 -0.4318)
							(mid 0.402042 -0.402042)
							(end 0.4318 -0.3302)
						)
						(arc
							(start 0.4318 0.3302)
							(mid 0.402042 0.402042)
							(end 0.3302 0.4318)
						)
					)
					(width 0)
					(fill yes)
				)
			)
		)
		(pad "2" smd custom
			(at 0 0.762 180)
			(size 0.2159 0.2159)
			(layers "B.Cu" "B.Mask" "B.Paste")
			(net "GND")
			(options
				(clearance outline)
				(anchor circle)
			)
			(primitives
				(gr_poly
					(pts
						(arc
							(start -0.3302 0.4318)
							(mid -0.402042 0.402042)
							(end -0.4318 0.3302)
						)
						(arc
							(start -0.4318 -0.3302)
							(mid -0.402042 -0.402042)
							(end -0.3302 -0.4318)
						)
						(arc
							(start 0.3302 -0.4318)
							(mid 0.402042 -0.402042)
							(end 0.4318 -0.3302)
						)
						(arc
							(start 0.4318 0.3302)
							(mid 0.402042 0.402042)
							(end 0.3302 0.4318)
						)
					)
					(width 0)
					(fill yes)
				)
			)
		)
	)
	(footprint ""
		(layer "B.Cu")
		(at 57.365392 -147.743164 90)
		(property "Reference" "R365"
			(at 0 0 90)
			(layer "B.SilkS")
			(hide yes)
			(effects
				(font
					(size 1.27 1.27)
				)
				(justify mirror)
			)
		)
		(property "Value" "4K7R2F-GP"
			(at -0.064008 -3.993896 90)
			(unlocked yes)
			(layer "B.Fab")
			(hide yes)
			(effects
				(font
					(size 1.016 1.016)
					(thickness 0.1524)
				)
				(justify mirror)
			)
		)
		(property "Device Type" "R402H16"
			(at -0.064008 -5.517896 90)
			(unlocked yes)
			(layer "B.Fab")
			(hide yes)
			(effects
				(font
					(size 1.016 1.016)
					(thickness 0.1524)
				)
				(justify mirror)
			)
		)
		(duplicate_pad_numbers_are_jumpers no)
		(fp_line
			(start 0.508 -0.9398)
			(end 0.508 0.9398)
			(stroke
				(width 0.1524)
				(type default)
			)
			(layer "B.SilkS")
		)
		(fp_line
			(start -0.508 -0.9398)
			(end 0.508 -0.9398)
			(stroke
				(width 0.1524)
				(type default)
			)
			(layer "B.SilkS")
		)
		(fp_rect
			(start 0.508 0.9398)
			(end -0.508 -0.9398)
			(stroke
				(width 0)
				(type default)
			)
			(fill no)
			(layer "B.CrtYd")
		)
		(fp_rect
			(start 0.508 0.9398)
			(end -0.508 -0.9398)
			(stroke
				(width 0)
				(type default)
			)
			(fill no)
			(layer "B.Fab")
		)
		(pad "1" smd custom
			(at 0 -0.4445 270)
			(size 0.1397 0.1397)
			(layers "B.Cu" "B.Mask" "B.Paste")
			(net "BMC0_JTAG_RTCK")
			(options
				(clearance outline)
				(anchor circle)
			)
			(primitives
				(gr_poly
					(pts
						(arc
							(start -0.1778 0.2794)
							(mid -0.249642 0.249642)
							(end -0.2794 0.1778)
						)
						(arc
							(start -0.2794 -0.1778)
							(mid -0.249642 -0.249642)
							(end -0.1778 -0.2794)
						)
						(arc
							(start 0.1778 -0.2794)
							(mid 0.249642 -0.249642)
							(end 0.2794 -0.1778)
						)
						(arc
							(start 0.2794 0.1778)
							(mid 0.249642 0.249642)
							(end 0.1778 0.2794)
						)
					)
					(width 0)
					(fill yes)
				)
			)
		)
		(pad "2" smd custom
			(at 0 0.4445 270)
			(size 0.1397 0.1397)
			(layers "B.Cu" "B.Mask" "B.Paste")
			(net "GND")
			(options
				(clearance outline)
				(anchor circle)
			)
			(primitives
				(gr_poly
					(pts
						(arc
							(start -0.1778 0.2794)
							(mid -0.249642 0.249642)
							(end -0.2794 0.1778)
						)
						(arc
							(start -0.2794 -0.1778)
							(mid -0.249642 -0.249642)
							(end -0.1778 -0.2794)
						)
						(arc
							(start 0.1778 -0.2794)
							(mid 0.249642 -0.249642)
							(end 0.2794 -0.1778)
						)
						(arc
							(start 0.2794 0.1778)
							(mid 0.249642 0.249642)
							(end 0.1778 0.2794)
						)
					)
					(width 0)
					(fill yes)
				)
			)
		)
	)
	(footprint ""
		(layer "B.Cu")
		(at 20.37715 -140.808202 -90)
		(property "Reference" "R206"
			(at 0 0 90)
			(layer "B.SilkS")
			(hide yes)
			(effects
				(font
					(size 1.27 1.27)
				)
				(justify mirror)
			)
		)
		(property "Value" "60D4R2F-GP"
			(at -0.064008 -3.993896 270)
			(unlocked yes)
			(layer "B.Fab")
			(hide yes)
			(effects
				(font
					(size 1.016 1.016)
					(thickness 0.1524)
				)
				(justify mirror)
			)
		)
		(property "Device Type" "R402H16"
			(at -0.064008 -5.517896 270)
			(unlocked yes)
			(layer "B.Fab")
			(hide yes)
			(effects
				(font
					(size 1.016 1.016)
					(thickness 0.1524)
				)
				(justify mirror)
			)
		)
		(duplicate_pad_numbers_are_jumpers no)
		(fp_line
			(start -0.508 -0.9398)
			(end 0.508 -0.9398)
			(stroke
				(width 0.1524)
				(type default)
			)
			(layer "B.SilkS")
		)
		(fp_line
			(start 0.508 -0.9398)
			(end 0.508 0.9398)
			(stroke
				(width 0.1524)
				(type default)
			)
			(layer "B.SilkS")
		)
		(fp_rect
			(start 0.508 0.9398)
			(end -0.508 -0.9398)
			(stroke
				(width 0)
				(type default)
			)
			(fill no)
			(layer "B.CrtYd")
		)
		(fp_rect
			(start 0.508 0.9398)
			(end -0.508 -0.9398)
			(stroke
				(width 0)
				(type default)
			)
			(fill no)
			(layer "B.Fab")
		)
		(pad "1" smd custom
			(at 0 -0.4445 90)
			(size 0.1397 0.1397)
			(layers "B.Cu" "B.Mask" "B.Paste")
			(net "MEMCK_N")
			(options
				(clearance outline)
				(anchor circle)
			)
			(primitives
				(gr_poly
					(pts
						(arc
							(start -0.1778 0.2794)
							(mid -0.249642 0.249642)
							(end -0.2794 0.1778)
						)
						(arc
							(start -0.2794 -0.1778)
							(mid -0.249642 -0.249642)
							(end -0.1778 -0.2794)
						)
						(arc
							(start 0.1778 -0.2794)
							(mid 0.249642 -0.249642)
							(end 0.2794 -0.1778)
						)
						(arc
							(start 0.2794 0.1778)
							(mid 0.249642 0.249642)
							(end 0.1778 0.2794)
						)
					)
					(width 0)
					(fill yes)
				)
			)
		)
		(pad "2" smd custom
			(at 0 0.4445 90)
			(size 0.1397 0.1397)
			(layers "B.Cu" "B.Mask" "B.Paste")
			(net "MEMCK_TER")
			(options
				(clearance outline)
				(anchor circle)
			)
			(primitives
				(gr_poly
					(pts
						(arc
							(start -0.1778 0.2794)
							(mid -0.249642 0.249642)
							(end -0.2794 0.1778)
						)
						(arc
							(start -0.2794 -0.1778)
							(mid -0.249642 -0.249642)
							(end -0.1778 -0.2794)
						)
						(arc
							(start 0.1778 -0.2794)
							(mid 0.249642 -0.249642)
							(end 0.2794 -0.1778)
						)
						(arc
							(start 0.2794 0.1778)
							(mid 0.249642 0.249642)
							(end 0.1778 0.2794)
						)
					)
					(width 0)
					(fill yes)
				)
			)
		)
	)
	(footprint ""
		(layer "B.Cu")
		(at 83.7692 -98.494596 -90)
		(property "Reference" "R64"
			(at 0 0 90)
			(layer "B.SilkS")
			(hide yes)
			(effects
				(font
					(size 1.27 1.27)
				)
				(justify mirror)
			)
		)
		(property "Value" "10KR2F-2-GP"
			(at -0.064008 -3.993896 270)
			(unlocked yes)
			(layer "B.Fab")
			(hide yes)
			(effects
				(font
					(size 1.016 1.016)
					(thickness 0.1524)
				)
				(justify mirror)
			)
		)
		(property "Device Type" "R402H16"
			(at -0.064008 -5.517896 270)
			(unlocked yes)
			(layer "B.Fab")
			(hide yes)
			(effects
				(font
					(size 1.016 1.016)
					(thickness 0.1524)
				)
				(justify mirror)
			)
		)
		(duplicate_pad_numbers_are_jumpers no)
		(fp_line
			(start -0.508 -0.9398)
			(end 0.508 -0.9398)
			(stroke
				(width 0.1524)
				(type default)
			)
			(layer "B.SilkS")
		)
		(fp_line
			(start 0.508 -0.9398)
			(end 0.508 0.9398)
			(stroke
				(width 0.1524)
				(type default)
			)
			(layer "B.SilkS")
		)
		(fp_rect
			(start 0.508 0.9398)
			(end -0.508 -0.9398)
			(stroke
				(width 0)
				(type default)
			)
			(fill no)
			(layer "B.CrtYd")
		)
		(fp_rect
			(start 0.508 0.9398)
			(end -0.508 -0.9398)
			(stroke
				(width 0)
				(type default)
			)
			(fill no)
			(layer "B.Fab")
		)
		(pad "1" smd custom
			(at 0 -0.4445 90)
			(size 0.1397 0.1397)
			(layers "B.Cu" "B.Mask" "B.Paste")
			(net "P3V3_STBY")
			(options
				(clearance outline)
				(anchor circle)
			)
			(primitives
				(gr_poly
					(pts
						(arc
							(start -0.1778 0.2794)
							(mid -0.249642 0.249642)
							(end -0.2794 0.1778)
						)
						(arc
							(start -0.2794 -0.1778)
							(mid -0.249642 -0.249642)
							(end -0.1778 -0.2794)
						)
						(arc
							(start 0.1778 -0.2794)
							(mid 0.249642 -0.249642)
							(end 0.2794 -0.1778)
						)
						(arc
							(start 0.2794 0.1778)
							(mid 0.249642 0.249642)
							(end 0.1778 0.2794)
						)
					)
					(width 0)
					(fill yes)
				)
			)
		)
		(pad "2" smd custom
			(at 0 0.4445 90)
			(size 0.1397 0.1397)
			(layers "B.Cu" "B.Mask" "B.Paste")
			(net "MEZZ_A_PRSNT_120_N")
			(options
				(clearance outline)
				(anchor circle)
			)
			(primitives
				(gr_poly
					(pts
						(arc
							(start -0.1778 0.2794)
							(mid -0.249642 0.249642)
							(end -0.2794 0.1778)
						)
						(arc
							(start -0.2794 -0.1778)
							(mid -0.249642 -0.249642)
							(end -0.1778 -0.2794)
						)
						(arc
							(start 0.1778 -0.2794)
							(mid 0.249642 -0.249642)
							(end 0.2794 -0.1778)
						)
						(arc
							(start 0.2794 0.1778)
							(mid 0.249642 0.249642)
							(end 0.1778 0.2794)
						)
					)
					(width 0)
					(fill yes)
				)
			)
		)
	)
	(footprint ""
		(layer "B.Cu")
		(at 82.87639 -143.814292 -90)
		(property "Reference" "R127"
			(at 0 0 90)
			(layer "B.SilkS")
			(hide yes)
			(effects
				(font
					(size 1.27 1.27)
				)
				(justify mirror)
			)
		)
		(property "Value" "0R2J-2-GP"
			(at -0.064008 -3.993896 270)
			(unlocked yes)
			(layer "B.Fab")
			(hide yes)
			(effects
				(font
					(size 1.016 1.016)
					(thickness 0.1524)
				)
				(justify mirror)
			)
		)
		(property "Device Type" "R402H16"
			(at -0.064008 -5.517896 270)
			(unlocked yes)
			(layer "B.Fab")
			(hide yes)
			(effects
				(font
					(size 1.016 1.016)
					(thickness 0.1524)
				)
				(justify mirror)
			)
		)
		(duplicate_pad_numbers_are_jumpers no)
		(fp_line
			(start -0.508 -0.9398)
			(end 0.508 -0.9398)
			(stroke
				(width 0.1524)
				(type default)
			)
			(layer "B.SilkS")
		)
		(fp_line
			(start 0.508 -0.9398)
			(end 0.508 0.9398)
			(stroke
				(width 0.1524)
				(type default)
			)
			(layer "B.SilkS")
		)
		(fp_rect
			(start 0.508 0.9398)
			(end -0.508 -0.9398)
			(stroke
				(width 0)
				(type default)
			)
			(fill no)
			(layer "B.CrtYd")
		)
		(fp_rect
			(start 0.508 0.9398)
			(end -0.508 -0.9398)
			(stroke
				(width 0)
				(type default)
			)
			(fill no)
			(layer "B.Fab")
		)
		(pad "1" smd custom
			(at 0 -0.4445 90)
			(size 0.1397 0.1397)
			(layers "B.Cu" "B.Mask" "B.Paste")
			(net "I2C_EXP_LOC_SCL")
			(options
				(clearance outline)
				(anchor circle)
			)
			(primitives
				(gr_poly
					(pts
						(arc
							(start -0.1778 0.2794)
							(mid -0.249642 0.249642)
							(end -0.2794 0.1778)
						)
						(arc
							(start -0.2794 -0.1778)
							(mid -0.249642 -0.249642)
							(end -0.1778 -0.2794)
						)
						(arc
							(start 0.1778 -0.2794)
							(mid 0.249642 -0.249642)
							(end 0.2794 -0.1778)
						)
						(arc
							(start 0.2794 0.1778)
							(mid 0.249642 0.249642)
							(end 0.1778 0.2794)
						)
					)
					(width 0)
					(fill yes)
				)
			)
		)
		(pad "2" smd custom
			(at 0 0.4445 90)
			(size 0.1397 0.1397)
			(layers "B.Cu" "B.Mask" "B.Paste")
			(net "I2C_EXP_LOC_SCL_R")
			(options
				(clearance outline)
				(anchor circle)
			)
			(primitives
				(gr_poly
					(pts
						(arc
							(start -0.1778 0.2794)
							(mid -0.249642 0.249642)
							(end -0.2794 0.1778)
						)
						(arc
							(start -0.2794 -0.1778)
							(mid -0.249642 -0.249642)
							(end -0.1778 -0.2794)
						)
						(arc
							(start 0.1778 -0.2794)
							(mid 0.249642 -0.249642)
							(end 0.2794 -0.1778)
						)
						(arc
							(start 0.2794 0.1778)
							(mid 0.249642 0.249642)
							(end 0.1778 0.2794)
						)
					)
					(width 0)
					(fill yes)
				)
			)
		)
	)
	(footprint ""
		(layer "B.Cu")
		(at 33.9344 -152.0952 180)
		(property "Reference" "C93"
			(at 0 0 0)
			(layer "B.SilkS")
			(hide yes)
			(effects
				(font
					(size 1.27 1.27)
				)
				(justify mirror)
			)
		)
		(property "Value" "SCD1U16V2KX-3GP"
			(at -1.1811 -2.7051 180)
			(unlocked yes)
			(layer "B.Fab")
			(hide yes)
			(effects
				(font
					(size 1.016 1.016)
					(thickness 0.1524)
				)
				(justify mirror)
			)
		)
		(property "Device Type" "C402H22"
			(at -1.1811 -4.2291 180)
			(unlocked yes)
			(layer "B.Fab")
			(hide yes)
			(effects
				(font
					(size 1.016 1.016)
					(thickness 0.1524)
				)
				(justify mirror)
			)
		)
		(duplicate_pad_numbers_are_jumpers no)
		(fp_rect
			(start 0.4318 0.9525)
			(end -0.4318 -0.9525)
			(stroke
				(width 0)
				(type default)
			)
			(fill no)
			(layer "B.CrtYd")
		)
		(fp_rect
			(start 0.4318 0.9525)
			(end -0.4318 -0.9525)
			(stroke
				(width 0)
				(type default)
			)
			(fill no)
			(layer "B.Fab")
		)
		(pad "1" smd custom
			(at 0 -0.4445)
			(size 0.1524 0.1524)
			(layers "B.Cu" "B.Mask" "B.Paste")
			(net "MPLLAV33")
			(options
				(clearance outline)
				(anchor circle)
			)
			(primitives
				(gr_poly
					(pts
						(arc
							(start 0.3048 0.2032)
							(mid 0.275042 0.275042)
							(end 0.2032 0.3048)
						)
						(arc
							(start -0.2032 0.3048)
							(mid -0.275042 0.275042)
							(end -0.3048 0.2032)
						)
						(arc
							(start -0.3048 -0.2032)
							(mid -0.275042 -0.275042)
							(end -0.2032 -0.3048)
						)
						(arc
							(start 0.2032 -0.3048)
							(mid 0.275042 -0.275042)
							(end 0.3048 -0.2032)
						)
					)
					(width 0)
					(fill yes)
				)
			)
		)
		(pad "2" smd custom
			(at 0 0.4445)
			(size 0.1524 0.1524)
			(layers "B.Cu" "B.Mask" "B.Paste")
			(net "GND")
			(options
				(clearance outline)
				(anchor circle)
			)
			(primitives
				(gr_poly
					(pts
						(arc
							(start 0.3048 0.2032)
							(mid 0.275042 0.275042)
							(end 0.2032 0.3048)
						)
						(arc
							(start -0.2032 0.3048)
							(mid -0.275042 0.275042)
							(end -0.3048 0.2032)
						)
						(arc
							(start -0.3048 -0.2032)
							(mid -0.275042 -0.275042)
							(end -0.2032 -0.3048)
						)
						(arc
							(start 0.2032 -0.3048)
							(mid 0.275042 -0.275042)
							(end 0.3048 -0.2032)
						)
					)
					(width 0)
					(fill yes)
				)
			)
		)
	)
	(footprint ""
		(layer "B.Cu")
		(at 67.818 -149.479 90)
		(property "Reference" "R386"
			(at 0 0 90)
			(layer "B.SilkS")
			(hide yes)
			(effects
				(font
					(size 1.27 1.27)
				)
				(justify mirror)
			)
		)
		(property "Value" "4K7R2F-GP"
			(at -0.064008 -3.993896 90)
			(unlocked yes)
			(layer "B.Fab")
			(hide yes)
			(effects
				(font
					(size 1.016 1.016)
					(thickness 0.1524)
				)
				(justify mirror)
			)
		)
		(property "Device Type" "R402H16"
			(at -0.064008 -5.517896 90)
			(unlocked yes)
			(layer "B.Fab")
			(hide yes)
			(effects
				(font
					(size 1.016 1.016)
					(thickness 0.1524)
				)
				(justify mirror)
			)
		)
		(duplicate_pad_numbers_are_jumpers no)
		(fp_line
			(start 0.508 -0.9398)
			(end 0.508 0.9398)
			(stroke
				(width 0.1524)
				(type default)
			)
			(layer "B.SilkS")
		)
		(fp_line
			(start -0.508 -0.9398)
			(end 0.508 -0.9398)
			(stroke
				(width 0.1524)
				(type default)
			)
			(layer "B.SilkS")
		)
		(fp_rect
			(start 0.508 0.9398)
			(end -0.508 -0.9398)
			(stroke
				(width 0)
				(type default)
			)
			(fill no)
			(layer "B.CrtYd")
		)
		(fp_rect
			(start 0.508 0.9398)
			(end -0.508 -0.9398)
			(stroke
				(width 0)
				(type default)
			)
			(fill no)
			(layer "B.Fab")
		)
		(pad "1" smd custom
			(at 0 -0.4445 270)
			(size 0.1397 0.1397)
			(layers "B.Cu" "B.Mask" "B.Paste")
			(net "GND")
			(options
				(clearance outline)
				(anchor circle)
			)
			(primitives
				(gr_poly
					(pts
						(arc
							(start -0.1778 0.2794)
							(mid -0.249642 0.249642)
							(end -0.2794 0.1778)
						)
						(arc
							(start -0.2794 -0.1778)
							(mid -0.249642 -0.249642)
							(end -0.1778 -0.2794)
						)
						(arc
							(start 0.1778 -0.2794)
							(mid 0.249642 -0.249642)
							(end 0.2794 -0.1778)
						)
						(arc
							(start 0.2794 0.1778)
							(mid 0.249642 0.249642)
							(end 0.1778 0.2794)
						)
					)
					(width 0)
					(fill yes)
				)
			)
		)
		(pad "2" smd custom
			(at 0 0.4445 270)
			(size 0.1397 0.1397)
			(layers "B.Cu" "B.Mask" "B.Paste")
			(net "NCSI_TXD0")
			(options
				(clearance outline)
				(anchor circle)
			)
			(primitives
				(gr_poly
					(pts
						(arc
							(start -0.1778 0.2794)
							(mid -0.249642 0.249642)
							(end -0.2794 0.1778)
						)
						(arc
							(start -0.2794 -0.1778)
							(mid -0.249642 -0.249642)
							(end -0.1778 -0.2794)
						)
						(arc
							(start 0.1778 -0.2794)
							(mid 0.249642 -0.249642)
							(end 0.2794 -0.1778)
						)
						(arc
							(start 0.2794 0.1778)
							(mid 0.249642 0.249642)
							(end 0.1778 0.2794)
						)
					)
					(width 0)
					(fill yes)
				)
			)
		)
	)
	(footprint ""
		(layer "B.Cu")
		(at 57.0738 -150.6728 -90)
		(property "Reference" "R388"
			(at 0 0 90)
			(layer "B.SilkS")
			(hide yes)
			(effects
				(font
					(size 1.27 1.27)
				)
				(justify mirror)
			)
		)
		(property "Value" "4K7R2F-GP"
			(at -0.064008 -3.993896 270)
			(unlocked yes)
			(layer "B.Fab")
			(hide yes)
			(effects
				(font
					(size 1.016 1.016)
					(thickness 0.1524)
				)
				(justify mirror)
			)
		)
		(property "Device Type" "R402H16"
			(at -0.064008 -5.517896 270)
			(unlocked yes)
			(layer "B.Fab")
			(hide yes)
			(effects
				(font
					(size 1.016 1.016)
					(thickness 0.1524)
				)
				(justify mirror)
			)
		)
		(duplicate_pad_numbers_are_jumpers no)
		(fp_line
			(start -0.508 -0.9398)
			(end 0.508 -0.9398)
			(stroke
				(width 0.1524)
				(type default)
			)
			(layer "B.SilkS")
		)
		(fp_line
			(start 0.508 -0.9398)
			(end 0.508 0.9398)
			(stroke
				(width 0.1524)
				(type default)
			)
			(layer "B.SilkS")
		)
		(fp_rect
			(start 0.508 0.9398)
			(end -0.508 -0.9398)
			(stroke
				(width 0)
				(type default)
			)
			(fill no)
			(layer "B.CrtYd")
		)
		(fp_rect
			(start 0.508 0.9398)
			(end -0.508 -0.9398)
			(stroke
				(width 0)
				(type default)
			)
			(fill no)
			(layer "B.Fab")
		)
		(pad "1" smd custom
			(at 0 -0.4445 90)
			(size 0.1397 0.1397)
			(layers "B.Cu" "B.Mask" "B.Paste")
			(net "GND")
			(options
				(clearance outline)
				(anchor circle)
			)
			(primitives
				(gr_poly
					(pts
						(arc
							(start -0.1778 0.2794)
							(mid -0.249642 0.249642)
							(end -0.2794 0.1778)
						)
						(arc
							(start -0.2794 -0.1778)
							(mid -0.249642 -0.249642)
							(end -0.1778 -0.2794)
						)
						(arc
							(start 0.1778 -0.2794)
							(mid 0.249642 -0.249642)
							(end 0.2794 -0.1778)
						)
						(arc
							(start 0.2794 0.1778)
							(mid 0.249642 0.249642)
							(end 0.1778 0.2794)
						)
					)
					(width 0)
					(fill yes)
				)
			)
		)
		(pad "2" smd custom
			(at 0 0.4445 90)
			(size 0.1397 0.1397)
			(layers "B.Cu" "B.Mask" "B.Paste")
			(net "MAC1_TXD2")
			(options
				(clearance outline)
				(anchor circle)
			)
			(primitives
				(gr_poly
					(pts
						(arc
							(start -0.1778 0.2794)
							(mid -0.249642 0.249642)
							(end -0.2794 0.1778)
						)
						(arc
							(start -0.2794 -0.1778)
							(mid -0.249642 -0.249642)
							(end -0.1778 -0.2794)
						)
						(arc
							(start 0.1778 -0.2794)
							(mid 0.249642 -0.249642)
							(end 0.2794 -0.1778)
						)
						(arc
							(start 0.2794 0.1778)
							(mid 0.249642 0.249642)
							(end 0.1778 0.2794)
						)
					)
					(width 0)
					(fill yes)
				)
			)
		)
	)
	(footprint ""
		(layer "B.Cu")
		(at 42.931334 -154.997912 -90)
		(property "Reference" "TP66"
			(at 0 0 90)
			(layer "B.SilkS")
			(hide yes)
			(effects
				(font
					(size 1.27 1.27)
				)
				(justify mirror)
			)
		)
		(property "Value" "TPAD28-2-GP"
			(at 0.0127 -1.6637 270)
			(unlocked yes)
			(layer "B.Fab")
			(hide yes)
			(effects
				(font
					(size 1.016 1.016)
					(thickness 0.1524)
				)
				(justify mirror)
			)
		)
		(property "Device Type" "TPAD28"
			(at 0.0127 -3.1877 270)
			(unlocked yes)
			(layer "B.Fab")
			(hide yes)
			(effects
				(font
					(size 1.016 1.016)
					(thickness 0.1524)
				)
				(justify mirror)
			)
		)
		(duplicate_pad_numbers_are_jumpers no)
		(fp_poly
			(pts
				(arc
					(start 0 -0.3556)
					(mid 0 0.3556)
					(end 0 -0.3556)
				)
			)
			(stroke
				(width 0)
				(type default)
			)
			(fill no)
			(layer "B.CrtYd")
		)
		(fp_poly
			(pts
				(arc
					(start 0 -0.6096)
					(mid 0 0.6096)
					(end 0 -0.6096)
				)
			)
			(stroke
				(width 0)
				(type default)
			)
			(fill no)
			(layer "B.Fab")
		)
		(pad "1" smd circle
			(at 0 0 90)
			(size 0.7112 0.7112)
			(layers "B.Cu" "B.Mask" "B.Paste")
			(net "TP_BMC_GPION7")
		)
	)
	(footprint ""
		(layer "B.Cu")
		(at 82.919824 -145.101818 -90)
		(property "Reference" "R720"
			(at 0 0 90)
			(layer "B.SilkS")
			(hide yes)
			(effects
				(font
					(size 1.27 1.27)
				)
				(justify mirror)
			)
		)
		(property "Value" "0R2J-2-GP"
			(at -0.064008 -3.993896 270)
			(unlocked yes)
			(layer "B.Fab")
			(hide yes)
			(effects
				(font
					(size 1.016 1.016)
					(thickness 0.1524)
				)
				(justify mirror)
			)
		)
		(property "Device Type" "R402H16"
			(at -0.064008 -5.517896 270)
			(unlocked yes)
			(layer "B.Fab")
			(hide yes)
			(effects
				(font
					(size 1.016 1.016)
					(thickness 0.1524)
				)
				(justify mirror)
			)
		)
		(duplicate_pad_numbers_are_jumpers no)
		(fp_line
			(start -0.508 -0.9398)
			(end 0.508 -0.9398)
			(stroke
				(width 0.1524)
				(type default)
			)
			(layer "B.SilkS")
		)
		(fp_line
			(start 0.508 -0.9398)
			(end 0.508 0.9398)
			(stroke
				(width 0.1524)
				(type default)
			)
			(layer "B.SilkS")
		)
		(fp_rect
			(start 0.508 0.9398)
			(end -0.508 -0.9398)
			(stroke
				(width 0)
				(type default)
			)
			(fill no)
			(layer "B.CrtYd")
		)
		(fp_rect
			(start 0.508 0.9398)
			(end -0.508 -0.9398)
			(stroke
				(width 0)
				(type default)
			)
			(fill no)
			(layer "B.Fab")
		)
		(pad "1" smd custom
			(at 0 -0.4445 90)
			(size 0.1397 0.1397)
			(layers "B.Cu" "B.Mask" "B.Paste")
			(net "PWRGD_P3V3_STBY_N")
			(options
				(clearance outline)
				(anchor circle)
			)
			(primitives
				(gr_poly
					(pts
						(arc
							(start -0.1778 0.2794)
							(mid -0.249642 0.249642)
							(end -0.2794 0.1778)
						)
						(arc
							(start -0.2794 -0.1778)
							(mid -0.249642 -0.249642)
							(end -0.1778 -0.2794)
						)
						(arc
							(start 0.1778 -0.2794)
							(mid 0.249642 -0.249642)
							(end 0.2794 -0.1778)
						)
						(arc
							(start 0.2794 0.1778)
							(mid 0.249642 0.249642)
							(end 0.1778 0.2794)
						)
					)
					(width 0)
					(fill yes)
				)
			)
		)
		(pad "2" smd custom
			(at 0 0.4445 90)
			(size 0.1397 0.1397)
			(layers "B.Cu" "B.Mask" "B.Paste")
			(net "PWRGD_P3V3_STBY_N_R1")
			(options
				(clearance outline)
				(anchor circle)
			)
			(primitives
				(gr_poly
					(pts
						(arc
							(start -0.1778 0.2794)
							(mid -0.249642 0.249642)
							(end -0.2794 0.1778)
						)
						(arc
							(start -0.2794 -0.1778)
							(mid -0.249642 -0.249642)
							(end -0.1778 -0.2794)
						)
						(arc
							(start 0.1778 -0.2794)
							(mid 0.249642 -0.249642)
							(end 0.2794 -0.1778)
						)
						(arc
							(start 0.2794 0.1778)
							(mid 0.249642 0.249642)
							(end 0.1778 0.2794)
						)
					)
					(width 0)
					(fill yes)
				)
			)
		)
	)
	(footprint ""
		(layer "B.Cu")
		(at 53.975 -154.9908 180)
		(property "Reference" "R315"
			(at 0 0 0)
			(layer "B.SilkS")
			(hide yes)
			(effects
				(font
					(size 1.27 1.27)
				)
				(justify mirror)
			)
		)
		(property "Value" "10KR2F-2-GP"
			(at -0.064008 -3.993896 180)
			(unlocked yes)
			(layer "B.Fab")
			(hide yes)
			(effects
				(font
					(size 1.016 1.016)
					(thickness 0.1524)
				)
				(justify mirror)
			)
		)
		(property "Device Type" "R402H16"
			(at -0.064008 -5.517896 180)
			(unlocked yes)
			(layer "B.Fab")
			(hide yes)
			(effects
				(font
					(size 1.016 1.016)
					(thickness 0.1524)
				)
				(justify mirror)
			)
		)
		(duplicate_pad_numbers_are_jumpers no)
		(fp_line
			(start 0.508 -0.9398)
			(end 0.508 0.9398)
			(stroke
				(width 0.1524)
				(type default)
			)
			(layer "B.SilkS")
		)
		(fp_line
			(start -0.508 -0.9398)
			(end 0.508 -0.9398)
			(stroke
				(width 0.1524)
				(type default)
			)
			(layer "B.SilkS")
		)
		(fp_rect
			(start 0.508 0.9398)
			(end -0.508 -0.9398)
			(stroke
				(width 0)
				(type default)
			)
			(fill no)
			(layer "B.CrtYd")
		)
		(fp_rect
			(start 0.508 0.9398)
			(end -0.508 -0.9398)
			(stroke
				(width 0)
				(type default)
			)
			(fill no)
			(layer "B.Fab")
		)
		(pad "1" smd custom
			(at 0 -0.4445)
			(size 0.1397 0.1397)
			(layers "B.Cu" "B.Mask" "B.Paste")
			(net "BMC_ENTEST")
			(options
				(clearance outline)
				(anchor circle)
			)
			(primitives
				(gr_poly
					(pts
						(arc
							(start -0.1778 0.2794)
							(mid -0.249642 0.249642)
							(end -0.2794 0.1778)
						)
						(arc
							(start -0.2794 -0.1778)
							(mid -0.249642 -0.249642)
							(end -0.1778 -0.2794)
						)
						(arc
							(start 0.1778 -0.2794)
							(mid 0.249642 -0.249642)
							(end 0.2794 -0.1778)
						)
						(arc
							(start 0.2794 0.1778)
							(mid 0.249642 0.249642)
							(end 0.1778 0.2794)
						)
					)
					(width 0)
					(fill yes)
				)
			)
		)
		(pad "2" smd custom
			(at 0 0.4445)
			(size 0.1397 0.1397)
			(layers "B.Cu" "B.Mask" "B.Paste")
			(net "GND")
			(options
				(clearance outline)
				(anchor circle)
			)
			(primitives
				(gr_poly
					(pts
						(arc
							(start -0.1778 0.2794)
							(mid -0.249642 0.249642)
							(end -0.2794 0.1778)
						)
						(arc
							(start -0.2794 -0.1778)
							(mid -0.249642 -0.249642)
							(end -0.1778 -0.2794)
						)
						(arc
							(start 0.1778 -0.2794)
							(mid 0.249642 -0.249642)
							(end 0.2794 -0.1778)
						)
						(arc
							(start 0.2794 0.1778)
							(mid 0.249642 0.249642)
							(end 0.1778 0.2794)
						)
					)
					(width 0)
					(fill yes)
				)
			)
		)
	)
	(footprint ""
		(layer "B.Cu")
		(at 55.626 -156.845)
		(property "Reference" "TP218"
			(at 0 0 0)
			(layer "B.SilkS")
			(hide yes)
			(effects
				(font
					(size 1.27 1.27)
				)
				(justify mirror)
			)
		)
		(property "Value" "TPAD28-2-GP"
			(at 0.0127 -1.6637 0)
			(unlocked yes)
			(layer "B.Fab")
			(hide yes)
			(effects
				(font
					(size 1.016 1.016)
					(thickness 0.1524)
				)
				(justify mirror)
			)
		)
		(property "Device Type" "TPAD28"
			(at 0.0127 -3.1877 0)
			(unlocked yes)
			(layer "B.Fab")
			(hide yes)
			(effects
				(font
					(size 1.016 1.016)
					(thickness 0.1524)
				)
				(justify mirror)
			)
		)
		(duplicate_pad_numbers_are_jumpers no)
		(fp_poly
			(pts
				(arc
					(start 0.3556 0)
					(mid -0.3556 0)
					(end 0.3556 0)
				)
			)
			(stroke
				(width 0)
				(type default)
			)
			(fill no)
			(layer "B.CrtYd")
		)
		(fp_poly
			(pts
				(arc
					(start 0.6096 0)
					(mid -0.6096 0)
					(end 0.6096 0)
				)
			)
			(stroke
				(width 0)
				(type default)
			)
			(fill no)
			(layer "B.Fab")
		)
		(pad "1" smd circle
			(at 0 0 180)
			(size 0.7112 0.7112)
			(layers "B.Cu" "B.Mask" "B.Paste")
			(net "ADC_P1V8")
		)
	)
	(footprint ""
		(layer "B.Cu")
		(at 206.547974 -102.391718 -90)
		(property "Reference" "R833"
			(at 0 0 90)
			(layer "B.SilkS")
			(hide yes)
			(effects
				(font
					(size 1.27 1.27)
				)
				(justify mirror)
			)
		)
		(property "Value" "200KR2F-L-GP"
			(at -0.064008 -3.993896 270)
			(unlocked yes)
			(layer "B.Fab")
			(hide yes)
			(effects
				(font
					(size 1.016 1.016)
					(thickness 0.1524)
				)
				(justify mirror)
			)
		)
		(property "Device Type" "R402H16"
			(at -0.064008 -5.517896 270)
			(unlocked yes)
			(layer "B.Fab")
			(hide yes)
			(effects
				(font
					(size 1.016 1.016)
					(thickness 0.1524)
				)
				(justify mirror)
			)
		)
		(duplicate_pad_numbers_are_jumpers no)
		(fp_line
			(start -0.508 -0.9398)
			(end 0.508 -0.9398)
			(stroke
				(width 0.1524)
				(type default)
			)
			(layer "B.SilkS")
		)
		(fp_line
			(start 0.508 -0.9398)
			(end 0.508 0.9398)
			(stroke
				(width 0.1524)
				(type default)
			)
			(layer "B.SilkS")
		)
		(fp_rect
			(start 0.508 0.9398)
			(end -0.508 -0.9398)
			(stroke
				(width 0)
				(type default)
			)
			(fill no)
			(layer "B.CrtYd")
		)
		(fp_rect
			(start 0.508 0.9398)
			(end -0.508 -0.9398)
			(stroke
				(width 0)
				(type default)
			)
			(fill no)
			(layer "B.Fab")
		)
		(pad "1" smd custom
			(at 0 -0.4445 90)
			(size 0.1397 0.1397)
			(layers "B.Cu" "B.Mask" "B.Paste")
			(net "U82_VREF2")
			(options
				(clearance outline)
				(anchor circle)
			)
			(primitives
				(gr_poly
					(pts
						(arc
							(start -0.1778 0.2794)
							(mid -0.249642 0.249642)
							(end -0.2794 0.1778)
						)
						(arc
							(start -0.2794 -0.1778)
							(mid -0.249642 -0.249642)
							(end -0.1778 -0.2794)
						)
						(arc
							(start 0.1778 -0.2794)
							(mid 0.249642 -0.249642)
							(end 0.2794 -0.1778)
						)
						(arc
							(start 0.2794 0.1778)
							(mid 0.249642 0.249642)
							(end 0.1778 0.2794)
						)
					)
					(width 0)
					(fill yes)
				)
			)
		)
		(pad "2" smd custom
			(at 0 0.4445 90)
			(size 0.1397 0.1397)
			(layers "B.Cu" "B.Mask" "B.Paste")
			(net "P3V3_STBY")
			(options
				(clearance outline)
				(anchor circle)
			)
			(primitives
				(gr_poly
					(pts
						(arc
							(start -0.1778 0.2794)
							(mid -0.249642 0.249642)
							(end -0.2794 0.1778)
						)
						(arc
							(start -0.2794 -0.1778)
							(mid -0.249642 -0.249642)
							(end -0.1778 -0.2794)
						)
						(arc
							(start 0.1778 -0.2794)
							(mid 0.249642 -0.249642)
							(end 0.2794 -0.1778)
						)
						(arc
							(start 0.2794 0.1778)
							(mid 0.249642 0.249642)
							(end 0.1778 0.2794)
						)
					)
					(width 0)
					(fill yes)
				)
			)
		)
	)
	(footprint ""
		(layer "B.Cu")
		(at 38.98773 -140.300964 180)
		(property "Reference" "C97"
			(at 0 0 0)
			(layer "B.SilkS")
			(hide yes)
			(effects
				(font
					(size 1.27 1.27)
				)
				(justify mirror)
			)
		)
		(property "Value" "SC1U16V3KX-5GP"
			(at 0 -2.8194 180)
			(unlocked yes)
			(layer "B.Fab")
			(hide yes)
			(effects
				(font
					(size 1.016 1.016)
					(thickness 0.1524)
				)
				(justify mirror)
			)
		)
		(property "Device Type" "C603H36"
			(at 0 -4.3434 180)
			(unlocked yes)
			(layer "B.Fab")
			(hide yes)
			(effects
				(font
					(size 1.016 1.016)
					(thickness 0.1524)
				)
				(justify mirror)
			)
		)
		(duplicate_pad_numbers_are_jumpers no)
		(fp_line
			(start -0.508 0)
			(end 0.508 0)
			(stroke
				(width 0.2032)
				(type default)
			)
			(layer "B.SilkS")
		)
		(fp_rect
			(start 0.5842 1.3335)
			(end -0.5842 -1.3335)
			(stroke
				(width 0)
				(type default)
			)
			(fill no)
			(layer "B.CrtYd")
		)
		(fp_rect
			(start 0.5842 1.3335)
			(end -0.5842 -1.3335)
			(stroke
				(width 0)
				(type default)
			)
			(fill no)
			(layer "B.Fab")
		)
		(pad "1" smd custom
			(at 0 -0.762)
			(size 0.2159 0.2159)
			(layers "B.Cu" "B.Mask" "B.Paste")
			(net "P3V3_STBY")
			(options
				(clearance outline)
				(anchor circle)
			)
			(primitives
				(gr_poly
					(pts
						(arc
							(start -0.3302 0.4318)
							(mid -0.402042 0.402042)
							(end -0.4318 0.3302)
						)
						(arc
							(start -0.4318 -0.3302)
							(mid -0.402042 -0.402042)
							(end -0.3302 -0.4318)
						)
						(arc
							(start 0.3302 -0.4318)
							(mid 0.402042 -0.402042)
							(end 0.4318 -0.3302)
						)
						(arc
							(start 0.4318 0.3302)
							(mid 0.402042 0.402042)
							(end 0.3302 0.4318)
						)
					)
					(width 0)
					(fill yes)
				)
			)
		)
		(pad "2" smd custom
			(at 0 0.762)
			(size 0.2159 0.2159)
			(layers "B.Cu" "B.Mask" "B.Paste")
			(net "GND")
			(options
				(clearance outline)
				(anchor circle)
			)
			(primitives
				(gr_poly
					(pts
						(arc
							(start -0.3302 0.4318)
							(mid -0.402042 0.402042)
							(end -0.4318 0.3302)
						)
						(arc
							(start -0.4318 -0.3302)
							(mid -0.402042 -0.402042)
							(end -0.3302 -0.4318)
						)
						(arc
							(start 0.3302 -0.4318)
							(mid 0.402042 -0.402042)
							(end 0.4318 -0.3302)
						)
						(arc
							(start 0.4318 0.3302)
							(mid 0.402042 0.402042)
							(end 0.3302 0.4318)
						)
					)
					(width 0)
					(fill yes)
				)
			)
		)
	)
	(footprint ""
		(layer "B.Cu")
		(at 56.007 -141.6812)
		(property "Reference" "TP73"
			(at 0 0 0)
			(layer "B.SilkS")
			(hide yes)
			(effects
				(font
					(size 1.27 1.27)
				)
				(justify mirror)
			)
		)
		(property "Value" "TPAD28-2-GP"
			(at 0.0127 -1.6637 0)
			(unlocked yes)
			(layer "B.Fab")
			(hide yes)
			(effects
				(font
					(size 1.016 1.016)
					(thickness 0.1524)
				)
				(justify mirror)
			)
		)
		(property "Device Type" "TPAD28"
			(at 0.0127 -3.1877 0)
			(unlocked yes)
			(layer "B.Fab")
			(hide yes)
			(effects
				(font
					(size 1.016 1.016)
					(thickness 0.1524)
				)
				(justify mirror)
			)
		)
		(duplicate_pad_numbers_are_jumpers no)
		(fp_poly
			(pts
				(arc
					(start 0.3556 0)
					(mid -0.3556 0)
					(end 0.3556 0)
				)
			)
			(stroke
				(width 0)
				(type default)
			)
			(fill no)
			(layer "B.CrtYd")
		)
		(fp_poly
			(pts
				(arc
					(start 0.6096 0)
					(mid -0.6096 0)
					(end 0.6096 0)
				)
			)
			(stroke
				(width 0)
				(type default)
			)
			(fill no)
			(layer "B.Fab")
		)
		(pad "1" smd circle
			(at 0 0 180)
			(size 0.7112 0.7112)
			(layers "B.Cu" "B.Mask" "B.Paste")
			(net "TP_BMC_GPIOI5")
		)
	)
	(footprint ""
		(layer "B.Cu")
		(at 201.845418 -130.391408 180)
		(property "Reference" "C629"
			(at 0 0 0)
			(layer "B.SilkS")
			(hide yes)
			(effects
				(font
					(size 1.27 1.27)
				)
				(justify mirror)
			)
		)
		(property "Value" "SCD1U16V2KX-3GP"
			(at -1.1811 -2.7051 180)
			(unlocked yes)
			(layer "B.Fab")
			(hide yes)
			(effects
				(font
					(size 1.016 1.016)
					(thickness 0.1524)
				)
				(justify mirror)
			)
		)
		(property "Device Type" "C402H22"
			(at -1.1811 -4.2291 180)
			(unlocked yes)
			(layer "B.Fab")
			(hide yes)
			(effects
				(font
					(size 1.016 1.016)
					(thickness 0.1524)
				)
				(justify mirror)
			)
		)
		(duplicate_pad_numbers_are_jumpers no)
		(fp_rect
			(start 0.4318 0.9525)
			(end -0.4318 -0.9525)
			(stroke
				(width 0)
				(type default)
			)
			(fill no)
			(layer "B.CrtYd")
		)
		(fp_rect
			(start 0.4318 0.9525)
			(end -0.4318 -0.9525)
			(stroke
				(width 0)
				(type default)
			)
			(fill no)
			(layer "B.Fab")
		)
		(pad "1" smd custom
			(at 0 -0.4445)
			(size 0.1524 0.1524)
			(layers "B.Cu" "B.Mask" "B.Paste")
			(net "P3V3_M2")
			(options
				(clearance outline)
				(anchor circle)
			)
			(primitives
				(gr_poly
					(pts
						(arc
							(start 0.3048 0.2032)
							(mid 0.275042 0.275042)
							(end 0.2032 0.3048)
						)
						(arc
							(start -0.2032 0.3048)
							(mid -0.275042 0.275042)
							(end -0.3048 0.2032)
						)
						(arc
							(start -0.3048 -0.2032)
							(mid -0.275042 -0.275042)
							(end -0.2032 -0.3048)
						)
						(arc
							(start 0.2032 -0.3048)
							(mid 0.275042 -0.275042)
							(end 0.3048 -0.2032)
						)
					)
					(width 0)
					(fill yes)
				)
			)
		)
		(pad "2" smd custom
			(at 0 0.4445)
			(size 0.1524 0.1524)
			(layers "B.Cu" "B.Mask" "B.Paste")
			(net "GND")
			(options
				(clearance outline)
				(anchor circle)
			)
			(primitives
				(gr_poly
					(pts
						(arc
							(start 0.3048 0.2032)
							(mid 0.275042 0.275042)
							(end 0.2032 0.3048)
						)
						(arc
							(start -0.2032 0.3048)
							(mid -0.275042 0.275042)
							(end -0.3048 0.2032)
						)
						(arc
							(start -0.3048 -0.2032)
							(mid -0.275042 -0.275042)
							(end -0.2032 -0.3048)
						)
						(arc
							(start 0.2032 -0.3048)
							(mid 0.275042 -0.275042)
							(end 0.3048 -0.2032)
						)
					)
					(width 0)
					(fill yes)
				)
			)
		)
	)
	(footprint ""
		(layer "B.Cu")
		(at 207.059784 -108.793534 90)
		(property "Reference" "R813"
			(at 0 0 90)
			(layer "B.SilkS")
			(hide yes)
			(effects
				(font
					(size 1.27 1.27)
				)
				(justify mirror)
			)
		)
		(property "Value" "1KR2F-3-GP"
			(at -0.064008 -3.993896 90)
			(unlocked yes)
			(layer "B.Fab")
			(hide yes)
			(effects
				(font
					(size 1.016 1.016)
					(thickness 0.1524)
				)
				(justify mirror)
			)
		)
		(property "Device Type" "R402H16"
			(at -0.064008 -5.517896 90)
			(unlocked yes)
			(layer "B.Fab")
			(hide yes)
			(effects
				(font
					(size 1.016 1.016)
					(thickness 0.1524)
				)
				(justify mirror)
			)
		)
		(duplicate_pad_numbers_are_jumpers no)
		(fp_line
			(start 0.508 -0.9398)
			(end 0.508 0.9398)
			(stroke
				(width 0.1524)
				(type default)
			)
			(layer "B.SilkS")
		)
		(fp_line
			(start -0.508 -0.9398)
			(end 0.508 -0.9398)
			(stroke
				(width 0.1524)
				(type default)
			)
			(layer "B.SilkS")
		)
		(fp_rect
			(start 0.508 0.9398)
			(end -0.508 -0.9398)
			(stroke
				(width 0)
				(type default)
			)
			(fill no)
			(layer "B.CrtYd")
		)
		(fp_rect
			(start 0.508 0.9398)
			(end -0.508 -0.9398)
			(stroke
				(width 0)
				(type default)
			)
			(fill no)
			(layer "B.Fab")
		)
		(pad "1" smd custom
			(at 0 -0.4445 270)
			(size 0.1397 0.1397)
			(layers "B.Cu" "B.Mask" "B.Paste")
			(net "P1V8_STBY")
			(options
				(clearance outline)
				(anchor circle)
			)
			(primitives
				(gr_poly
					(pts
						(arc
							(start -0.1778 0.2794)
							(mid -0.249642 0.249642)
							(end -0.2794 0.1778)
						)
						(arc
							(start -0.2794 -0.1778)
							(mid -0.249642 -0.249642)
							(end -0.1778 -0.2794)
						)
						(arc
							(start 0.1778 -0.2794)
							(mid 0.249642 -0.249642)
							(end 0.2794 -0.1778)
						)
						(arc
							(start 0.2794 0.1778)
							(mid 0.249642 0.249642)
							(end 0.1778 0.2794)
						)
					)
					(width 0)
					(fill yes)
				)
			)
		)
		(pad "2" smd custom
			(at 0 0.4445 270)
			(size 0.1397 0.1397)
			(layers "B.Cu" "B.Mask" "B.Paste")
			(net "I2C_M2_1_1V8_SCL")
			(options
				(clearance outline)
				(anchor circle)
			)
			(primitives
				(gr_poly
					(pts
						(arc
							(start -0.1778 0.2794)
							(mid -0.249642 0.249642)
							(end -0.2794 0.1778)
						)
						(arc
							(start -0.2794 -0.1778)
							(mid -0.249642 -0.249642)
							(end -0.1778 -0.2794)
						)
						(arc
							(start 0.1778 -0.2794)
							(mid 0.249642 -0.249642)
							(end 0.2794 -0.1778)
						)
						(arc
							(start 0.2794 0.1778)
							(mid 0.249642 0.249642)
							(end 0.1778 0.2794)
						)
					)
					(width 0)
					(fill yes)
				)
			)
		)
	)
	(footprint ""
		(layer "B.Cu")
		(at 68.530724 -144.691608)
		(property "Reference" "R161"
			(at 0 0 0)
			(layer "B.SilkS")
			(hide yes)
			(effects
				(font
					(size 1.27 1.27)
				)
				(justify mirror)
			)
		)
		(property "Value" "0R2J-2-GP"
			(at -0.064008 -3.993896 0)
			(unlocked yes)
			(layer "B.Fab")
			(hide yes)
			(effects
				(font
					(size 1.016 1.016)
					(thickness 0.1524)
				)
				(justify mirror)
			)
		)
		(property "Device Type" "R402H16"
			(at -0.064008 -5.517896 0)
			(unlocked yes)
			(layer "B.Fab")
			(hide yes)
			(effects
				(font
					(size 1.016 1.016)
					(thickness 0.1524)
				)
				(justify mirror)
			)
		)
		(duplicate_pad_numbers_are_jumpers no)
		(fp_line
			(start -0.508 -0.9398)
			(end 0.508 -0.9398)
			(stroke
				(width 0.1524)
				(type default)
			)
			(layer "B.SilkS")
		)
		(fp_line
			(start 0.508 -0.9398)
			(end 0.508 0.9398)
			(stroke
				(width 0.1524)
				(type default)
			)
			(layer "B.SilkS")
		)
		(fp_rect
			(start 0.508 0.9398)
			(end -0.508 -0.9398)
			(stroke
				(width 0)
				(type default)
			)
			(fill no)
			(layer "B.CrtYd")
		)
		(fp_rect
			(start 0.508 0.9398)
			(end -0.508 -0.9398)
			(stroke
				(width 0)
				(type default)
			)
			(fill no)
			(layer "B.Fab")
		)
		(pad "1" smd custom
			(at 0 -0.4445 180)
			(size 0.1397 0.1397)
			(layers "B.Cu" "B.Mask" "B.Paste")
			(net "BMC_SMB12_DAT")
			(options
				(clearance outline)
				(anchor circle)
			)
			(primitives
				(gr_poly
					(pts
						(arc
							(start -0.1778 0.2794)
							(mid -0.249642 0.249642)
							(end -0.2794 0.1778)
						)
						(arc
							(start -0.2794 -0.1778)
							(mid -0.249642 -0.249642)
							(end -0.1778 -0.2794)
						)
						(arc
							(start 0.1778 -0.2794)
							(mid 0.249642 -0.249642)
							(end 0.2794 -0.1778)
						)
						(arc
							(start 0.2794 0.1778)
							(mid 0.249642 0.249642)
							(end 0.1778 0.2794)
						)
					)
					(width 0)
					(fill yes)
				)
			)
		)
		(pad "2" smd custom
			(at 0 0.4445 180)
			(size 0.1397 0.1397)
			(layers "B.Cu" "B.Mask" "B.Paste")
			(net "I2C_DEBUG_SDA_L")
			(options
				(clearance outline)
				(anchor circle)
			)
			(primitives
				(gr_poly
					(pts
						(arc
							(start -0.1778 0.2794)
							(mid -0.249642 0.249642)
							(end -0.2794 0.1778)
						)
						(arc
							(start -0.2794 -0.1778)
							(mid -0.249642 -0.249642)
							(end -0.1778 -0.2794)
						)
						(arc
							(start 0.1778 -0.2794)
							(mid 0.249642 -0.249642)
							(end 0.2794 -0.1778)
						)
						(arc
							(start 0.2794 0.1778)
							(mid 0.249642 0.249642)
							(end 0.1778 0.2794)
						)
					)
					(width 0)
					(fill yes)
				)
			)
		)
	)
	(footprint ""
		(layer "B.Cu")
		(at 40.281606 -132.286248 90)
		(property "Reference" "R370"
			(at 0 0 90)
			(layer "B.SilkS")
			(hide yes)
			(effects
				(font
					(size 1.27 1.27)
				)
				(justify mirror)
			)
		)
		(property "Value" "4K7R2F-GP"
			(at -0.064008 -3.993896 90)
			(unlocked yes)
			(layer "B.Fab")
			(hide yes)
			(effects
				(font
					(size 1.016 1.016)
					(thickness 0.1524)
				)
				(justify mirror)
			)
		)
		(property "Device Type" "R402H16"
			(at -0.064008 -5.517896 90)
			(unlocked yes)
			(layer "B.Fab")
			(hide yes)
			(effects
				(font
					(size 1.016 1.016)
					(thickness 0.1524)
				)
				(justify mirror)
			)
		)
		(duplicate_pad_numbers_are_jumpers no)
		(fp_line
			(start 0.508 -0.9398)
			(end 0.508 0.9398)
			(stroke
				(width 0.1524)
				(type default)
			)
			(layer "B.SilkS")
		)
		(fp_line
			(start -0.508 -0.9398)
			(end 0.508 -0.9398)
			(stroke
				(width 0.1524)
				(type default)
			)
			(layer "B.SilkS")
		)
		(fp_rect
			(start 0.508 0.9398)
			(end -0.508 -0.9398)
			(stroke
				(width 0)
				(type default)
			)
			(fill no)
			(layer "B.CrtYd")
		)
		(fp_rect
			(start 0.508 0.9398)
			(end -0.508 -0.9398)
			(stroke
				(width 0)
				(type default)
			)
			(fill no)
			(layer "B.Fab")
		)
		(pad "1" smd custom
			(at 0 -0.4445 270)
			(size 0.1397 0.1397)
			(layers "B.Cu" "B.Mask" "B.Paste")
			(net "P3V3_STBY")
			(options
				(clearance outline)
				(anchor circle)
			)
			(primitives
				(gr_poly
					(pts
						(arc
							(start -0.1778 0.2794)
							(mid -0.249642 0.249642)
							(end -0.2794 0.1778)
						)
						(arc
							(start -0.2794 -0.1778)
							(mid -0.249642 -0.249642)
							(end -0.1778 -0.2794)
						)
						(arc
							(start 0.1778 -0.2794)
							(mid 0.249642 -0.249642)
							(end 0.2794 -0.1778)
						)
						(arc
							(start 0.2794 0.1778)
							(mid 0.249642 0.249642)
							(end 0.1778 0.2794)
						)
					)
					(width 0)
					(fill yes)
				)
			)
		)
		(pad "2" smd custom
			(at 0 0.4445 270)
			(size 0.1397 0.1397)
			(layers "B.Cu" "B.Mask" "B.Paste")
			(net "BMC_SPI_MOSI")
			(options
				(clearance outline)
				(anchor circle)
			)
			(primitives
				(gr_poly
					(pts
						(arc
							(start -0.1778 0.2794)
							(mid -0.249642 0.249642)
							(end -0.2794 0.1778)
						)
						(arc
							(start -0.2794 -0.1778)
							(mid -0.249642 -0.249642)
							(end -0.1778 -0.2794)
						)
						(arc
							(start 0.1778 -0.2794)
							(mid 0.249642 -0.249642)
							(end 0.2794 -0.1778)
						)
						(arc
							(start 0.2794 0.1778)
							(mid 0.249642 0.249642)
							(end 0.1778 0.2794)
						)
					)
					(width 0)
					(fill yes)
				)
			)
		)
	)
	(footprint ""
		(layer "B.Cu")
		(at 132.41782 -21.30552 180)
		(property "Reference" "R744"
			(at 0 0 0)
			(layer "B.SilkS")
			(hide yes)
			(effects
				(font
					(size 1.27 1.27)
				)
				(justify mirror)
			)
		)
		(property "Value" "11KR2F-L-GP"
			(at -0.064008 -3.993896 180)
			(unlocked yes)
			(layer "B.Fab")
			(hide yes)
			(effects
				(font
					(size 1.016 1.016)
					(thickness 0.1524)
				)
				(justify mirror)
			)
		)
		(property "Device Type" "R402H16"
			(at -0.064008 -5.517896 180)
			(unlocked yes)
			(layer "B.Fab")
			(hide yes)
			(effects
				(font
					(size 1.016 1.016)
					(thickness 0.1524)
				)
				(justify mirror)
			)
		)
		(duplicate_pad_numbers_are_jumpers no)
		(fp_line
			(start 0.508 -0.9398)
			(end 0.508 0.9398)
			(stroke
				(width 0.1524)
				(type default)
			)
			(layer "B.SilkS")
		)
		(fp_line
			(start -0.508 -0.9398)
			(end 0.508 -0.9398)
			(stroke
				(width 0.1524)
				(type default)
			)
			(layer "B.SilkS")
		)
		(fp_rect
			(start 0.508 0.9398)
			(end -0.508 -0.9398)
			(stroke
				(width 0)
				(type default)
			)
			(fill no)
			(layer "B.CrtYd")
		)
		(fp_rect
			(start 0.508 0.9398)
			(end -0.508 -0.9398)
			(stroke
				(width 0)
				(type default)
			)
			(fill no)
			(layer "B.Fab")
		)
		(pad "1" smd custom
			(at 0 -0.4445)
			(size 0.1397 0.1397)
			(layers "B.Cu" "B.Mask" "B.Paste")
			(net "IOM_ADM1278_EN")
			(options
				(clearance outline)
				(anchor circle)
			)
			(primitives
				(gr_poly
					(pts
						(arc
							(start -0.1778 0.2794)
							(mid -0.249642 0.249642)
							(end -0.2794 0.1778)
						)
						(arc
							(start -0.2794 -0.1778)
							(mid -0.249642 -0.249642)
							(end -0.1778 -0.2794)
						)
						(arc
							(start 0.1778 -0.2794)
							(mid 0.249642 -0.249642)
							(end 0.2794 -0.1778)
						)
						(arc
							(start 0.2794 0.1778)
							(mid 0.249642 0.249642)
							(end 0.1778 0.2794)
						)
					)
					(width 0)
					(fill yes)
				)
			)
		)
		(pad "2" smd custom
			(at 0 0.4445)
			(size 0.1397 0.1397)
			(layers "B.Cu" "B.Mask" "B.Paste")
			(net "GND")
			(options
				(clearance outline)
				(anchor circle)
			)
			(primitives
				(gr_poly
					(pts
						(arc
							(start -0.1778 0.2794)
							(mid -0.249642 0.249642)
							(end -0.2794 0.1778)
						)
						(arc
							(start -0.2794 -0.1778)
							(mid -0.249642 -0.249642)
							(end -0.1778 -0.2794)
						)
						(arc
							(start 0.1778 -0.2794)
							(mid 0.249642 -0.249642)
							(end 0.2794 -0.1778)
						)
						(arc
							(start 0.2794 0.1778)
							(mid 0.249642 0.249642)
							(end 0.1778 0.2794)
						)
					)
					(width 0)
					(fill yes)
				)
			)
		)
	)
	(footprint ""
		(layer "B.Cu")
		(at 89.916 -161.2646 180)
		(property "Reference" "C16"
			(at 0 0 0)
			(layer "B.SilkS")
			(hide yes)
			(effects
				(font
					(size 1.27 1.27)
				)
				(justify mirror)
			)
		)
		(property "Value" "SC1U16V3KX-5GP"
			(at 0 -2.8194 180)
			(unlocked yes)
			(layer "B.Fab")
			(hide yes)
			(effects
				(font
					(size 1.016 1.016)
					(thickness 0.1524)
				)
				(justify mirror)
			)
		)
		(property "Device Type" "C603H36"
			(at 0 -4.3434 180)
			(unlocked yes)
			(layer "B.Fab")
			(hide yes)
			(effects
				(font
					(size 1.016 1.016)
					(thickness 0.1524)
				)
				(justify mirror)
			)
		)
		(duplicate_pad_numbers_are_jumpers no)
		(fp_line
			(start -0.508 0)
			(end 0.508 0)
			(stroke
				(width 0.2032)
				(type default)
			)
			(layer "B.SilkS")
		)
		(fp_rect
			(start 0.5842 1.3335)
			(end -0.5842 -1.3335)
			(stroke
				(width 0)
				(type default)
			)
			(fill no)
			(layer "B.CrtYd")
		)
		(fp_rect
			(start 0.5842 1.3335)
			(end -0.5842 -1.3335)
			(stroke
				(width 0)
				(type default)
			)
			(fill no)
			(layer "B.Fab")
		)
		(pad "1" smd custom
			(at 0 -0.762)
			(size 0.2159 0.2159)
			(layers "B.Cu" "B.Mask" "B.Paste")
			(net "P3V3_STBY")
			(options
				(clearance outline)
				(anchor circle)
			)
			(primitives
				(gr_poly
					(pts
						(arc
							(start -0.3302 0.4318)
							(mid -0.402042 0.402042)
							(end -0.4318 0.3302)
						)
						(arc
							(start -0.4318 -0.3302)
							(mid -0.402042 -0.402042)
							(end -0.3302 -0.4318)
						)
						(arc
							(start 0.3302 -0.4318)
							(mid 0.402042 -0.402042)
							(end 0.4318 -0.3302)
						)
						(arc
							(start 0.4318 0.3302)
							(mid 0.402042 0.402042)
							(end 0.3302 0.4318)
						)
					)
					(width 0)
					(fill yes)
				)
			)
		)
		(pad "2" smd custom
			(at 0 0.762)
			(size 0.2159 0.2159)
			(layers "B.Cu" "B.Mask" "B.Paste")
			(net "GND")
			(options
				(clearance outline)
				(anchor circle)
			)
			(primitives
				(gr_poly
					(pts
						(arc
							(start -0.3302 0.4318)
							(mid -0.402042 0.402042)
							(end -0.4318 0.3302)
						)
						(arc
							(start -0.4318 -0.3302)
							(mid -0.402042 -0.402042)
							(end -0.3302 -0.4318)
						)
						(arc
							(start 0.3302 -0.4318)
							(mid 0.402042 -0.402042)
							(end 0.4318 -0.3302)
						)
						(arc
							(start 0.4318 0.3302)
							(mid 0.402042 0.402042)
							(end 0.3302 0.4318)
						)
					)
					(width 0)
					(fill yes)
				)
			)
		)
	)
	(footprint ""
		(layer "B.Cu")
		(at 87.8586 -147.124674 -90)
		(property "Reference" "R429"
			(at 0 0 90)
			(layer "B.SilkS")
			(hide yes)
			(effects
				(font
					(size 1.27 1.27)
				)
				(justify mirror)
			)
		)
		(property "Value" "4K7R2F-GP"
			(at -0.064008 -3.993896 270)
			(unlocked yes)
			(layer "B.Fab")
			(hide yes)
			(effects
				(font
					(size 1.016 1.016)
					(thickness 0.1524)
				)
				(justify mirror)
			)
		)
		(property "Device Type" "R402H16"
			(at -0.064008 -5.517896 270)
			(unlocked yes)
			(layer "B.Fab")
			(hide yes)
			(effects
				(font
					(size 1.016 1.016)
					(thickness 0.1524)
				)
				(justify mirror)
			)
		)
		(duplicate_pad_numbers_are_jumpers no)
		(fp_line
			(start -0.508 -0.9398)
			(end 0.508 -0.9398)
			(stroke
				(width 0.1524)
				(type default)
			)
			(layer "B.SilkS")
		)
		(fp_line
			(start 0.508 -0.9398)
			(end 0.508 0.9398)
			(stroke
				(width 0.1524)
				(type default)
			)
			(layer "B.SilkS")
		)
		(fp_rect
			(start 0.508 0.9398)
			(end -0.508 -0.9398)
			(stroke
				(width 0)
				(type default)
			)
			(fill no)
			(layer "B.CrtYd")
		)
		(fp_rect
			(start 0.508 0.9398)
			(end -0.508 -0.9398)
			(stroke
				(width 0)
				(type default)
			)
			(fill no)
			(layer "B.Fab")
		)
		(pad "1" smd custom
			(at 0 -0.4445 90)
			(size 0.1397 0.1397)
			(layers "B.Cu" "B.Mask" "B.Paste")
			(net "TCA9555_A1")
			(options
				(clearance outline)
				(anchor circle)
			)
			(primitives
				(gr_poly
					(pts
						(arc
							(start -0.1778 0.2794)
							(mid -0.249642 0.249642)
							(end -0.2794 0.1778)
						)
						(arc
							(start -0.2794 -0.1778)
							(mid -0.249642 -0.249642)
							(end -0.1778 -0.2794)
						)
						(arc
							(start 0.1778 -0.2794)
							(mid 0.249642 -0.249642)
							(end 0.2794 -0.1778)
						)
						(arc
							(start 0.2794 0.1778)
							(mid 0.249642 0.249642)
							(end 0.1778 0.2794)
						)
					)
					(width 0)
					(fill yes)
				)
			)
		)
		(pad "2" smd custom
			(at 0 0.4445 90)
			(size 0.1397 0.1397)
			(layers "B.Cu" "B.Mask" "B.Paste")
			(net "GND")
			(options
				(clearance outline)
				(anchor circle)
			)
			(primitives
				(gr_poly
					(pts
						(arc
							(start -0.1778 0.2794)
							(mid -0.249642 0.249642)
							(end -0.2794 0.1778)
						)
						(arc
							(start -0.2794 -0.1778)
							(mid -0.249642 -0.249642)
							(end -0.1778 -0.2794)
						)
						(arc
							(start 0.1778 -0.2794)
							(mid 0.249642 -0.249642)
							(end 0.2794 -0.1778)
						)
						(arc
							(start 0.2794 0.1778)
							(mid 0.249642 0.249642)
							(end 0.1778 0.2794)
						)
					)
					(width 0)
					(fill yes)
				)
			)
		)
	)
	(footprint ""
		(layer "B.Cu")
		(at 39.751254 -142.892018 180)
		(property "Reference" "R145"
			(at 0 0 0)
			(layer "B.SilkS")
			(hide yes)
			(effects
				(font
					(size 1.27 1.27)
				)
				(justify mirror)
			)
		)
		(property "Value" "240R2F-1-GP"
			(at -0.064008 -3.993896 180)
			(unlocked yes)
			(layer "B.Fab")
			(hide yes)
			(effects
				(font
					(size 1.016 1.016)
					(thickness 0.1524)
				)
				(justify mirror)
			)
		)
		(property "Device Type" "R402H16"
			(at -0.064008 -5.517896 180)
			(unlocked yes)
			(layer "B.Fab")
			(hide yes)
			(effects
				(font
					(size 1.016 1.016)
					(thickness 0.1524)
				)
				(justify mirror)
			)
		)
		(duplicate_pad_numbers_are_jumpers no)
		(fp_line
			(start 0.508 -0.9398)
			(end 0.508 0.9398)
			(stroke
				(width 0.1524)
				(type default)
			)
			(layer "B.SilkS")
		)
		(fp_line
			(start -0.508 -0.9398)
			(end 0.508 -0.9398)
			(stroke
				(width 0.1524)
				(type default)
			)
			(layer "B.SilkS")
		)
		(fp_rect
			(start 0.508 0.9398)
			(end -0.508 -0.9398)
			(stroke
				(width 0)
				(type default)
			)
			(fill no)
			(layer "B.CrtYd")
		)
		(fp_rect
			(start 0.508 0.9398)
			(end -0.508 -0.9398)
			(stroke
				(width 0)
				(type default)
			)
			(fill no)
			(layer "B.Fab")
		)
		(pad "1" smd custom
			(at 0 -0.4445)
			(size 0.1397 0.1397)
			(layers "B.Cu" "B.Mask" "B.Paste")
			(net "GND")
			(options
				(clearance outline)
				(anchor circle)
			)
			(primitives
				(gr_poly
					(pts
						(arc
							(start -0.1778 0.2794)
							(mid -0.249642 0.249642)
							(end -0.2794 0.1778)
						)
						(arc
							(start -0.2794 -0.1778)
							(mid -0.249642 -0.249642)
							(end -0.1778 -0.2794)
						)
						(arc
							(start 0.1778 -0.2794)
							(mid 0.249642 -0.249642)
							(end 0.2794 -0.1778)
						)
						(arc
							(start 0.2794 0.1778)
							(mid 0.249642 0.249642)
							(end 0.1778 0.2794)
						)
					)
					(width 0)
					(fill yes)
				)
			)
		)
		(pad "2" smd custom
			(at 0 0.4445)
			(size 0.1397 0.1397)
			(layers "B.Cu" "B.Mask" "B.Paste")
			(net "MIOZ")
			(options
				(clearance outline)
				(anchor circle)
			)
			(primitives
				(gr_poly
					(pts
						(arc
							(start -0.1778 0.2794)
							(mid -0.249642 0.249642)
							(end -0.2794 0.1778)
						)
						(arc
							(start -0.2794 -0.1778)
							(mid -0.249642 -0.249642)
							(end -0.1778 -0.2794)
						)
						(arc
							(start 0.1778 -0.2794)
							(mid 0.249642 -0.249642)
							(end 0.2794 -0.1778)
						)
						(arc
							(start 0.2794 0.1778)
							(mid 0.249642 0.249642)
							(end 0.1778 0.2794)
						)
					)
					(width 0)
					(fill yes)
				)
			)
		)
	)
	(footprint ""
		(layer "B.Cu")
		(at 39.456614 -156.177488 180)
		(property "Reference" "R316"
			(at 0 0 0)
			(layer "B.SilkS")
			(hide yes)
			(effects
				(font
					(size 1.27 1.27)
				)
				(justify mirror)
			)
		)
		(property "Value" "0R2J-2-GP"
			(at -0.064008 -3.993896 180)
			(unlocked yes)
			(layer "B.Fab")
			(hide yes)
			(effects
				(font
					(size 1.016 1.016)
					(thickness 0.1524)
				)
				(justify mirror)
			)
		)
		(property "Device Type" "R402H16"
			(at -0.064008 -5.517896 180)
			(unlocked yes)
			(layer "B.Fab")
			(hide yes)
			(effects
				(font
					(size 1.016 1.016)
					(thickness 0.1524)
				)
				(justify mirror)
			)
		)
		(duplicate_pad_numbers_are_jumpers no)
		(fp_line
			(start 0.508 -0.9398)
			(end 0.508 0.9398)
			(stroke
				(width 0.1524)
				(type default)
			)
			(layer "B.SilkS")
		)
		(fp_line
			(start -0.508 -0.9398)
			(end 0.508 -0.9398)
			(stroke
				(width 0.1524)
				(type default)
			)
			(layer "B.SilkS")
		)
		(fp_rect
			(start 0.508 0.9398)
			(end -0.508 -0.9398)
			(stroke
				(width 0)
				(type default)
			)
			(fill no)
			(layer "B.CrtYd")
		)
		(fp_rect
			(start 0.508 0.9398)
			(end -0.508 -0.9398)
			(stroke
				(width 0)
				(type default)
			)
			(fill no)
			(layer "B.Fab")
		)
		(pad "1" smd custom
			(at 0 -0.4445)
			(size 0.1397 0.1397)
			(layers "B.Cu" "B.Mask" "B.Paste")
			(net "BMC_RMT_HB")
			(options
				(clearance outline)
				(anchor circle)
			)
			(primitives
				(gr_poly
					(pts
						(arc
							(start -0.1778 0.2794)
							(mid -0.249642 0.249642)
							(end -0.2794 0.1778)
						)
						(arc
							(start -0.2794 -0.1778)
							(mid -0.249642 -0.249642)
							(end -0.1778 -0.2794)
						)
						(arc
							(start 0.1778 -0.2794)
							(mid 0.249642 -0.249642)
							(end 0.2794 -0.1778)
						)
						(arc
							(start 0.2794 0.1778)
							(mid 0.249642 0.249642)
							(end 0.1778 0.2794)
						)
					)
					(width 0)
					(fill yes)
				)
			)
		)
		(pad "2" smd custom
			(at 0 0.4445)
			(size 0.1397 0.1397)
			(layers "B.Cu" "B.Mask" "B.Paste")
			(net "BMC_RMT_HEARTBEAT")
			(options
				(clearance outline)
				(anchor circle)
			)
			(primitives
				(gr_poly
					(pts
						(arc
							(start -0.1778 0.2794)
							(mid -0.249642 0.249642)
							(end -0.2794 0.1778)
						)
						(arc
							(start -0.2794 -0.1778)
							(mid -0.249642 -0.249642)
							(end -0.1778 -0.2794)
						)
						(arc
							(start 0.1778 -0.2794)
							(mid 0.249642 -0.249642)
							(end 0.2794 -0.1778)
						)
						(arc
							(start 0.2794 0.1778)
							(mid 0.249642 0.249642)
							(end 0.1778 0.2794)
						)
					)
					(width 0)
					(fill yes)
				)
			)
		)
	)
	(footprint ""
		(layer "B.Cu")
		(at 78.68031 -152.908 180)
		(property "Reference" "R101"
			(at 0 0 0)
			(layer "B.SilkS")
			(hide yes)
			(effects
				(font
					(size 1.27 1.27)
				)
				(justify mirror)
			)
		)
		(property "Value" "0R2J-2-GP"
			(at -0.064008 -3.993896 180)
			(unlocked yes)
			(layer "B.Fab")
			(hide yes)
			(effects
				(font
					(size 1.016 1.016)
					(thickness 0.1524)
				)
				(justify mirror)
			)
		)
		(property "Device Type" "R402H16"
			(at -0.064008 -5.517896 180)
			(unlocked yes)
			(layer "B.Fab")
			(hide yes)
			(effects
				(font
					(size 1.016 1.016)
					(thickness 0.1524)
				)
				(justify mirror)
			)
		)
		(duplicate_pad_numbers_are_jumpers no)
		(fp_line
			(start 0.508 -0.9398)
			(end 0.508 0.9398)
			(stroke
				(width 0.1524)
				(type default)
			)
			(layer "B.SilkS")
		)
		(fp_line
			(start -0.508 -0.9398)
			(end 0.508 -0.9398)
			(stroke
				(width 0.1524)
				(type default)
			)
			(layer "B.SilkS")
		)
		(fp_rect
			(start 0.508 0.9398)
			(end -0.508 -0.9398)
			(stroke
				(width 0)
				(type default)
			)
			(fill no)
			(layer "B.CrtYd")
		)
		(fp_rect
			(start 0.508 0.9398)
			(end -0.508 -0.9398)
			(stroke
				(width 0)
				(type default)
			)
			(fill no)
			(layer "B.Fab")
		)
		(pad "1" smd custom
			(at 0 -0.4445)
			(size 0.1397 0.1397)
			(layers "B.Cu" "B.Mask" "B.Paste")
			(net "I2C_COMP_ALERT_N")
			(options
				(clearance outline)
				(anchor circle)
			)
			(primitives
				(gr_poly
					(pts
						(arc
							(start -0.1778 0.2794)
							(mid -0.249642 0.249642)
							(end -0.2794 0.1778)
						)
						(arc
							(start -0.2794 -0.1778)
							(mid -0.249642 -0.249642)
							(end -0.1778 -0.2794)
						)
						(arc
							(start 0.1778 -0.2794)
							(mid 0.249642 -0.249642)
							(end 0.2794 -0.1778)
						)
						(arc
							(start 0.2794 0.1778)
							(mid 0.249642 0.249642)
							(end 0.1778 0.2794)
						)
					)
					(width 0)
					(fill yes)
				)
			)
		)
		(pad "2" smd custom
			(at 0 0.4445)
			(size 0.1397 0.1397)
			(layers "B.Cu" "B.Mask" "B.Paste")
			(net "I2C_BMC_COMP_ALERT_N_R")
			(options
				(clearance outline)
				(anchor circle)
			)
			(primitives
				(gr_poly
					(pts
						(arc
							(start -0.1778 0.2794)
							(mid -0.249642 0.249642)
							(end -0.2794 0.1778)
						)
						(arc
							(start -0.2794 -0.1778)
							(mid -0.249642 -0.249642)
							(end -0.1778 -0.2794)
						)
						(arc
							(start 0.1778 -0.2794)
							(mid 0.249642 -0.249642)
							(end 0.2794 -0.1778)
						)
						(arc
							(start 0.2794 0.1778)
							(mid 0.249642 0.249642)
							(end 0.1778 0.2794)
						)
					)
					(width 0)
					(fill yes)
				)
			)
		)
	)
	(footprint ""
		(layer "B.Cu")
		(at 96.52 -152.4254 180)
		(property "Reference" "R42"
			(at 0 0 0)
			(layer "B.SilkS")
			(hide yes)
			(effects
				(font
					(size 1.27 1.27)
				)
				(justify mirror)
			)
		)
		(property "Value" "4K7R2F-GP"
			(at -0.064008 -3.993896 180)
			(unlocked yes)
			(layer "B.Fab")
			(hide yes)
			(effects
				(font
					(size 1.016 1.016)
					(thickness 0.1524)
				)
				(justify mirror)
			)
		)
		(property "Device Type" "R402H16"
			(at -0.064008 -5.517896 180)
			(unlocked yes)
			(layer "B.Fab")
			(hide yes)
			(effects
				(font
					(size 1.016 1.016)
					(thickness 0.1524)
				)
				(justify mirror)
			)
		)
		(duplicate_pad_numbers_are_jumpers no)
		(fp_line
			(start 0.508 -0.9398)
			(end 0.508 0.9398)
			(stroke
				(width 0.1524)
				(type default)
			)
			(layer "B.SilkS")
		)
		(fp_line
			(start -0.508 -0.9398)
			(end 0.508 -0.9398)
			(stroke
				(width 0.1524)
				(type default)
			)
			(layer "B.SilkS")
		)
		(fp_rect
			(start 0.508 0.9398)
			(end -0.508 -0.9398)
			(stroke
				(width 0)
				(type default)
			)
			(fill no)
			(layer "B.CrtYd")
		)
		(fp_rect
			(start 0.508 0.9398)
			(end -0.508 -0.9398)
			(stroke
				(width 0)
				(type default)
			)
			(fill no)
			(layer "B.Fab")
		)
		(pad "1" smd custom
			(at 0 -0.4445)
			(size 0.1397 0.1397)
			(layers "B.Cu" "B.Mask" "B.Paste")
			(net "USB_EN_3")
			(options
				(clearance outline)
				(anchor circle)
			)
			(primitives
				(gr_poly
					(pts
						(arc
							(start -0.1778 0.2794)
							(mid -0.249642 0.249642)
							(end -0.2794 0.1778)
						)
						(arc
							(start -0.2794 -0.1778)
							(mid -0.249642 -0.249642)
							(end -0.1778 -0.2794)
						)
						(arc
							(start 0.1778 -0.2794)
							(mid 0.249642 -0.249642)
							(end 0.2794 -0.1778)
						)
						(arc
							(start 0.2794 0.1778)
							(mid 0.249642 0.249642)
							(end 0.1778 0.2794)
						)
					)
					(width 0)
					(fill yes)
				)
			)
		)
		(pad "2" smd custom
			(at 0 0.4445)
			(size 0.1397 0.1397)
			(layers "B.Cu" "B.Mask" "B.Paste")
			(net "GND")
			(options
				(clearance outline)
				(anchor circle)
			)
			(primitives
				(gr_poly
					(pts
						(arc
							(start -0.1778 0.2794)
							(mid -0.249642 0.249642)
							(end -0.2794 0.1778)
						)
						(arc
							(start -0.2794 -0.1778)
							(mid -0.249642 -0.249642)
							(end -0.1778 -0.2794)
						)
						(arc
							(start 0.1778 -0.2794)
							(mid 0.249642 -0.249642)
							(end 0.2794 -0.1778)
						)
						(arc
							(start 0.2794 0.1778)
							(mid 0.249642 0.249642)
							(end 0.1778 0.2794)
						)
					)
					(width 0)
					(fill yes)
				)
			)
		)
	)
	(footprint ""
		(layer "B.Cu")
		(at 44.137326 -147.30476 90)
		(property "Reference" "C53"
			(at 0 0 90)
			(layer "B.SilkS")
			(hide yes)
			(effects
				(font
					(size 1.27 1.27)
				)
				(justify mirror)
			)
		)
		(property "Value" "SCD01U25V2KX-3GP"
			(at -1.1811 -2.7051 90)
			(unlocked yes)
			(layer "B.Fab")
			(hide yes)
			(effects
				(font
					(size 1.016 1.016)
					(thickness 0.1524)
				)
				(justify mirror)
			)
		)
		(property "Device Type" "C402H22"
			(at -1.1811 -4.2291 90)
			(unlocked yes)
			(layer "B.Fab")
			(hide yes)
			(effects
				(font
					(size 1.016 1.016)
					(thickness 0.1524)
				)
				(justify mirror)
			)
		)
		(duplicate_pad_numbers_are_jumpers no)
		(fp_rect
			(start 0.4318 0.9525)
			(end -0.4318 -0.9525)
			(stroke
				(width 0)
				(type default)
			)
			(fill no)
			(layer "B.CrtYd")
		)
		(fp_rect
			(start 0.4318 0.9525)
			(end -0.4318 -0.9525)
			(stroke
				(width 0)
				(type default)
			)
			(fill no)
			(layer "B.Fab")
		)
		(pad "1" smd custom
			(at 0 -0.4445 270)
			(size 0.1524 0.1524)
			(layers "B.Cu" "B.Mask" "B.Paste")
			(net "DDR_VREF")
			(options
				(clearance outline)
				(anchor circle)
			)
			(primitives
				(gr_poly
					(pts
						(arc
							(start 0.3048 0.2032)
							(mid 0.275042 0.275042)
							(end 0.2032 0.3048)
						)
						(arc
							(start -0.2032 0.3048)
							(mid -0.275042 0.275042)
							(end -0.3048 0.2032)
						)
						(arc
							(start -0.3048 -0.2032)
							(mid -0.275042 -0.275042)
							(end -0.2032 -0.3048)
						)
						(arc
							(start 0.2032 -0.3048)
							(mid 0.275042 -0.275042)
							(end 0.3048 -0.2032)
						)
					)
					(width 0)
					(fill yes)
				)
			)
		)
		(pad "2" smd custom
			(at 0 0.4445 270)
			(size 0.1524 0.1524)
			(layers "B.Cu" "B.Mask" "B.Paste")
			(net "GND")
			(options
				(clearance outline)
				(anchor circle)
			)
			(primitives
				(gr_poly
					(pts
						(arc
							(start 0.3048 0.2032)
							(mid 0.275042 0.275042)
							(end 0.2032 0.3048)
						)
						(arc
							(start -0.2032 0.3048)
							(mid -0.275042 0.275042)
							(end -0.3048 0.2032)
						)
						(arc
							(start -0.3048 -0.2032)
							(mid -0.275042 -0.275042)
							(end -0.2032 -0.3048)
						)
						(arc
							(start 0.2032 -0.3048)
							(mid 0.275042 -0.275042)
							(end 0.3048 -0.2032)
						)
					)
					(width 0)
					(fill yes)
				)
			)
		)
	)
	(footprint ""
		(layer "B.Cu")
		(at 224.989644 -68.51523 90)
		(property "Reference" "C639"
			(at 0 0 90)
			(layer "B.SilkS")
			(hide yes)
			(effects
				(font
					(size 1.27 1.27)
				)
				(justify mirror)
			)
		)
		(property "Value" "SCD1U16V2KX-3GP"
			(at -1.1811 -2.7051 90)
			(unlocked yes)
			(layer "B.Fab")
			(hide yes)
			(effects
				(font
					(size 1.016 1.016)
					(thickness 0.1524)
				)
				(justify mirror)
			)
		)
		(property "Device Type" "C402H22"
			(at -1.1811 -4.2291 90)
			(unlocked yes)
			(layer "B.Fab")
			(hide yes)
			(effects
				(font
					(size 1.016 1.016)
					(thickness 0.1524)
				)
				(justify mirror)
			)
		)
		(duplicate_pad_numbers_are_jumpers no)
		(fp_rect
			(start 0.4318 0.9525)
			(end -0.4318 -0.9525)
			(stroke
				(width 0)
				(type default)
			)
			(fill no)
			(layer "B.CrtYd")
		)
		(fp_rect
			(start 0.4318 0.9525)
			(end -0.4318 -0.9525)
			(stroke
				(width 0)
				(type default)
			)
			(fill no)
			(layer "B.Fab")
		)
		(pad "1" smd custom
			(at 0 -0.4445 270)
			(size 0.1524 0.1524)
			(layers "B.Cu" "B.Mask" "B.Paste")
			(net "P3V3_M2")
			(options
				(clearance outline)
				(anchor circle)
			)
			(primitives
				(gr_poly
					(pts
						(arc
							(start 0.3048 0.2032)
							(mid 0.275042 0.275042)
							(end 0.2032 0.3048)
						)
						(arc
							(start -0.2032 0.3048)
							(mid -0.275042 0.275042)
							(end -0.3048 0.2032)
						)
						(arc
							(start -0.3048 -0.2032)
							(mid -0.275042 -0.275042)
							(end -0.2032 -0.3048)
						)
						(arc
							(start 0.2032 -0.3048)
							(mid 0.275042 -0.275042)
							(end 0.3048 -0.2032)
						)
					)
					(width 0)
					(fill yes)
				)
			)
		)
		(pad "2" smd custom
			(at 0 0.4445 270)
			(size 0.1524 0.1524)
			(layers "B.Cu" "B.Mask" "B.Paste")
			(net "GND")
			(options
				(clearance outline)
				(anchor circle)
			)
			(primitives
				(gr_poly
					(pts
						(arc
							(start 0.3048 0.2032)
							(mid 0.275042 0.275042)
							(end 0.2032 0.3048)
						)
						(arc
							(start -0.2032 0.3048)
							(mid -0.275042 0.275042)
							(end -0.3048 0.2032)
						)
						(arc
							(start -0.3048 -0.2032)
							(mid -0.275042 -0.275042)
							(end -0.2032 -0.3048)
						)
						(arc
							(start 0.2032 -0.3048)
							(mid 0.275042 -0.275042)
							(end 0.3048 -0.2032)
						)
					)
					(width 0)
					(fill yes)
				)
			)
		)
	)
	(footprint ""
		(layer "B.Cu")
		(at 19.15287 -131.007358 180)
		(property "Reference" "R236"
			(at 0 0 0)
			(layer "B.SilkS")
			(hide yes)
			(effects
				(font
					(size 1.27 1.27)
				)
				(justify mirror)
			)
		)
		(property "Value" "120R2F-GP"
			(at -0.064008 -3.993896 180)
			(unlocked yes)
			(layer "B.Fab")
			(hide yes)
			(effects
				(font
					(size 1.016 1.016)
					(thickness 0.1524)
				)
				(justify mirror)
			)
		)
		(property "Device Type" "R402H16"
			(at -0.064008 -5.517896 180)
			(unlocked yes)
			(layer "B.Fab")
			(hide yes)
			(effects
				(font
					(size 1.016 1.016)
					(thickness 0.1524)
				)
				(justify mirror)
			)
		)
		(duplicate_pad_numbers_are_jumpers no)
		(fp_line
			(start 0.508 -0.9398)
			(end 0.508 0.9398)
			(stroke
				(width 0.1524)
				(type default)
			)
			(layer "B.SilkS")
		)
		(fp_line
			(start -0.508 -0.9398)
			(end 0.508 -0.9398)
			(stroke
				(width 0.1524)
				(type default)
			)
			(layer "B.SilkS")
		)
		(fp_rect
			(start 0.508 0.9398)
			(end -0.508 -0.9398)
			(stroke
				(width 0)
				(type default)
			)
			(fill no)
			(layer "B.CrtYd")
		)
		(fp_rect
			(start 0.508 0.9398)
			(end -0.508 -0.9398)
			(stroke
				(width 0)
				(type default)
			)
			(fill no)
			(layer "B.Fab")
		)
		(pad "1" smd custom
			(at 0 -0.4445)
			(size 0.1397 0.1397)
			(layers "B.Cu" "B.Mask" "B.Paste")
			(net "MEMA_1")
			(options
				(clearance outline)
				(anchor circle)
			)
			(primitives
				(gr_poly
					(pts
						(arc
							(start -0.1778 0.2794)
							(mid -0.249642 0.249642)
							(end -0.2794 0.1778)
						)
						(arc
							(start -0.2794 -0.1778)
							(mid -0.249642 -0.249642)
							(end -0.1778 -0.2794)
						)
						(arc
							(start 0.1778 -0.2794)
							(mid 0.249642 -0.249642)
							(end 0.2794 -0.1778)
						)
						(arc
							(start 0.2794 0.1778)
							(mid 0.249642 0.249642)
							(end 0.1778 0.2794)
						)
					)
					(width 0)
					(fill yes)
				)
			)
		)
		(pad "2" smd custom
			(at 0 0.4445)
			(size 0.1397 0.1397)
			(layers "B.Cu" "B.Mask" "B.Paste")
			(net "P1V2_STBY")
			(options
				(clearance outline)
				(anchor circle)
			)
			(primitives
				(gr_poly
					(pts
						(arc
							(start -0.1778 0.2794)
							(mid -0.249642 0.249642)
							(end -0.2794 0.1778)
						)
						(arc
							(start -0.2794 -0.1778)
							(mid -0.249642 -0.249642)
							(end -0.1778 -0.2794)
						)
						(arc
							(start 0.1778 -0.2794)
							(mid 0.249642 -0.249642)
							(end 0.2794 -0.1778)
						)
						(arc
							(start 0.2794 0.1778)
							(mid 0.249642 0.249642)
							(end 0.1778 0.2794)
						)
					)
					(width 0)
					(fill yes)
				)
			)
		)
	)
	(footprint ""
		(layer "B.Cu")
		(at 83.194652 -152.914096 180)
		(property "Reference" "C39"
			(at 0 0 0)
			(layer "B.SilkS")
			(hide yes)
			(effects
				(font
					(size 1.27 1.27)
				)
				(justify mirror)
			)
		)
		(property "Value" "SCD1U16V2KX-3GP"
			(at -1.1811 -2.7051 180)
			(unlocked yes)
			(layer "B.Fab")
			(hide yes)
			(effects
				(font
					(size 1.016 1.016)
					(thickness 0.1524)
				)
				(justify mirror)
			)
		)
		(property "Device Type" "C402H22"
			(at -1.1811 -4.2291 180)
			(unlocked yes)
			(layer "B.Fab")
			(hide yes)
			(effects
				(font
					(size 1.016 1.016)
					(thickness 0.1524)
				)
				(justify mirror)
			)
		)
		(duplicate_pad_numbers_are_jumpers no)
		(fp_rect
			(start 0.4318 0.9525)
			(end -0.4318 -0.9525)
			(stroke
				(width 0)
				(type default)
			)
			(fill no)
			(layer "B.CrtYd")
		)
		(fp_rect
			(start 0.4318 0.9525)
			(end -0.4318 -0.9525)
			(stroke
				(width 0)
				(type default)
			)
			(fill no)
			(layer "B.Fab")
		)
		(pad "1" smd custom
			(at 0 -0.4445)
			(size 0.1524 0.1524)
			(layers "B.Cu" "B.Mask" "B.Paste")
			(net "P3V3_STBY")
			(options
				(clearance outline)
				(anchor circle)
			)
			(primitives
				(gr_poly
					(pts
						(arc
							(start 0.3048 0.2032)
							(mid 0.275042 0.275042)
							(end 0.2032 0.3048)
						)
						(arc
							(start -0.2032 0.3048)
							(mid -0.275042 0.275042)
							(end -0.3048 0.2032)
						)
						(arc
							(start -0.3048 -0.2032)
							(mid -0.275042 -0.275042)
							(end -0.2032 -0.3048)
						)
						(arc
							(start 0.2032 -0.3048)
							(mid 0.275042 -0.275042)
							(end 0.3048 -0.2032)
						)
					)
					(width 0)
					(fill yes)
				)
			)
		)
		(pad "2" smd custom
			(at 0 0.4445)
			(size 0.1524 0.1524)
			(layers "B.Cu" "B.Mask" "B.Paste")
			(net "GND")
			(options
				(clearance outline)
				(anchor circle)
			)
			(primitives
				(gr_poly
					(pts
						(arc
							(start 0.3048 0.2032)
							(mid 0.275042 0.275042)
							(end 0.2032 0.3048)
						)
						(arc
							(start -0.2032 0.3048)
							(mid -0.275042 0.275042)
							(end -0.3048 0.2032)
						)
						(arc
							(start -0.3048 -0.2032)
							(mid -0.275042 -0.275042)
							(end -0.2032 -0.3048)
						)
						(arc
							(start 0.2032 -0.3048)
							(mid 0.275042 -0.275042)
							(end 0.3048 -0.2032)
						)
					)
					(width 0)
					(fill yes)
				)
			)
		)
	)
	(footprint ""
		(layer "B.Cu")
		(at 50.1396 -163.2712 90)
		(property "Reference" "R191"
			(at 0 0 90)
			(layer "B.SilkS")
			(hide yes)
			(effects
				(font
					(size 1.27 1.27)
				)
				(justify mirror)
			)
		)
		(property "Value" "2K2R2F-GP"
			(at -0.064008 -3.993896 90)
			(unlocked yes)
			(layer "B.Fab")
			(hide yes)
			(effects
				(font
					(size 1.016 1.016)
					(thickness 0.1524)
				)
				(justify mirror)
			)
		)
		(property "Device Type" "R402H16"
			(at -0.064008 -5.517896 90)
			(unlocked yes)
			(layer "B.Fab")
			(hide yes)
			(effects
				(font
					(size 1.016 1.016)
					(thickness 0.1524)
				)
				(justify mirror)
			)
		)
		(duplicate_pad_numbers_are_jumpers no)
		(fp_line
			(start 0.508 -0.9398)
			(end 0.508 0.9398)
			(stroke
				(width 0.1524)
				(type default)
			)
			(layer "B.SilkS")
		)
		(fp_line
			(start -0.508 -0.9398)
			(end 0.508 -0.9398)
			(stroke
				(width 0.1524)
				(type default)
			)
			(layer "B.SilkS")
		)
		(fp_rect
			(start 0.508 0.9398)
			(end -0.508 -0.9398)
			(stroke
				(width 0)
				(type default)
			)
			(fill no)
			(layer "B.CrtYd")
		)
		(fp_rect
			(start 0.508 0.9398)
			(end -0.508 -0.9398)
			(stroke
				(width 0)
				(type default)
			)
			(fill no)
			(layer "B.Fab")
		)
		(pad "1" smd custom
			(at 0 -0.4445 270)
			(size 0.1397 0.1397)
			(layers "B.Cu" "B.Mask" "B.Paste")
			(net "I2C_MEZZ_OOB_SCL")
			(options
				(clearance outline)
				(anchor circle)
			)
			(primitives
				(gr_poly
					(pts
						(arc
							(start -0.1778 0.2794)
							(mid -0.249642 0.249642)
							(end -0.2794 0.1778)
						)
						(arc
							(start -0.2794 -0.1778)
							(mid -0.249642 -0.249642)
							(end -0.1778 -0.2794)
						)
						(arc
							(start 0.1778 -0.2794)
							(mid 0.249642 -0.249642)
							(end 0.2794 -0.1778)
						)
						(arc
							(start 0.2794 0.1778)
							(mid 0.249642 0.249642)
							(end 0.1778 0.2794)
						)
					)
					(width 0)
					(fill yes)
				)
			)
		)
		(pad "2" smd custom
			(at 0 0.4445 270)
			(size 0.1397 0.1397)
			(layers "B.Cu" "B.Mask" "B.Paste")
			(net "P3V3_STBY")
			(options
				(clearance outline)
				(anchor circle)
			)
			(primitives
				(gr_poly
					(pts
						(arc
							(start -0.1778 0.2794)
							(mid -0.249642 0.249642)
							(end -0.2794 0.1778)
						)
						(arc
							(start -0.2794 -0.1778)
							(mid -0.249642 -0.249642)
							(end -0.1778 -0.2794)
						)
						(arc
							(start 0.1778 -0.2794)
							(mid 0.249642 -0.249642)
							(end 0.2794 -0.1778)
						)
						(arc
							(start 0.2794 0.1778)
							(mid 0.249642 0.249642)
							(end 0.1778 0.2794)
						)
					)
					(width 0)
					(fill yes)
				)
			)
		)
	)
	(footprint ""
		(layer "B.Cu")
		(at 90.678 -149.479)
		(property "Reference" "R40"
			(at 0 0 0)
			(layer "B.SilkS")
			(hide yes)
			(effects
				(font
					(size 1.27 1.27)
				)
				(justify mirror)
			)
		)
		(property "Value" "4K7R2F-GP"
			(at -0.064008 -3.993896 0)
			(unlocked yes)
			(layer "B.Fab")
			(hide yes)
			(effects
				(font
					(size 1.016 1.016)
					(thickness 0.1524)
				)
				(justify mirror)
			)
		)
		(property "Device Type" "R402H16"
			(at -0.064008 -5.517896 0)
			(unlocked yes)
			(layer "B.Fab")
			(hide yes)
			(effects
				(font
					(size 1.016 1.016)
					(thickness 0.1524)
				)
				(justify mirror)
			)
		)
		(duplicate_pad_numbers_are_jumpers no)
		(fp_line
			(start -0.508 -0.9398)
			(end 0.508 -0.9398)
			(stroke
				(width 0.1524)
				(type default)
			)
			(layer "B.SilkS")
		)
		(fp_line
			(start 0.508 -0.9398)
			(end 0.508 0.9398)
			(stroke
				(width 0.1524)
				(type default)
			)
			(layer "B.SilkS")
		)
		(fp_rect
			(start 0.508 0.9398)
			(end -0.508 -0.9398)
			(stroke
				(width 0)
				(type default)
			)
			(fill no)
			(layer "B.CrtYd")
		)
		(fp_rect
			(start 0.508 0.9398)
			(end -0.508 -0.9398)
			(stroke
				(width 0)
				(type default)
			)
			(fill no)
			(layer "B.Fab")
		)
		(pad "1" smd custom
			(at 0 -0.4445 180)
			(size 0.1397 0.1397)
			(layers "B.Cu" "B.Mask" "B.Paste")
			(net "USB_EN_1")
			(options
				(clearance outline)
				(anchor circle)
			)
			(primitives
				(gr_poly
					(pts
						(arc
							(start -0.1778 0.2794)
							(mid -0.249642 0.249642)
							(end -0.2794 0.1778)
						)
						(arc
							(start -0.2794 -0.1778)
							(mid -0.249642 -0.249642)
							(end -0.1778 -0.2794)
						)
						(arc
							(start 0.1778 -0.2794)
							(mid 0.249642 -0.249642)
							(end 0.2794 -0.1778)
						)
						(arc
							(start 0.2794 0.1778)
							(mid 0.249642 0.249642)
							(end 0.1778 0.2794)
						)
					)
					(width 0)
					(fill yes)
				)
			)
		)
		(pad "2" smd custom
			(at 0 0.4445 180)
			(size 0.1397 0.1397)
			(layers "B.Cu" "B.Mask" "B.Paste")
			(net "GND")
			(options
				(clearance outline)
				(anchor circle)
			)
			(primitives
				(gr_poly
					(pts
						(arc
							(start -0.1778 0.2794)
							(mid -0.249642 0.249642)
							(end -0.2794 0.1778)
						)
						(arc
							(start -0.2794 -0.1778)
							(mid -0.249642 -0.249642)
							(end -0.1778 -0.2794)
						)
						(arc
							(start 0.1778 -0.2794)
							(mid 0.249642 -0.249642)
							(end 0.2794 -0.1778)
						)
						(arc
							(start 0.2794 0.1778)
							(mid 0.249642 0.249642)
							(end 0.1778 0.2794)
						)
					)
					(width 0)
					(fill yes)
				)
			)
		)
	)
	(footprint ""
		(layer "B.Cu")
		(at 48.14443 -163.240974 90)
		(property "Reference" "R192"
			(at 0 0 90)
			(layer "B.SilkS")
			(hide yes)
			(effects
				(font
					(size 1.27 1.27)
				)
				(justify mirror)
			)
		)
		(property "Value" "2K2R2F-GP"
			(at -0.064008 -3.993896 90)
			(unlocked yes)
			(layer "B.Fab")
			(hide yes)
			(effects
				(font
					(size 1.016 1.016)
					(thickness 0.1524)
				)
				(justify mirror)
			)
		)
		(property "Device Type" "R402H16"
			(at -0.064008 -5.517896 90)
			(unlocked yes)
			(layer "B.Fab")
			(hide yes)
			(effects
				(font
					(size 1.016 1.016)
					(thickness 0.1524)
				)
				(justify mirror)
			)
		)
		(duplicate_pad_numbers_are_jumpers no)
		(fp_line
			(start 0.508 -0.9398)
			(end 0.508 0.9398)
			(stroke
				(width 0.1524)
				(type default)
			)
			(layer "B.SilkS")
		)
		(fp_line
			(start -0.508 -0.9398)
			(end 0.508 -0.9398)
			(stroke
				(width 0.1524)
				(type default)
			)
			(layer "B.SilkS")
		)
		(fp_rect
			(start 0.508 0.9398)
			(end -0.508 -0.9398)
			(stroke
				(width 0)
				(type default)
			)
			(fill no)
			(layer "B.CrtYd")
		)
		(fp_rect
			(start 0.508 0.9398)
			(end -0.508 -0.9398)
			(stroke
				(width 0)
				(type default)
			)
			(fill no)
			(layer "B.Fab")
		)
		(pad "1" smd custom
			(at 0 -0.4445 270)
			(size 0.1397 0.1397)
			(layers "B.Cu" "B.Mask" "B.Paste")
			(net "I2C_MEZZ_OOB_SDA")
			(options
				(clearance outline)
				(anchor circle)
			)
			(primitives
				(gr_poly
					(pts
						(arc
							(start -0.1778 0.2794)
							(mid -0.249642 0.249642)
							(end -0.2794 0.1778)
						)
						(arc
							(start -0.2794 -0.1778)
							(mid -0.249642 -0.249642)
							(end -0.1778 -0.2794)
						)
						(arc
							(start 0.1778 -0.2794)
							(mid 0.249642 -0.249642)
							(end 0.2794 -0.1778)
						)
						(arc
							(start 0.2794 0.1778)
							(mid 0.249642 0.249642)
							(end 0.1778 0.2794)
						)
					)
					(width 0)
					(fill yes)
				)
			)
		)
		(pad "2" smd custom
			(at 0 0.4445 270)
			(size 0.1397 0.1397)
			(layers "B.Cu" "B.Mask" "B.Paste")
			(net "P3V3_STBY")
			(options
				(clearance outline)
				(anchor circle)
			)
			(primitives
				(gr_poly
					(pts
						(arc
							(start -0.1778 0.2794)
							(mid -0.249642 0.249642)
							(end -0.2794 0.1778)
						)
						(arc
							(start -0.2794 -0.1778)
							(mid -0.249642 -0.249642)
							(end -0.1778 -0.2794)
						)
						(arc
							(start 0.1778 -0.2794)
							(mid 0.249642 -0.249642)
							(end 0.2794 -0.1778)
						)
						(arc
							(start 0.2794 0.1778)
							(mid 0.249642 0.249642)
							(end 0.1778 0.2794)
						)
					)
					(width 0)
					(fill yes)
				)
			)
		)
	)
	(footprint ""
		(layer "B.Cu")
		(at 218.568016 -43.445176)
		(property "Reference" "R466"
			(at 0 0 0)
			(layer "B.SilkS")
			(hide yes)
			(effects
				(font
					(size 1.27 1.27)
				)
				(justify mirror)
			)
		)
		(property "Value" "2D7R3-GP"
			(at 0.0254 -2.5146 0)
			(unlocked yes)
			(layer "B.Fab")
			(hide yes)
			(effects
				(font
					(size 1.016 1.016)
					(thickness 0.1524)
				)
				(justify mirror)
			)
		)
		(property "Device Type" "R603H22"
			(at 0.0254 -4.0386 0)
			(unlocked yes)
			(layer "B.Fab")
			(hide yes)
			(effects
				(font
					(size 1.016 1.016)
					(thickness 0.1524)
				)
				(justify mirror)
			)
		)
		(duplicate_pad_numbers_are_jumpers no)
		(fp_line
			(start -0.2032 0)
			(end -0.4826 0)
			(stroke
				(width 0.2032)
				(type default)
			)
			(layer "B.SilkS")
		)
		(fp_line
			(start 0.4826 0)
			(end 0.2032 0)
			(stroke
				(width 0.2032)
				(type default)
			)
			(layer "B.SilkS")
		)
		(fp_rect
			(start 0.5842 1.3335)
			(end -0.5842 -1.3335)
			(stroke
				(width 0)
				(type default)
			)
			(fill no)
			(layer "B.CrtYd")
		)
		(fp_rect
			(start 0.5842 1.3335)
			(end -0.5842 -1.3335)
			(stroke
				(width 0)
				(type default)
			)
			(fill no)
			(layer "B.Fab")
		)
		(pad "1" smd custom
			(at 0 -0.762 180)
			(size 0.2159 0.2159)
			(layers "B.Cu" "B.Mask" "B.Paste")
			(net "P5V_VBST")
			(options
				(clearance outline)
				(anchor circle)
			)
			(primitives
				(gr_poly
					(pts
						(arc
							(start -0.3302 0.4318)
							(mid -0.402042 0.402042)
							(end -0.4318 0.3302)
						)
						(arc
							(start -0.4318 -0.3302)
							(mid -0.402042 -0.402042)
							(end -0.3302 -0.4318)
						)
						(arc
							(start 0.3302 -0.4318)
							(mid 0.402042 -0.402042)
							(end 0.4318 -0.3302)
						)
						(arc
							(start 0.4318 0.3302)
							(mid 0.402042 0.402042)
							(end 0.3302 0.4318)
						)
					)
					(width 0)
					(fill yes)
				)
			)
		)
		(pad "2" smd custom
			(at 0 0.762 180)
			(size 0.2159 0.2159)
			(layers "B.Cu" "B.Mask" "B.Paste")
			(net "P5V_VBST_RC")
			(options
				(clearance outline)
				(anchor circle)
			)
			(primitives
				(gr_poly
					(pts
						(arc
							(start -0.3302 0.4318)
							(mid -0.402042 0.402042)
							(end -0.4318 0.3302)
						)
						(arc
							(start -0.4318 -0.3302)
							(mid -0.402042 -0.402042)
							(end -0.3302 -0.4318)
						)
						(arc
							(start 0.3302 -0.4318)
							(mid 0.402042 -0.402042)
							(end 0.4318 -0.3302)
						)
						(arc
							(start 0.4318 0.3302)
							(mid 0.402042 0.402042)
							(end 0.3302 0.4318)
						)
					)
					(width 0)
					(fill yes)
				)
			)
		)
	)
	(footprint ""
		(layer "B.Cu")
		(at 46.10227 -146.962114)
		(property "Reference" "C108"
			(at 0 0 0)
			(layer "B.SilkS")
			(hide yes)
			(effects
				(font
					(size 1.27 1.27)
				)
				(justify mirror)
			)
		)
		(property "Value" "SC1U16V3KX-5GP"
			(at 0 -2.8194 0)
			(unlocked yes)
			(layer "B.Fab")
			(hide yes)
			(effects
				(font
					(size 1.016 1.016)
					(thickness 0.1524)
				)
				(justify mirror)
			)
		)
		(property "Device Type" "C603H36"
			(at 0 -4.3434 0)
			(unlocked yes)
			(layer "B.Fab")
			(hide yes)
			(effects
				(font
					(size 1.016 1.016)
					(thickness 0.1524)
				)
				(justify mirror)
			)
		)
		(duplicate_pad_numbers_are_jumpers no)
		(fp_line
			(start -0.508 0)
			(end 0.508 0)
			(stroke
				(width 0.2032)
				(type default)
			)
			(layer "B.SilkS")
		)
		(fp_rect
			(start 0.5842 1.3335)
			(end -0.5842 -1.3335)
			(stroke
				(width 0)
				(type default)
			)
			(fill no)
			(layer "B.CrtYd")
		)
		(fp_rect
			(start 0.5842 1.3335)
			(end -0.5842 -1.3335)
			(stroke
				(width 0)
				(type default)
			)
			(fill no)
			(layer "B.Fab")
		)
		(pad "1" smd custom
			(at 0 -0.762 180)
			(size 0.2159 0.2159)
			(layers "B.Cu" "B.Mask" "B.Paste")
			(net "P1V15_STBY")
			(options
				(clearance outline)
				(anchor circle)
			)
			(primitives
				(gr_poly
					(pts
						(arc
							(start -0.3302 0.4318)
							(mid -0.402042 0.402042)
							(end -0.4318 0.3302)
						)
						(arc
							(start -0.4318 -0.3302)
							(mid -0.402042 -0.402042)
							(end -0.3302 -0.4318)
						)
						(arc
							(start 0.3302 -0.4318)
							(mid 0.402042 -0.402042)
							(end 0.4318 -0.3302)
						)
						(arc
							(start 0.4318 0.3302)
							(mid 0.402042 0.402042)
							(end 0.3302 0.4318)
						)
					)
					(width 0)
					(fill yes)
				)
			)
		)
		(pad "2" smd custom
			(at 0 0.762 180)
			(size 0.2159 0.2159)
			(layers "B.Cu" "B.Mask" "B.Paste")
			(net "GND")
			(options
				(clearance outline)
				(anchor circle)
			)
			(primitives
				(gr_poly
					(pts
						(arc
							(start -0.3302 0.4318)
							(mid -0.402042 0.402042)
							(end -0.4318 0.3302)
						)
						(arc
							(start -0.4318 -0.3302)
							(mid -0.402042 -0.402042)
							(end -0.3302 -0.4318)
						)
						(arc
							(start 0.3302 -0.4318)
							(mid 0.402042 -0.402042)
							(end 0.4318 -0.3302)
						)
						(arc
							(start 0.4318 0.3302)
							(mid 0.402042 0.402042)
							(end 0.3302 0.4318)
						)
					)
					(width 0)
					(fill yes)
				)
			)
		)
	)
	(footprint ""
		(layer "B.Cu")
		(at 193.29527 -136.854438 90)
		(property "Reference" "R808"
			(at 0 0 90)
			(layer "B.SilkS")
			(hide yes)
			(effects
				(font
					(size 1.27 1.27)
				)
				(justify mirror)
			)
		)
		(property "Value" "0R2J-2-GP"
			(at -0.064008 -3.993896 90)
			(unlocked yes)
			(layer "B.Fab")
			(hide yes)
			(effects
				(font
					(size 1.016 1.016)
					(thickness 0.1524)
				)
				(justify mirror)
			)
		)
		(property "Device Type" "R402H16"
			(at -0.064008 -5.517896 90)
			(unlocked yes)
			(layer "B.Fab")
			(hide yes)
			(effects
				(font
					(size 1.016 1.016)
					(thickness 0.1524)
				)
				(justify mirror)
			)
		)
		(duplicate_pad_numbers_are_jumpers no)
		(fp_line
			(start 0.508 -0.9398)
			(end 0.508 0.9398)
			(stroke
				(width 0.1524)
				(type default)
			)
			(layer "B.SilkS")
		)
		(fp_line
			(start -0.508 -0.9398)
			(end 0.508 -0.9398)
			(stroke
				(width 0.1524)
				(type default)
			)
			(layer "B.SilkS")
		)
		(fp_rect
			(start 0.508 0.9398)
			(end -0.508 -0.9398)
			(stroke
				(width 0)
				(type default)
			)
			(fill no)
			(layer "B.CrtYd")
		)
		(fp_rect
			(start 0.508 0.9398)
			(end -0.508 -0.9398)
			(stroke
				(width 0)
				(type default)
			)
			(fill no)
			(layer "B.Fab")
		)
		(pad "1" smd custom
			(at 0 -0.4445 270)
			(size 0.1397 0.1397)
			(layers "B.Cu" "B.Mask" "B.Paste")
			(net "M2_1_PRESENT_N")
			(options
				(clearance outline)
				(anchor circle)
			)
			(primitives
				(gr_poly
					(pts
						(arc
							(start -0.1778 0.2794)
							(mid -0.249642 0.249642)
							(end -0.2794 0.1778)
						)
						(arc
							(start -0.2794 -0.1778)
							(mid -0.249642 -0.249642)
							(end -0.1778 -0.2794)
						)
						(arc
							(start 0.1778 -0.2794)
							(mid 0.249642 -0.249642)
							(end 0.2794 -0.1778)
						)
						(arc
							(start 0.2794 0.1778)
							(mid 0.249642 0.249642)
							(end 0.1778 0.2794)
						)
					)
					(width 0)
					(fill yes)
				)
			)
		)
		(pad "2" smd custom
			(at 0 0.4445 270)
			(size 0.1397 0.1397)
			(layers "B.Cu" "B.Mask" "B.Paste")
			(net "M2_1_PRESENT_N_R")
			(options
				(clearance outline)
				(anchor circle)
			)
			(primitives
				(gr_poly
					(pts
						(arc
							(start -0.1778 0.2794)
							(mid -0.249642 0.249642)
							(end -0.2794 0.1778)
						)
						(arc
							(start -0.2794 -0.1778)
							(mid -0.249642 -0.249642)
							(end -0.1778 -0.2794)
						)
						(arc
							(start 0.1778 -0.2794)
							(mid 0.249642 -0.249642)
							(end 0.2794 -0.1778)
						)
						(arc
							(start 0.2794 0.1778)
							(mid 0.249642 0.249642)
							(end 0.1778 0.2794)
						)
					)
					(width 0)
					(fill yes)
				)
			)
		)
	)
	(footprint ""
		(layer "B.Cu")
		(at 47.34814 -156.892752 90)
		(property "Reference" "R324"
			(at 0 0 90)
			(layer "B.SilkS")
			(hide yes)
			(effects
				(font
					(size 1.27 1.27)
				)
				(justify mirror)
			)
		)
		(property "Value" "4K7R2F-GP"
			(at -0.064008 -3.993896 90)
			(unlocked yes)
			(layer "B.Fab")
			(hide yes)
			(effects
				(font
					(size 1.016 1.016)
					(thickness 0.1524)
				)
				(justify mirror)
			)
		)
		(property "Device Type" "R402H16"
			(at -0.064008 -5.517896 90)
			(unlocked yes)
			(layer "B.Fab")
			(hide yes)
			(effects
				(font
					(size 1.016 1.016)
					(thickness 0.1524)
				)
				(justify mirror)
			)
		)
		(duplicate_pad_numbers_are_jumpers no)
		(fp_line
			(start 0.508 -0.9398)
			(end 0.508 0.9398)
			(stroke
				(width 0.1524)
				(type default)
			)
			(layer "B.SilkS")
		)
		(fp_line
			(start -0.508 -0.9398)
			(end 0.508 -0.9398)
			(stroke
				(width 0.1524)
				(type default)
			)
			(layer "B.SilkS")
		)
		(fp_rect
			(start 0.508 0.9398)
			(end -0.508 -0.9398)
			(stroke
				(width 0)
				(type default)
			)
			(fill no)
			(layer "B.CrtYd")
		)
		(fp_rect
			(start 0.508 0.9398)
			(end -0.508 -0.9398)
			(stroke
				(width 0)
				(type default)
			)
			(fill no)
			(layer "B.Fab")
		)
		(pad "1" smd custom
			(at 0 -0.4445 270)
			(size 0.1397 0.1397)
			(layers "B.Cu" "B.Mask" "B.Paste")
			(net "BOARD_REV_2")
			(options
				(clearance outline)
				(anchor circle)
			)
			(primitives
				(gr_poly
					(pts
						(arc
							(start -0.1778 0.2794)
							(mid -0.249642 0.249642)
							(end -0.2794 0.1778)
						)
						(arc
							(start -0.2794 -0.1778)
							(mid -0.249642 -0.249642)
							(end -0.1778 -0.2794)
						)
						(arc
							(start 0.1778 -0.2794)
							(mid 0.249642 -0.249642)
							(end 0.2794 -0.1778)
						)
						(arc
							(start 0.2794 0.1778)
							(mid 0.249642 0.249642)
							(end 0.1778 0.2794)
						)
					)
					(width 0)
					(fill yes)
				)
			)
		)
		(pad "2" smd custom
			(at 0 0.4445 270)
			(size 0.1397 0.1397)
			(layers "B.Cu" "B.Mask" "B.Paste")
			(net "GND")
			(options
				(clearance outline)
				(anchor circle)
			)
			(primitives
				(gr_poly
					(pts
						(arc
							(start -0.1778 0.2794)
							(mid -0.249642 0.249642)
							(end -0.2794 0.1778)
						)
						(arc
							(start -0.2794 -0.1778)
							(mid -0.249642 -0.249642)
							(end -0.1778 -0.2794)
						)
						(arc
							(start 0.1778 -0.2794)
							(mid 0.249642 -0.249642)
							(end 0.2794 -0.1778)
						)
						(arc
							(start 0.2794 0.1778)
							(mid 0.249642 0.249642)
							(end 0.1778 0.2794)
						)
					)
					(width 0)
					(fill yes)
				)
			)
		)
	)
	(footprint ""
		(layer "B.Cu")
		(at 48.8442 -124.9172 180)
		(property "Reference" "R286"
			(at 0 0 0)
			(layer "B.SilkS")
			(hide yes)
			(effects
				(font
					(size 1.27 1.27)
				)
				(justify mirror)
			)
		)
		(property "Value" "0R2J-2-GP"
			(at -0.064008 -3.993896 180)
			(unlocked yes)
			(layer "B.Fab")
			(hide yes)
			(effects
				(font
					(size 1.016 1.016)
					(thickness 0.1524)
				)
				(justify mirror)
			)
		)
		(property "Device Type" "R402H16"
			(at -0.064008 -5.517896 180)
			(unlocked yes)
			(layer "B.Fab")
			(hide yes)
			(effects
				(font
					(size 1.016 1.016)
					(thickness 0.1524)
				)
				(justify mirror)
			)
		)
		(duplicate_pad_numbers_are_jumpers no)
		(fp_line
			(start 0.508 -0.9398)
			(end 0.508 0.9398)
			(stroke
				(width 0.1524)
				(type default)
			)
			(layer "B.SilkS")
		)
		(fp_line
			(start -0.508 -0.9398)
			(end 0.508 -0.9398)
			(stroke
				(width 0.1524)
				(type default)
			)
			(layer "B.SilkS")
		)
		(fp_rect
			(start 0.508 0.9398)
			(end -0.508 -0.9398)
			(stroke
				(width 0)
				(type default)
			)
			(fill no)
			(layer "B.CrtYd")
		)
		(fp_rect
			(start 0.508 0.9398)
			(end -0.508 -0.9398)
			(stroke
				(width 0)
				(type default)
			)
			(fill no)
			(layer "B.Fab")
		)
		(pad "1" smd custom
			(at 0 -0.4445)
			(size 0.1397 0.1397)
			(layers "B.Cu" "B.Mask" "B.Paste")
			(net "SCC_LOC_FULL_PWR_EN")
			(options
				(clearance outline)
				(anchor circle)
			)
			(primitives
				(gr_poly
					(pts
						(arc
							(start -0.1778 0.2794)
							(mid -0.249642 0.249642)
							(end -0.2794 0.1778)
						)
						(arc
							(start -0.2794 -0.1778)
							(mid -0.249642 -0.249642)
							(end -0.1778 -0.2794)
						)
						(arc
							(start 0.1778 -0.2794)
							(mid 0.249642 -0.249642)
							(end 0.2794 -0.1778)
						)
						(arc
							(start 0.2794 0.1778)
							(mid 0.249642 0.249642)
							(end 0.1778 0.2794)
						)
					)
					(width 0)
					(fill yes)
				)
			)
		)
		(pad "2" smd custom
			(at 0 0.4445)
			(size 0.1397 0.1397)
			(layers "B.Cu" "B.Mask" "B.Paste")
			(net "SCC_LOC_FULLPWR_EN")
			(options
				(clearance outline)
				(anchor circle)
			)
			(primitives
				(gr_poly
					(pts
						(arc
							(start -0.1778 0.2794)
							(mid -0.249642 0.249642)
							(end -0.2794 0.1778)
						)
						(arc
							(start -0.2794 -0.1778)
							(mid -0.249642 -0.249642)
							(end -0.1778 -0.2794)
						)
						(arc
							(start 0.1778 -0.2794)
							(mid 0.249642 -0.249642)
							(end 0.2794 -0.1778)
						)
						(arc
							(start 0.2794 0.1778)
							(mid 0.249642 0.249642)
							(end 0.1778 0.2794)
						)
					)
					(width 0)
					(fill yes)
				)
			)
		)
	)
	(footprint ""
		(layer "B.Cu")
		(at 34.404046 -142.938246 180)
		(property "Reference" "C57"
			(at 0 0 0)
			(layer "B.SilkS")
			(hide yes)
			(effects
				(font
					(size 1.27 1.27)
				)
				(justify mirror)
			)
		)
		(property "Value" "SC10U6D3V5KX-4GP"
			(at 0.0762 -6.1214 180)
			(unlocked yes)
			(layer "B.Fab")
			(hide yes)
			(effects
				(font
					(size 1.016 1.016)
					(thickness 0.1524)
				)
				(justify mirror)
			)
		)
		(property "Device Type" "C805H58"
			(at 0.0762 -8.1534 180)
			(unlocked yes)
			(layer "B.Fab")
			(hide yes)
			(effects
				(font
					(size 1.016 1.016)
					(thickness 0.1524)
				)
				(justify mirror)
			)
		)
		(duplicate_pad_numbers_are_jumpers no)
		(fp_line
			(start -0.635 0)
			(end 0.635 0)
			(stroke
				(width 0.508)
				(type default)
			)
			(layer "B.SilkS")
		)
		(fp_rect
			(start 0.9652 1.778)
			(end -0.9652 -1.778)
			(stroke
				(width 0)
				(type default)
			)
			(fill no)
			(layer "B.CrtYd")
		)
		(fp_poly
			(pts
				(xy 0.9652 -1.778) (xy -0.9652 -1.778) (xy -0.9652 1.778) (xy 0.9652 1.778)
			)
			(stroke
				(width 0)
				(type default)
			)
			(fill no)
			(layer "B.Fab")
		)
		(pad "1" smd rect
			(at 0 -0.9652)
			(size 1.397 1.143)
			(layers "B.Cu" "B.Mask" "B.Paste")
			(net "GND")
		)
		(pad "2" smd rect
			(at 0 0.9652)
			(size 1.397 1.143)
			(layers "B.Cu" "B.Mask" "B.Paste")
			(net "P1V2_STBY")
		)
	)
	(footprint ""
		(layer "B.Cu")
		(at 61.4934 -148.5138 180)
		(property "Reference" "R389"
			(at 0 0 0)
			(layer "B.SilkS")
			(hide yes)
			(effects
				(font
					(size 1.27 1.27)
				)
				(justify mirror)
			)
		)
		(property "Value" "4K7R2F-GP"
			(at -0.064008 -3.993896 180)
			(unlocked yes)
			(layer "B.Fab")
			(hide yes)
			(effects
				(font
					(size 1.016 1.016)
					(thickness 0.1524)
				)
				(justify mirror)
			)
		)
		(property "Device Type" "R402H16"
			(at -0.064008 -5.517896 180)
			(unlocked yes)
			(layer "B.Fab")
			(hide yes)
			(effects
				(font
					(size 1.016 1.016)
					(thickness 0.1524)
				)
				(justify mirror)
			)
		)
		(duplicate_pad_numbers_are_jumpers no)
		(fp_line
			(start 0.508 -0.9398)
			(end 0.508 0.9398)
			(stroke
				(width 0.1524)
				(type default)
			)
			(layer "B.SilkS")
		)
		(fp_line
			(start -0.508 -0.9398)
			(end 0.508 -0.9398)
			(stroke
				(width 0.1524)
				(type default)
			)
			(layer "B.SilkS")
		)
		(fp_rect
			(start 0.508 0.9398)
			(end -0.508 -0.9398)
			(stroke
				(width 0)
				(type default)
			)
			(fill no)
			(layer "B.CrtYd")
		)
		(fp_rect
			(start 0.508 0.9398)
			(end -0.508 -0.9398)
			(stroke
				(width 0)
				(type default)
			)
			(fill no)
			(layer "B.Fab")
		)
		(pad "1" smd custom
			(at 0 -0.4445)
			(size 0.1397 0.1397)
			(layers "B.Cu" "B.Mask" "B.Paste")
			(net "GND")
			(options
				(clearance outline)
				(anchor circle)
			)
			(primitives
				(gr_poly
					(pts
						(arc
							(start -0.1778 0.2794)
							(mid -0.249642 0.249642)
							(end -0.2794 0.1778)
						)
						(arc
							(start -0.2794 -0.1778)
							(mid -0.249642 -0.249642)
							(end -0.1778 -0.2794)
						)
						(arc
							(start 0.1778 -0.2794)
							(mid 0.249642 -0.249642)
							(end 0.2794 -0.1778)
						)
						(arc
							(start 0.2794 0.1778)
							(mid 0.249642 0.249642)
							(end 0.1778 0.2794)
						)
					)
					(width 0)
					(fill yes)
				)
			)
		)
		(pad "2" smd custom
			(at 0 0.4445)
			(size 0.1397 0.1397)
			(layers "B.Cu" "B.Mask" "B.Paste")
			(net "MAC1_TXD3")
			(options
				(clearance outline)
				(anchor circle)
			)
			(primitives
				(gr_poly
					(pts
						(arc
							(start -0.1778 0.2794)
							(mid -0.249642 0.249642)
							(end -0.2794 0.1778)
						)
						(arc
							(start -0.2794 -0.1778)
							(mid -0.249642 -0.249642)
							(end -0.1778 -0.2794)
						)
						(arc
							(start 0.1778 -0.2794)
							(mid 0.249642 -0.249642)
							(end 0.2794 -0.1778)
						)
						(arc
							(start 0.2794 0.1778)
							(mid 0.249642 0.249642)
							(end 0.1778 0.2794)
						)
					)
					(width 0)
					(fill yes)
				)
			)
		)
	)
	(footprint ""
		(layer "B.Cu")
		(at 10.20699 -141.008862 90)
		(property "Reference" "R254"
			(at 0 0 90)
			(layer "B.SilkS")
			(hide yes)
			(effects
				(font
					(size 1.27 1.27)
				)
				(justify mirror)
			)
		)
		(property "Value" "120R2F-GP"
			(at -0.064008 -3.993896 90)
			(unlocked yes)
			(layer "B.Fab")
			(hide yes)
			(effects
				(font
					(size 1.016 1.016)
					(thickness 0.1524)
				)
				(justify mirror)
			)
		)
		(property "Device Type" "R402H16"
			(at -0.064008 -5.517896 90)
			(unlocked yes)
			(layer "B.Fab")
			(hide yes)
			(effects
				(font
					(size 1.016 1.016)
					(thickness 0.1524)
				)
				(justify mirror)
			)
		)
		(duplicate_pad_numbers_are_jumpers no)
		(fp_line
			(start 0.508 -0.9398)
			(end 0.508 0.9398)
			(stroke
				(width 0.1524)
				(type default)
			)
			(layer "B.SilkS")
		)
		(fp_line
			(start -0.508 -0.9398)
			(end 0.508 -0.9398)
			(stroke
				(width 0.1524)
				(type default)
			)
			(layer "B.SilkS")
		)
		(fp_rect
			(start 0.508 0.9398)
			(end -0.508 -0.9398)
			(stroke
				(width 0)
				(type default)
			)
			(fill no)
			(layer "B.CrtYd")
		)
		(fp_rect
			(start 0.508 0.9398)
			(end -0.508 -0.9398)
			(stroke
				(width 0)
				(type default)
			)
			(fill no)
			(layer "B.Fab")
		)
		(pad "1" smd custom
			(at 0 -0.4445 270)
			(size 0.1397 0.1397)
			(layers "B.Cu" "B.Mask" "B.Paste")
			(net "GND")
			(options
				(clearance outline)
				(anchor circle)
			)
			(primitives
				(gr_poly
					(pts
						(arc
							(start -0.1778 0.2794)
							(mid -0.249642 0.249642)
							(end -0.2794 0.1778)
						)
						(arc
							(start -0.2794 -0.1778)
							(mid -0.249642 -0.249642)
							(end -0.1778 -0.2794)
						)
						(arc
							(start 0.1778 -0.2794)
							(mid 0.249642 -0.249642)
							(end 0.2794 -0.1778)
						)
						(arc
							(start 0.2794 0.1778)
							(mid 0.249642 0.249642)
							(end 0.1778 0.2794)
						)
					)
					(width 0)
					(fill yes)
				)
			)
		)
		(pad "2" smd custom
			(at 0 0.4445 270)
			(size 0.1397 0.1397)
			(layers "B.Cu" "B.Mask" "B.Paste")
			(net "MEMA_10")
			(options
				(clearance outline)
				(anchor circle)
			)
			(primitives
				(gr_poly
					(pts
						(arc
							(start -0.1778 0.2794)
							(mid -0.249642 0.249642)
							(end -0.2794 0.1778)
						)
						(arc
							(start -0.2794 -0.1778)
							(mid -0.249642 -0.249642)
							(end -0.1778 -0.2794)
						)
						(arc
							(start 0.1778 -0.2794)
							(mid 0.249642 -0.249642)
							(end 0.2794 -0.1778)
						)
						(arc
							(start 0.2794 0.1778)
							(mid 0.249642 0.249642)
							(end 0.1778 0.2794)
						)
					)
					(width 0)
					(fill yes)
				)
			)
		)
	)
	(footprint ""
		(layer "B.Cu")
		(at 13.323824 -145.23593 90)
		(property "Reference" "R209"
			(at 0 0 90)
			(layer "B.SilkS")
			(hide yes)
			(effects
				(font
					(size 1.27 1.27)
				)
				(justify mirror)
			)
		)
		(property "Value" "120R2F-GP"
			(at -0.064008 -3.993896 90)
			(unlocked yes)
			(layer "B.Fab")
			(hide yes)
			(effects
				(font
					(size 1.016 1.016)
					(thickness 0.1524)
				)
				(justify mirror)
			)
		)
		(property "Device Type" "R402H16"
			(at -0.064008 -5.517896 90)
			(unlocked yes)
			(layer "B.Fab")
			(hide yes)
			(effects
				(font
					(size 1.016 1.016)
					(thickness 0.1524)
				)
				(justify mirror)
			)
		)
		(duplicate_pad_numbers_are_jumpers no)
		(fp_line
			(start 0.508 -0.9398)
			(end 0.508 0.9398)
			(stroke
				(width 0.1524)
				(type default)
			)
			(layer "B.SilkS")
		)
		(fp_line
			(start -0.508 -0.9398)
			(end 0.508 -0.9398)
			(stroke
				(width 0.1524)
				(type default)
			)
			(layer "B.SilkS")
		)
		(fp_rect
			(start 0.508 0.9398)
			(end -0.508 -0.9398)
			(stroke
				(width 0)
				(type default)
			)
			(fill no)
			(layer "B.CrtYd")
		)
		(fp_rect
			(start 0.508 0.9398)
			(end -0.508 -0.9398)
			(stroke
				(width 0)
				(type default)
			)
			(fill no)
			(layer "B.Fab")
		)
		(pad "1" smd custom
			(at 0 -0.4445 270)
			(size 0.1397 0.1397)
			(layers "B.Cu" "B.Mask" "B.Paste")
			(net "GND")
			(options
				(clearance outline)
				(anchor circle)
			)
			(primitives
				(gr_poly
					(pts
						(arc
							(start -0.1778 0.2794)
							(mid -0.249642 0.249642)
							(end -0.2794 0.1778)
						)
						(arc
							(start -0.2794 -0.1778)
							(mid -0.249642 -0.249642)
							(end -0.1778 -0.2794)
						)
						(arc
							(start 0.1778 -0.2794)
							(mid 0.249642 -0.249642)
							(end 0.2794 -0.1778)
						)
						(arc
							(start 0.2794 0.1778)
							(mid 0.249642 0.249642)
							(end 0.1778 0.2794)
						)
					)
					(width 0)
					(fill yes)
				)
			)
		)
		(pad "2" smd custom
			(at 0 0.4445 270)
			(size 0.1397 0.1397)
			(layers "B.Cu" "B.Mask" "B.Paste")
			(net "MEMCKE")
			(options
				(clearance outline)
				(anchor circle)
			)
			(primitives
				(gr_poly
					(pts
						(arc
							(start -0.1778 0.2794)
							(mid -0.249642 0.249642)
							(end -0.2794 0.1778)
						)
						(arc
							(start -0.2794 -0.1778)
							(mid -0.249642 -0.249642)
							(end -0.1778 -0.2794)
						)
						(arc
							(start 0.1778 -0.2794)
							(mid 0.249642 -0.249642)
							(end 0.2794 -0.1778)
						)
						(arc
							(start 0.2794 0.1778)
							(mid 0.249642 0.249642)
							(end 0.1778 0.2794)
						)
					)
					(width 0)
					(fill yes)
				)
			)
		)
	)
	(footprint ""
		(layer "B.Cu")
		(at 72.780144 -151.998426 -90)
		(property "Reference" "C41"
			(at 0 0 90)
			(layer "B.SilkS")
			(hide yes)
			(effects
				(font
					(size 1.27 1.27)
				)
				(justify mirror)
			)
		)
		(property "Value" "SCD1U16V2KX-3GP"
			(at -1.1811 -2.7051 270)
			(unlocked yes)
			(layer "B.Fab")
			(hide yes)
			(effects
				(font
					(size 1.016 1.016)
					(thickness 0.1524)
				)
				(justify mirror)
			)
		)
		(property "Device Type" "C402H22"
			(at -1.1811 -4.2291 270)
			(unlocked yes)
			(layer "B.Fab")
			(hide yes)
			(effects
				(font
					(size 1.016 1.016)
					(thickness 0.1524)
				)
				(justify mirror)
			)
		)
		(duplicate_pad_numbers_are_jumpers no)
		(fp_rect
			(start 0.4318 0.9525)
			(end -0.4318 -0.9525)
			(stroke
				(width 0)
				(type default)
			)
			(fill no)
			(layer "B.CrtYd")
		)
		(fp_rect
			(start 0.4318 0.9525)
			(end -0.4318 -0.9525)
			(stroke
				(width 0)
				(type default)
			)
			(fill no)
			(layer "B.Fab")
		)
		(pad "1" smd custom
			(at 0 -0.4445 90)
			(size 0.1524 0.1524)
			(layers "B.Cu" "B.Mask" "B.Paste")
			(net "P3V3_STBY")
			(options
				(clearance outline)
				(anchor circle)
			)
			(primitives
				(gr_poly
					(pts
						(arc
							(start 0.3048 0.2032)
							(mid 0.275042 0.275042)
							(end 0.2032 0.3048)
						)
						(arc
							(start -0.2032 0.3048)
							(mid -0.275042 0.275042)
							(end -0.3048 0.2032)
						)
						(arc
							(start -0.3048 -0.2032)
							(mid -0.275042 -0.275042)
							(end -0.2032 -0.3048)
						)
						(arc
							(start 0.2032 -0.3048)
							(mid 0.275042 -0.275042)
							(end 0.3048 -0.2032)
						)
					)
					(width 0)
					(fill yes)
				)
			)
		)
		(pad "2" smd custom
			(at 0 0.4445 90)
			(size 0.1524 0.1524)
			(layers "B.Cu" "B.Mask" "B.Paste")
			(net "GND")
			(options
				(clearance outline)
				(anchor circle)
			)
			(primitives
				(gr_poly
					(pts
						(arc
							(start 0.3048 0.2032)
							(mid 0.275042 0.275042)
							(end 0.2032 0.3048)
						)
						(arc
							(start -0.2032 0.3048)
							(mid -0.275042 0.275042)
							(end -0.3048 0.2032)
						)
						(arc
							(start -0.3048 -0.2032)
							(mid -0.275042 -0.275042)
							(end -0.2032 -0.3048)
						)
						(arc
							(start 0.2032 -0.3048)
							(mid 0.275042 -0.275042)
							(end 0.3048 -0.2032)
						)
					)
					(width 0)
					(fill yes)
				)
			)
		)
	)
	(footprint ""
		(layer "B.Cu")
		(at 24.8666 -129.1082 180)
		(property "Reference" "R244"
			(at 0 0 0)
			(layer "B.SilkS")
			(hide yes)
			(effects
				(font
					(size 1.27 1.27)
				)
				(justify mirror)
			)
		)
		(property "Value" "120R2F-GP"
			(at -0.064008 -3.993896 180)
			(unlocked yes)
			(layer "B.Fab")
			(hide yes)
			(effects
				(font
					(size 1.016 1.016)
					(thickness 0.1524)
				)
				(justify mirror)
			)
		)
		(property "Device Type" "R402H16"
			(at -0.064008 -5.517896 180)
			(unlocked yes)
			(layer "B.Fab")
			(hide yes)
			(effects
				(font
					(size 1.016 1.016)
					(thickness 0.1524)
				)
				(justify mirror)
			)
		)
		(duplicate_pad_numbers_are_jumpers no)
		(fp_line
			(start 0.508 -0.9398)
			(end 0.508 0.9398)
			(stroke
				(width 0.1524)
				(type default)
			)
			(layer "B.SilkS")
		)
		(fp_line
			(start -0.508 -0.9398)
			(end 0.508 -0.9398)
			(stroke
				(width 0.1524)
				(type default)
			)
			(layer "B.SilkS")
		)
		(fp_rect
			(start 0.508 0.9398)
			(end -0.508 -0.9398)
			(stroke
				(width 0)
				(type default)
			)
			(fill no)
			(layer "B.CrtYd")
		)
		(fp_rect
			(start 0.508 0.9398)
			(end -0.508 -0.9398)
			(stroke
				(width 0)
				(type default)
			)
			(fill no)
			(layer "B.Fab")
		)
		(pad "1" smd custom
			(at 0 -0.4445)
			(size 0.1397 0.1397)
			(layers "B.Cu" "B.Mask" "B.Paste")
			(net "GND")
			(options
				(clearance outline)
				(anchor circle)
			)
			(primitives
				(gr_poly
					(pts
						(arc
							(start -0.1778 0.2794)
							(mid -0.249642 0.249642)
							(end -0.2794 0.1778)
						)
						(arc
							(start -0.2794 -0.1778)
							(mid -0.249642 -0.249642)
							(end -0.1778 -0.2794)
						)
						(arc
							(start 0.1778 -0.2794)
							(mid 0.249642 -0.249642)
							(end 0.2794 -0.1778)
						)
						(arc
							(start 0.2794 0.1778)
							(mid 0.249642 0.249642)
							(end 0.1778 0.2794)
						)
					)
					(width 0)
					(fill yes)
				)
			)
		)
		(pad "2" smd custom
			(at 0 0.4445)
			(size 0.1397 0.1397)
			(layers "B.Cu" "B.Mask" "B.Paste")
			(net "MEMA_5")
			(options
				(clearance outline)
				(anchor circle)
			)
			(primitives
				(gr_poly
					(pts
						(arc
							(start -0.1778 0.2794)
							(mid -0.249642 0.249642)
							(end -0.2794 0.1778)
						)
						(arc
							(start -0.2794 -0.1778)
							(mid -0.249642 -0.249642)
							(end -0.1778 -0.2794)
						)
						(arc
							(start 0.1778 -0.2794)
							(mid 0.249642 -0.249642)
							(end 0.2794 -0.1778)
						)
						(arc
							(start 0.2794 0.1778)
							(mid 0.249642 0.249642)
							(end 0.1778 0.2794)
						)
					)
					(width 0)
					(fill yes)
				)
			)
		)
	)
	(footprint ""
		(layer "B.Cu")
		(at 170.035728 -125.527308 -90)
		(property "Reference" "C620"
			(at 0 0 90)
			(layer "B.SilkS")
			(hide yes)
			(effects
				(font
					(size 1.27 1.27)
				)
				(justify mirror)
			)
		)
		(property "Value" "SCD1U16V2KX-3GP"
			(at -1.1811 -2.7051 270)
			(unlocked yes)
			(layer "B.Fab")
			(hide yes)
			(effects
				(font
					(size 1.016 1.016)
					(thickness 0.1524)
				)
				(justify mirror)
			)
		)
		(property "Device Type" "C402H22"
			(at -1.1811 -4.2291 270)
			(unlocked yes)
			(layer "B.Fab")
			(hide yes)
			(effects
				(font
					(size 1.016 1.016)
					(thickness 0.1524)
				)
				(justify mirror)
			)
		)
		(duplicate_pad_numbers_are_jumpers no)
		(fp_rect
			(start 0.4318 0.9525)
			(end -0.4318 -0.9525)
			(stroke
				(width 0)
				(type default)
			)
			(fill no)
			(layer "B.CrtYd")
		)
		(fp_rect
			(start 0.4318 0.9525)
			(end -0.4318 -0.9525)
			(stroke
				(width 0)
				(type default)
			)
			(fill no)
			(layer "B.Fab")
		)
		(pad "1" smd custom
			(at 0 -0.4445 90)
			(size 0.1524 0.1524)
			(layers "B.Cu" "B.Mask" "B.Paste")
			(net "P3V3_M2")
			(options
				(clearance outline)
				(anchor circle)
			)
			(primitives
				(gr_poly
					(pts
						(arc
							(start 0.3048 0.2032)
							(mid 0.275042 0.275042)
							(end 0.2032 0.3048)
						)
						(arc
							(start -0.2032 0.3048)
							(mid -0.275042 0.275042)
							(end -0.3048 0.2032)
						)
						(arc
							(start -0.3048 -0.2032)
							(mid -0.275042 -0.275042)
							(end -0.2032 -0.3048)
						)
						(arc
							(start 0.2032 -0.3048)
							(mid 0.275042 -0.275042)
							(end 0.3048 -0.2032)
						)
					)
					(width 0)
					(fill yes)
				)
			)
		)
		(pad "2" smd custom
			(at 0 0.4445 90)
			(size 0.1524 0.1524)
			(layers "B.Cu" "B.Mask" "B.Paste")
			(net "GND")
			(options
				(clearance outline)
				(anchor circle)
			)
			(primitives
				(gr_poly
					(pts
						(arc
							(start 0.3048 0.2032)
							(mid 0.275042 0.275042)
							(end 0.2032 0.3048)
						)
						(arc
							(start -0.2032 0.3048)
							(mid -0.275042 0.275042)
							(end -0.3048 0.2032)
						)
						(arc
							(start -0.3048 -0.2032)
							(mid -0.275042 -0.275042)
							(end -0.2032 -0.3048)
						)
						(arc
							(start 0.2032 -0.3048)
							(mid 0.275042 -0.275042)
							(end 0.3048 -0.2032)
						)
					)
					(width 0)
					(fill yes)
				)
			)
		)
	)
	(footprint ""
		(layer "B.Cu")
		(at 37.2364 -131.826 180)
		(property "Reference" "R416"
			(at 0 0 0)
			(layer "B.SilkS")
			(hide yes)
			(effects
				(font
					(size 1.27 1.27)
				)
				(justify mirror)
			)
		)
		(property "Value" "4K7R2F-GP"
			(at -0.064008 -3.993896 180)
			(unlocked yes)
			(layer "B.Fab")
			(hide yes)
			(effects
				(font
					(size 1.016 1.016)
					(thickness 0.1524)
				)
				(justify mirror)
			)
		)
		(property "Device Type" "R402H16"
			(at -0.064008 -5.517896 180)
			(unlocked yes)
			(layer "B.Fab")
			(hide yes)
			(effects
				(font
					(size 1.016 1.016)
					(thickness 0.1524)
				)
				(justify mirror)
			)
		)
		(duplicate_pad_numbers_are_jumpers no)
		(fp_line
			(start 0.508 -0.9398)
			(end 0.508 0.9398)
			(stroke
				(width 0.1524)
				(type default)
			)
			(layer "B.SilkS")
		)
		(fp_line
			(start -0.508 -0.9398)
			(end 0.508 -0.9398)
			(stroke
				(width 0.1524)
				(type default)
			)
			(layer "B.SilkS")
		)
		(fp_rect
			(start 0.508 0.9398)
			(end -0.508 -0.9398)
			(stroke
				(width 0)
				(type default)
			)
			(fill no)
			(layer "B.CrtYd")
		)
		(fp_rect
			(start 0.508 0.9398)
			(end -0.508 -0.9398)
			(stroke
				(width 0)
				(type default)
			)
			(fill no)
			(layer "B.Fab")
		)
		(pad "1" smd custom
			(at 0 -0.4445)
			(size 0.1397 0.1397)
			(layers "B.Cu" "B.Mask" "B.Paste")
			(net "P3V3_STBY")
			(options
				(clearance outline)
				(anchor circle)
			)
			(primitives
				(gr_poly
					(pts
						(arc
							(start -0.1778 0.2794)
							(mid -0.249642 0.249642)
							(end -0.2794 0.1778)
						)
						(arc
							(start -0.2794 -0.1778)
							(mid -0.249642 -0.249642)
							(end -0.1778 -0.2794)
						)
						(arc
							(start 0.1778 -0.2794)
							(mid 0.249642 -0.249642)
							(end 0.2794 -0.1778)
						)
						(arc
							(start 0.2794 0.1778)
							(mid 0.249642 0.249642)
							(end 0.1778 0.2794)
						)
					)
					(width 0)
					(fill yes)
				)
			)
		)
		(pad "2" smd custom
			(at 0 0.4445)
			(size 0.1397 0.1397)
			(layers "B.Cu" "B.Mask" "B.Paste")
			(net "BMC_ML_PWR_YELLOW_LED")
			(options
				(clearance outline)
				(anchor circle)
			)
			(primitives
				(gr_poly
					(pts
						(arc
							(start -0.1778 0.2794)
							(mid -0.249642 0.249642)
							(end -0.2794 0.1778)
						)
						(arc
							(start -0.2794 -0.1778)
							(mid -0.249642 -0.249642)
							(end -0.1778 -0.2794)
						)
						(arc
							(start 0.1778 -0.2794)
							(mid 0.249642 -0.249642)
							(end 0.2794 -0.1778)
						)
						(arc
							(start 0.2794 0.1778)
							(mid 0.249642 0.249642)
							(end 0.1778 0.2794)
						)
					)
					(width 0)
					(fill yes)
				)
			)
		)
	)
	(footprint ""
		(layer "B.Cu")
		(at 10.211562 -139.575032 90)
		(property "Reference" "R233"
			(at 0 0 90)
			(layer "B.SilkS")
			(hide yes)
			(effects
				(font
					(size 1.27 1.27)
				)
				(justify mirror)
			)
		)
		(property "Value" "120R2F-GP"
			(at -0.064008 -3.993896 90)
			(unlocked yes)
			(layer "B.Fab")
			(hide yes)
			(effects
				(font
					(size 1.016 1.016)
					(thickness 0.1524)
				)
				(justify mirror)
			)
		)
		(property "Device Type" "R402H16"
			(at -0.064008 -5.517896 90)
			(unlocked yes)
			(layer "B.Fab")
			(hide yes)
			(effects
				(font
					(size 1.016 1.016)
					(thickness 0.1524)
				)
				(justify mirror)
			)
		)
		(duplicate_pad_numbers_are_jumpers no)
		(fp_line
			(start 0.508 -0.9398)
			(end 0.508 0.9398)
			(stroke
				(width 0.1524)
				(type default)
			)
			(layer "B.SilkS")
		)
		(fp_line
			(start -0.508 -0.9398)
			(end 0.508 -0.9398)
			(stroke
				(width 0.1524)
				(type default)
			)
			(layer "B.SilkS")
		)
		(fp_rect
			(start 0.508 0.9398)
			(end -0.508 -0.9398)
			(stroke
				(width 0)
				(type default)
			)
			(fill no)
			(layer "B.CrtYd")
		)
		(fp_rect
			(start 0.508 0.9398)
			(end -0.508 -0.9398)
			(stroke
				(width 0)
				(type default)
			)
			(fill no)
			(layer "B.Fab")
		)
		(pad "1" smd custom
			(at 0 -0.4445 270)
			(size 0.1397 0.1397)
			(layers "B.Cu" "B.Mask" "B.Paste")
			(net "GND")
			(options
				(clearance outline)
				(anchor circle)
			)
			(primitives
				(gr_poly
					(pts
						(arc
							(start -0.1778 0.2794)
							(mid -0.249642 0.249642)
							(end -0.2794 0.1778)
						)
						(arc
							(start -0.2794 -0.1778)
							(mid -0.249642 -0.249642)
							(end -0.1778 -0.2794)
						)
						(arc
							(start 0.1778 -0.2794)
							(mid 0.249642 -0.249642)
							(end 0.2794 -0.1778)
						)
						(arc
							(start 0.2794 0.1778)
							(mid 0.249642 0.249642)
							(end 0.1778 0.2794)
						)
					)
					(width 0)
					(fill yes)
				)
			)
		)
		(pad "2" smd custom
			(at 0 0.4445 270)
			(size 0.1397 0.1397)
			(layers "B.Cu" "B.Mask" "B.Paste")
			(net "MEMA_0")
			(options
				(clearance outline)
				(anchor circle)
			)
			(primitives
				(gr_poly
					(pts
						(arc
							(start -0.1778 0.2794)
							(mid -0.249642 0.249642)
							(end -0.2794 0.1778)
						)
						(arc
							(start -0.2794 -0.1778)
							(mid -0.249642 -0.249642)
							(end -0.1778 -0.2794)
						)
						(arc
							(start 0.1778 -0.2794)
							(mid 0.249642 -0.249642)
							(end 0.2794 -0.1778)
						)
						(arc
							(start 0.2794 0.1778)
							(mid 0.249642 0.249642)
							(end 0.1778 0.2794)
						)
					)
					(width 0)
					(fill yes)
				)
			)
		)
	)
	(footprint ""
		(layer "B.Cu")
		(at 196.457062 -133.83895 180)
		(property "Reference" "C628"
			(at 0 0 0)
			(layer "B.SilkS")
			(hide yes)
			(effects
				(font
					(size 1.27 1.27)
				)
				(justify mirror)
			)
		)
		(property "Value" "SCD1U16V2KX-3GP"
			(at -1.1811 -2.7051 180)
			(unlocked yes)
			(layer "B.Fab")
			(hide yes)
			(effects
				(font
					(size 1.016 1.016)
					(thickness 0.1524)
				)
				(justify mirror)
			)
		)
		(property "Device Type" "C402H22"
			(at -1.1811 -4.2291 180)
			(unlocked yes)
			(layer "B.Fab")
			(hide yes)
			(effects
				(font
					(size 1.016 1.016)
					(thickness 0.1524)
				)
				(justify mirror)
			)
		)
		(duplicate_pad_numbers_are_jumpers no)
		(fp_rect
			(start 0.4318 0.9525)
			(end -0.4318 -0.9525)
			(stroke
				(width 0)
				(type default)
			)
			(fill no)
			(layer "B.CrtYd")
		)
		(fp_rect
			(start 0.4318 0.9525)
			(end -0.4318 -0.9525)
			(stroke
				(width 0)
				(type default)
			)
			(fill no)
			(layer "B.Fab")
		)
		(pad "1" smd custom
			(at 0 -0.4445)
			(size 0.1524 0.1524)
			(layers "B.Cu" "B.Mask" "B.Paste")
			(net "P3V3_M2")
			(options
				(clearance outline)
				(anchor circle)
			)
			(primitives
				(gr_poly
					(pts
						(arc
							(start 0.3048 0.2032)
							(mid 0.275042 0.275042)
							(end 0.2032 0.3048)
						)
						(arc
							(start -0.2032 0.3048)
							(mid -0.275042 0.275042)
							(end -0.3048 0.2032)
						)
						(arc
							(start -0.3048 -0.2032)
							(mid -0.275042 -0.275042)
							(end -0.2032 -0.3048)
						)
						(arc
							(start 0.2032 -0.3048)
							(mid 0.275042 -0.275042)
							(end 0.3048 -0.2032)
						)
					)
					(width 0)
					(fill yes)
				)
			)
		)
		(pad "2" smd custom
			(at 0 0.4445)
			(size 0.1524 0.1524)
			(layers "B.Cu" "B.Mask" "B.Paste")
			(net "GND")
			(options
				(clearance outline)
				(anchor circle)
			)
			(primitives
				(gr_poly
					(pts
						(arc
							(start 0.3048 0.2032)
							(mid 0.275042 0.275042)
							(end 0.2032 0.3048)
						)
						(arc
							(start -0.2032 0.3048)
							(mid -0.275042 0.275042)
							(end -0.3048 0.2032)
						)
						(arc
							(start -0.3048 -0.2032)
							(mid -0.275042 -0.275042)
							(end -0.2032 -0.3048)
						)
						(arc
							(start 0.2032 -0.3048)
							(mid 0.275042 -0.275042)
							(end 0.3048 -0.2032)
						)
					)
					(width 0)
					(fill yes)
				)
			)
		)
	)
	(footprint ""
		(layer "B.Cu")
		(at 67.306952 -169.282618 -90)
		(property "Reference" "R79"
			(at 0 0 90)
			(layer "B.SilkS")
			(hide yes)
			(effects
				(font
					(size 1.27 1.27)
				)
				(justify mirror)
			)
		)
		(property "Value" "470KR2F-GP"
			(at -0.064008 -3.993896 270)
			(unlocked yes)
			(layer "B.Fab")
			(hide yes)
			(effects
				(font
					(size 1.016 1.016)
					(thickness 0.1524)
				)
				(justify mirror)
			)
		)
		(property "Device Type" "R402H16"
			(at -0.064008 -5.517896 270)
			(unlocked yes)
			(layer "B.Fab")
			(hide yes)
			(effects
				(font
					(size 1.016 1.016)
					(thickness 0.1524)
				)
				(justify mirror)
			)
		)
		(duplicate_pad_numbers_are_jumpers no)
		(fp_line
			(start -0.508 -0.9398)
			(end 0.508 -0.9398)
			(stroke
				(width 0.1524)
				(type default)
			)
			(layer "B.SilkS")
		)
		(fp_line
			(start 0.508 -0.9398)
			(end 0.508 0.9398)
			(stroke
				(width 0.1524)
				(type default)
			)
			(layer "B.SilkS")
		)
		(fp_rect
			(start 0.508 0.9398)
			(end -0.508 -0.9398)
			(stroke
				(width 0)
				(type default)
			)
			(fill no)
			(layer "B.CrtYd")
		)
		(fp_rect
			(start 0.508 0.9398)
			(end -0.508 -0.9398)
			(stroke
				(width 0)
				(type default)
			)
			(fill no)
			(layer "B.Fab")
		)
		(pad "1" smd custom
			(at 0 -0.4445 90)
			(size 0.1397 0.1397)
			(layers "B.Cu" "B.Mask" "B.Paste")
			(net "BMC_SELF_HW_RST_D")
			(options
				(clearance outline)
				(anchor circle)
			)
			(primitives
				(gr_poly
					(pts
						(arc
							(start -0.1778 0.2794)
							(mid -0.249642 0.249642)
							(end -0.2794 0.1778)
						)
						(arc
							(start -0.2794 -0.1778)
							(mid -0.249642 -0.249642)
							(end -0.1778 -0.2794)
						)
						(arc
							(start 0.1778 -0.2794)
							(mid 0.249642 -0.249642)
							(end 0.2794 -0.1778)
						)
						(arc
							(start 0.2794 0.1778)
							(mid 0.249642 0.249642)
							(end 0.1778 0.2794)
						)
					)
					(width 0)
					(fill yes)
				)
			)
		)
		(pad "2" smd custom
			(at 0 0.4445 90)
			(size 0.1397 0.1397)
			(layers "B.Cu" "B.Mask" "B.Paste")
			(net "GND")
			(options
				(clearance outline)
				(anchor circle)
			)
			(primitives
				(gr_poly
					(pts
						(arc
							(start -0.1778 0.2794)
							(mid -0.249642 0.249642)
							(end -0.2794 0.1778)
						)
						(arc
							(start -0.2794 -0.1778)
							(mid -0.249642 -0.249642)
							(end -0.1778 -0.2794)
						)
						(arc
							(start 0.1778 -0.2794)
							(mid 0.249642 -0.249642)
							(end 0.2794 -0.1778)
						)
						(arc
							(start 0.2794 0.1778)
							(mid 0.249642 0.249642)
							(end 0.1778 0.2794)
						)
					)
					(width 0)
					(fill yes)
				)
			)
		)
	)
	(footprint ""
		(layer "B.Cu")
		(at 207.159352 -105.724198 180)
		(property "Reference" "U82"
			(at 0 0 0)
			(layer "B.SilkS")
			(hide yes)
			(effects
				(font
					(size 1.27 1.27)
				)
				(justify mirror)
			)
		)
		(property "Value" "PCA9306DCTT-GP"
			(at 0 -11.6332 180)
			(unlocked yes)
			(layer "B.Fab")
			(hide yes)
			(effects
				(font
					(size 1.016 1.016)
					(thickness 0.1524)
				)
				(justify mirror)
			)
		)
		(property "Device Type" "SSOIC8H52"
			(at 0 -13.1572 180)
			(unlocked yes)
			(layer "B.Fab")
			(hide yes)
			(effects
				(font
					(size 1.016 1.016)
					(thickness 0.1524)
				)
				(justify mirror)
			)
		)
		(duplicate_pad_numbers_are_jumpers no)
		(fp_line
			(start 1.7018 -0.5842)
			(end 1.7018 2.286)
			(stroke
				(width 0.1524)
				(type default)
			)
			(layer "B.SilkS")
		)
		(fp_line
			(start 1.7018 -0.5842)
			(end -1.0668 -0.5842)
			(stroke
				(width 0.1524)
				(type default)
			)
			(layer "B.SilkS")
		)
		(fp_line
			(start 1.524 0.5842)
			(end 1.524 2.286)
			(stroke
				(width 0.508)
				(type default)
			)
			(layer "B.SilkS")
		)
		(fp_line
			(start 1.397 0)
			(end 1.7018 0.3048)
			(stroke
				(width 0.1524)
				(type default)
			)
			(layer "B.SilkS")
		)
		(fp_line
			(start 1.397 0)
			(end 1.7018 -0.3048)
			(stroke
				(width 0.1524)
				(type default)
			)
			(layer "B.SilkS")
		)
		(fp_line
			(start -1.0668 0.5842)
			(end 1.524 0.5842)
			(stroke
				(width 0.1524)
				(type default)
			)
			(layer "B.SilkS")
		)
		(fp_line
			(start -1.0668 -0.5842)
			(end -1.0668 0.5842)
			(stroke
				(width 0.1524)
				(type default)
			)
			(layer "B.SilkS")
		)
		(fp_poly
			(pts
				(xy 1.1684 -0.5842) (xy -1.0668 -0.5842) (xy -1.0668 0.5842) (xy 1.1684 0.5842)
			)
			(stroke
				(width 0)
				(type default)
			)
			(fill yes)
			(layer "B.SilkS")
		)
		(fp_poly
			(pts
				(xy 1.778 2.54) (xy -1.778 2.54) (xy -1.778 -2.54) (xy 1.778 -2.54)
			)
			(stroke
				(width 0)
				(type default)
			)
			(fill no)
			(layer "B.CrtYd")
		)
		(fp_poly
			(pts
				(xy 1.778 -2.54) (xy -1.778 -2.54) (xy -1.778 2.54) (xy 1.778 2.54)
			)
			(stroke
				(width 0)
				(type default)
			)
			(fill no)
			(layer "B.Fab")
		)
		(pad "1" smd rect
			(at 0.97536 1.6256)
			(size 0.3556 1.524)
			(layers "B.Cu" "B.Mask" "B.Paste")
			(net "GND")
		)
		(pad "2" smd rect
			(at 0.32512 1.6256)
			(size 0.3556 1.524)
			(layers "B.Cu" "B.Mask" "B.Paste")
			(net "P1V8_STBY")
		)
		(pad "3" smd rect
			(at -0.32512 1.6256)
			(size 0.3556 1.524)
			(layers "B.Cu" "B.Mask" "B.Paste")
			(net "I2C_M2_1_1V8_SCL")
		)
		(pad "4" smd rect
			(at -0.97536 1.6256)
			(size 0.3556 1.524)
			(layers "B.Cu" "B.Mask" "B.Paste")
			(net "I2C_M2_1_1V8_SDA")
		)
		(pad "5" smd rect
			(at -0.97536 -1.6256)
			(size 0.3556 1.524)
			(layers "B.Cu" "B.Mask" "B.Paste")
			(net "I2C_M2_1_SDA")
		)
		(pad "6" smd rect
			(at -0.32512 -1.6256)
			(size 0.3556 1.524)
			(layers "B.Cu" "B.Mask" "B.Paste")
			(net "I2C_M2_1_SCL")
		)
		(pad "7" smd rect
			(at 0.32512 -1.6256)
			(size 0.3556 1.524)
			(layers "B.Cu" "B.Mask" "B.Paste")
			(net "U82_VREF2")
		)
		(pad "8" smd rect
			(at 0.97536 -1.6256)
			(size 0.3556 1.524)
			(layers "B.Cu" "B.Mask" "B.Paste")
			(net "U82_VREF2")
		)
	)
	(footprint ""
		(layer "B.Cu")
		(at 50.1396 -139.446)
		(property "Reference" "TP72"
			(at 0 0 0)
			(layer "B.SilkS")
			(hide yes)
			(effects
				(font
					(size 1.27 1.27)
				)
				(justify mirror)
			)
		)
		(property "Value" "TPAD28-2-GP"
			(at 0.0127 -1.6637 0)
			(unlocked yes)
			(layer "B.Fab")
			(hide yes)
			(effects
				(font
					(size 1.016 1.016)
					(thickness 0.1524)
				)
				(justify mirror)
			)
		)
		(property "Device Type" "TPAD28"
			(at 0.0127 -3.1877 0)
			(unlocked yes)
			(layer "B.Fab")
			(hide yes)
			(effects
				(font
					(size 1.016 1.016)
					(thickness 0.1524)
				)
				(justify mirror)
			)
		)
		(duplicate_pad_numbers_are_jumpers no)
		(fp_poly
			(pts
				(arc
					(start 0.3556 0)
					(mid -0.3556 0)
					(end 0.3556 0)
				)
			)
			(stroke
				(width 0)
				(type default)
			)
			(fill no)
			(layer "B.CrtYd")
		)
		(fp_poly
			(pts
				(arc
					(start 0.6096 0)
					(mid -0.6096 0)
					(end 0.6096 0)
				)
			)
			(stroke
				(width 0)
				(type default)
			)
			(fill no)
			(layer "B.Fab")
		)
		(pad "1" smd circle
			(at 0 0 180)
			(size 0.7112 0.7112)
			(layers "B.Cu" "B.Mask" "B.Paste")
			(net "TP_BMC_GPIOI1")
		)
	)
	(footprint ""
		(layer "B.Cu")
		(at 57.0738 -151.6888 -90)
		(property "Reference" "R383"
			(at 0 0 90)
			(layer "B.SilkS")
			(hide yes)
			(effects
				(font
					(size 1.27 1.27)
				)
				(justify mirror)
			)
		)
		(property "Value" "4K7R2F-GP"
			(at -0.064008 -3.993896 270)
			(unlocked yes)
			(layer "B.Fab")
			(hide yes)
			(effects
				(font
					(size 1.016 1.016)
					(thickness 0.1524)
				)
				(justify mirror)
			)
		)
		(property "Device Type" "R402H16"
			(at -0.064008 -5.517896 270)
			(unlocked yes)
			(layer "B.Fab")
			(hide yes)
			(effects
				(font
					(size 1.016 1.016)
					(thickness 0.1524)
				)
				(justify mirror)
			)
		)
		(duplicate_pad_numbers_are_jumpers no)
		(fp_line
			(start -0.508 -0.9398)
			(end 0.508 -0.9398)
			(stroke
				(width 0.1524)
				(type default)
			)
			(layer "B.SilkS")
		)
		(fp_line
			(start 0.508 -0.9398)
			(end 0.508 0.9398)
			(stroke
				(width 0.1524)
				(type default)
			)
			(layer "B.SilkS")
		)
		(fp_rect
			(start 0.508 0.9398)
			(end -0.508 -0.9398)
			(stroke
				(width 0)
				(type default)
			)
			(fill no)
			(layer "B.CrtYd")
		)
		(fp_rect
			(start 0.508 0.9398)
			(end -0.508 -0.9398)
			(stroke
				(width 0)
				(type default)
			)
			(fill no)
			(layer "B.Fab")
		)
		(pad "1" smd custom
			(at 0 -0.4445 90)
			(size 0.1397 0.1397)
			(layers "B.Cu" "B.Mask" "B.Paste")
			(net "P3V3_STBY")
			(options
				(clearance outline)
				(anchor circle)
			)
			(primitives
				(gr_poly
					(pts
						(arc
							(start -0.1778 0.2794)
							(mid -0.249642 0.249642)
							(end -0.2794 0.1778)
						)
						(arc
							(start -0.2794 -0.1778)
							(mid -0.249642 -0.249642)
							(end -0.1778 -0.2794)
						)
						(arc
							(start 0.1778 -0.2794)
							(mid 0.249642 -0.249642)
							(end 0.2794 -0.1778)
						)
						(arc
							(start 0.2794 0.1778)
							(mid 0.249642 0.249642)
							(end 0.1778 0.2794)
						)
					)
					(width 0)
					(fill yes)
				)
			)
		)
		(pad "2" smd custom
			(at 0 0.4445 90)
			(size 0.1397 0.1397)
			(layers "B.Cu" "B.Mask" "B.Paste")
			(net "MAC1_TXD2")
			(options
				(clearance outline)
				(anchor circle)
			)
			(primitives
				(gr_poly
					(pts
						(arc
							(start -0.1778 0.2794)
							(mid -0.249642 0.249642)
							(end -0.2794 0.1778)
						)
						(arc
							(start -0.2794 -0.1778)
							(mid -0.249642 -0.249642)
							(end -0.1778 -0.2794)
						)
						(arc
							(start 0.1778 -0.2794)
							(mid 0.249642 -0.249642)
							(end 0.2794 -0.1778)
						)
						(arc
							(start 0.2794 0.1778)
							(mid 0.249642 0.249642)
							(end 0.1778 0.2794)
						)
					)
					(width 0)
					(fill yes)
				)
			)
		)
	)
	(footprint ""
		(layer "B.Cu")
		(at 49.787302 -135.75665 180)
		(property "Reference" "R291"
			(at 0 0 0)
			(layer "B.SilkS")
			(hide yes)
			(effects
				(font
					(size 1.27 1.27)
				)
				(justify mirror)
			)
		)
		(property "Value" "0R2J-2-GP"
			(at -0.064008 -3.993896 180)
			(unlocked yes)
			(layer "B.Fab")
			(hide yes)
			(effects
				(font
					(size 1.016 1.016)
					(thickness 0.1524)
				)
				(justify mirror)
			)
		)
		(property "Device Type" "R402H16"
			(at -0.064008 -5.517896 180)
			(unlocked yes)
			(layer "B.Fab")
			(hide yes)
			(effects
				(font
					(size 1.016 1.016)
					(thickness 0.1524)
				)
				(justify mirror)
			)
		)
		(duplicate_pad_numbers_are_jumpers no)
		(fp_line
			(start 0.508 -0.9398)
			(end 0.508 0.9398)
			(stroke
				(width 0.1524)
				(type default)
			)
			(layer "B.SilkS")
		)
		(fp_line
			(start -0.508 -0.9398)
			(end 0.508 -0.9398)
			(stroke
				(width 0.1524)
				(type default)
			)
			(layer "B.SilkS")
		)
		(fp_rect
			(start 0.508 0.9398)
			(end -0.508 -0.9398)
			(stroke
				(width 0)
				(type default)
			)
			(fill no)
			(layer "B.CrtYd")
		)
		(fp_rect
			(start 0.508 0.9398)
			(end -0.508 -0.9398)
			(stroke
				(width 0)
				(type default)
			)
			(fill no)
			(layer "B.Fab")
		)
		(pad "1" smd custom
			(at 0 -0.4445)
			(size 0.1397 0.1397)
			(layers "B.Cu" "B.Mask" "B.Paste")
			(net "DPB_MISC_ALERT_OUT")
			(options
				(clearance outline)
				(anchor circle)
			)
			(primitives
				(gr_poly
					(pts
						(arc
							(start -0.1778 0.2794)
							(mid -0.249642 0.249642)
							(end -0.2794 0.1778)
						)
						(arc
							(start -0.2794 -0.1778)
							(mid -0.249642 -0.249642)
							(end -0.1778 -0.2794)
						)
						(arc
							(start 0.1778 -0.2794)
							(mid 0.249642 -0.249642)
							(end 0.2794 -0.1778)
						)
						(arc
							(start 0.2794 0.1778)
							(mid 0.249642 0.249642)
							(end 0.1778 0.2794)
						)
					)
					(width 0)
					(fill yes)
				)
			)
		)
		(pad "2" smd custom
			(at 0 0.4445)
			(size 0.1397 0.1397)
			(layers "B.Cu" "B.Mask" "B.Paste")
			(net "DPB_MISC_ALERT_O_R")
			(options
				(clearance outline)
				(anchor circle)
			)
			(primitives
				(gr_poly
					(pts
						(arc
							(start -0.1778 0.2794)
							(mid -0.249642 0.249642)
							(end -0.2794 0.1778)
						)
						(arc
							(start -0.2794 -0.1778)
							(mid -0.249642 -0.249642)
							(end -0.1778 -0.2794)
						)
						(arc
							(start 0.1778 -0.2794)
							(mid 0.249642 -0.249642)
							(end 0.2794 -0.1778)
						)
						(arc
							(start 0.2794 0.1778)
							(mid 0.249642 0.249642)
							(end 0.1778 0.2794)
						)
					)
					(width 0)
					(fill yes)
				)
			)
		)
	)
	(footprint ""
		(layer "B.Cu")
		(at 37.9222 -157.5308 -90)
		(property "Reference" "R700"
			(at 0 0 90)
			(layer "B.SilkS")
			(hide yes)
			(effects
				(font
					(size 1.27 1.27)
				)
				(justify mirror)
			)
		)
		(property "Value" "4K7R2F-GP"
			(at -0.064008 -3.993896 270)
			(unlocked yes)
			(layer "B.Fab")
			(hide yes)
			(effects
				(font
					(size 1.016 1.016)
					(thickness 0.1524)
				)
				(justify mirror)
			)
		)
		(property "Device Type" "R402H16"
			(at -0.064008 -5.517896 270)
			(unlocked yes)
			(layer "B.Fab")
			(hide yes)
			(effects
				(font
					(size 1.016 1.016)
					(thickness 0.1524)
				)
				(justify mirror)
			)
		)
		(duplicate_pad_numbers_are_jumpers no)
		(fp_line
			(start -0.508 -0.9398)
			(end 0.508 -0.9398)
			(stroke
				(width 0.1524)
				(type default)
			)
			(layer "B.SilkS")
		)
		(fp_line
			(start 0.508 -0.9398)
			(end 0.508 0.9398)
			(stroke
				(width 0.1524)
				(type default)
			)
			(layer "B.SilkS")
		)
		(fp_rect
			(start 0.508 0.9398)
			(end -0.508 -0.9398)
			(stroke
				(width 0)
				(type default)
			)
			(fill no)
			(layer "B.CrtYd")
		)
		(fp_rect
			(start 0.508 0.9398)
			(end -0.508 -0.9398)
			(stroke
				(width 0)
				(type default)
			)
			(fill no)
			(layer "B.Fab")
		)
		(pad "1" smd custom
			(at 0 -0.4445 90)
			(size 0.1397 0.1397)
			(layers "B.Cu" "B.Mask" "B.Paste")
			(net "P3V3_STBY")
			(options
				(clearance outline)
				(anchor circle)
			)
			(primitives
				(gr_poly
					(pts
						(arc
							(start -0.1778 0.2794)
							(mid -0.249642 0.249642)
							(end -0.2794 0.1778)
						)
						(arc
							(start -0.2794 -0.1778)
							(mid -0.249642 -0.249642)
							(end -0.1778 -0.2794)
						)
						(arc
							(start 0.1778 -0.2794)
							(mid 0.249642 -0.249642)
							(end 0.2794 -0.1778)
						)
						(arc
							(start 0.2794 0.1778)
							(mid 0.249642 0.249642)
							(end 0.1778 0.2794)
						)
					)
					(width 0)
					(fill yes)
				)
			)
		)
		(pad "2" smd custom
			(at 0 0.4445 90)
			(size 0.1397 0.1397)
			(layers "B.Cu" "B.Mask" "B.Paste")
			(net "IOM_TYPE3")
			(options
				(clearance outline)
				(anchor circle)
			)
			(primitives
				(gr_poly
					(pts
						(arc
							(start -0.1778 0.2794)
							(mid -0.249642 0.249642)
							(end -0.2794 0.1778)
						)
						(arc
							(start -0.2794 -0.1778)
							(mid -0.249642 -0.249642)
							(end -0.1778 -0.2794)
						)
						(arc
							(start 0.1778 -0.2794)
							(mid 0.249642 -0.249642)
							(end 0.2794 -0.1778)
						)
						(arc
							(start 0.2794 0.1778)
							(mid 0.249642 0.249642)
							(end 0.1778 0.2794)
						)
					)
					(width 0)
					(fill yes)
				)
			)
		)
	)
	(footprint ""
		(layer "B.Cu")
		(at 54.723792 -135.610854 180)
		(property "Reference" "R353"
			(at 0 0 0)
			(layer "B.SilkS")
			(hide yes)
			(effects
				(font
					(size 1.27 1.27)
				)
				(justify mirror)
			)
		)
		(property "Value" "4K7R2F-GP"
			(at -0.064008 -3.993896 180)
			(unlocked yes)
			(layer "B.Fab")
			(hide yes)
			(effects
				(font
					(size 1.016 1.016)
					(thickness 0.1524)
				)
				(justify mirror)
			)
		)
		(property "Device Type" "R402H16"
			(at -0.064008 -5.517896 180)
			(unlocked yes)
			(layer "B.Fab")
			(hide yes)
			(effects
				(font
					(size 1.016 1.016)
					(thickness 0.1524)
				)
				(justify mirror)
			)
		)
		(duplicate_pad_numbers_are_jumpers no)
		(fp_line
			(start 0.508 -0.9398)
			(end 0.508 0.9398)
			(stroke
				(width 0.1524)
				(type default)
			)
			(layer "B.SilkS")
		)
		(fp_line
			(start -0.508 -0.9398)
			(end 0.508 -0.9398)
			(stroke
				(width 0.1524)
				(type default)
			)
			(layer "B.SilkS")
		)
		(fp_rect
			(start 0.508 0.9398)
			(end -0.508 -0.9398)
			(stroke
				(width 0)
				(type default)
			)
			(fill no)
			(layer "B.CrtYd")
		)
		(fp_rect
			(start 0.508 0.9398)
			(end -0.508 -0.9398)
			(stroke
				(width 0)
				(type default)
			)
			(fill no)
			(layer "B.Fab")
		)
		(pad "1" smd custom
			(at 0 -0.4445)
			(size 0.1397 0.1397)
			(layers "B.Cu" "B.Mask" "B.Paste")
			(net "P3V3_STBY")
			(options
				(clearance outline)
				(anchor circle)
			)
			(primitives
				(gr_poly
					(pts
						(arc
							(start -0.1778 0.2794)
							(mid -0.249642 0.249642)
							(end -0.2794 0.1778)
						)
						(arc
							(start -0.2794 -0.1778)
							(mid -0.249642 -0.249642)
							(end -0.1778 -0.2794)
						)
						(arc
							(start 0.1778 -0.2794)
							(mid 0.249642 -0.249642)
							(end 0.2794 -0.1778)
						)
						(arc
							(start 0.2794 0.1778)
							(mid 0.249642 0.249642)
							(end 0.1778 0.2794)
						)
					)
					(width 0)
					(fill yes)
				)
			)
		)
		(pad "2" smd custom
			(at 0 0.4445)
			(size 0.1397 0.1397)
			(layers "B.Cu" "B.Mask" "B.Paste")
			(net "SLOTID_1")
			(options
				(clearance outline)
				(anchor circle)
			)
			(primitives
				(gr_poly
					(pts
						(arc
							(start -0.1778 0.2794)
							(mid -0.249642 0.249642)
							(end -0.2794 0.1778)
						)
						(arc
							(start -0.2794 -0.1778)
							(mid -0.249642 -0.249642)
							(end -0.1778 -0.2794)
						)
						(arc
							(start 0.1778 -0.2794)
							(mid 0.249642 -0.249642)
							(end 0.2794 -0.1778)
						)
						(arc
							(start 0.2794 0.1778)
							(mid 0.249642 0.249642)
							(end 0.1778 0.2794)
						)
					)
					(width 0)
					(fill yes)
				)
			)
		)
	)
	(footprint ""
		(layer "B.Cu")
		(at 38.443154 -127.888238)
		(property "Reference" "R732"
			(at 0 0 0)
			(layer "B.SilkS")
			(hide yes)
			(effects
				(font
					(size 1.27 1.27)
				)
				(justify mirror)
			)
		)
		(property "Value" "0R2J-2-GP"
			(at -0.064008 -3.993896 0)
			(unlocked yes)
			(layer "B.Fab")
			(hide yes)
			(effects
				(font
					(size 1.016 1.016)
					(thickness 0.1524)
				)
				(justify mirror)
			)
		)
		(property "Device Type" "R402H16"
			(at -0.064008 -5.517896 0)
			(unlocked yes)
			(layer "B.Fab")
			(hide yes)
			(effects
				(font
					(size 1.016 1.016)
					(thickness 0.1524)
				)
				(justify mirror)
			)
		)
		(duplicate_pad_numbers_are_jumpers no)
		(fp_line
			(start -0.508 -0.9398)
			(end 0.508 -0.9398)
			(stroke
				(width 0.1524)
				(type default)
			)
			(layer "B.SilkS")
		)
		(fp_line
			(start 0.508 -0.9398)
			(end 0.508 0.9398)
			(stroke
				(width 0.1524)
				(type default)
			)
			(layer "B.SilkS")
		)
		(fp_rect
			(start 0.508 0.9398)
			(end -0.508 -0.9398)
			(stroke
				(width 0)
				(type default)
			)
			(fill no)
			(layer "B.CrtYd")
		)
		(fp_rect
			(start 0.508 0.9398)
			(end -0.508 -0.9398)
			(stroke
				(width 0)
				(type default)
			)
			(fill no)
			(layer "B.Fab")
		)
		(pad "1" smd custom
			(at 0 -0.4445 180)
			(size 0.1397 0.1397)
			(layers "B.Cu" "B.Mask" "B.Paste")
			(net "U104_EN")
			(options
				(clearance outline)
				(anchor circle)
			)
			(primitives
				(gr_poly
					(pts
						(arc
							(start -0.1778 0.2794)
							(mid -0.249642 0.249642)
							(end -0.2794 0.1778)
						)
						(arc
							(start -0.2794 -0.1778)
							(mid -0.249642 -0.249642)
							(end -0.1778 -0.2794)
						)
						(arc
							(start 0.1778 -0.2794)
							(mid 0.249642 -0.249642)
							(end 0.2794 -0.1778)
						)
						(arc
							(start 0.2794 0.1778)
							(mid 0.249642 0.249642)
							(end 0.1778 0.2794)
						)
					)
					(width 0)
					(fill yes)
				)
			)
		)
		(pad "2" smd custom
			(at 0 0.4445 180)
			(size 0.1397 0.1397)
			(layers "B.Cu" "B.Mask" "B.Paste")
			(net "COMP_PWR_EN")
			(options
				(clearance outline)
				(anchor circle)
			)
			(primitives
				(gr_poly
					(pts
						(arc
							(start -0.1778 0.2794)
							(mid -0.249642 0.249642)
							(end -0.2794 0.1778)
						)
						(arc
							(start -0.2794 -0.1778)
							(mid -0.249642 -0.249642)
							(end -0.1778 -0.2794)
						)
						(arc
							(start 0.1778 -0.2794)
							(mid 0.249642 -0.249642)
							(end 0.2794 -0.1778)
						)
						(arc
							(start 0.2794 0.1778)
							(mid 0.249642 0.249642)
							(end 0.1778 0.2794)
						)
					)
					(width 0)
					(fill yes)
				)
			)
		)
	)
	(footprint ""
		(layer "B.Cu")
		(at 74.88428 -142.525242 90)
		(property "Reference" "R385"
			(at 0 0 90)
			(layer "B.SilkS")
			(hide yes)
			(effects
				(font
					(size 1.27 1.27)
				)
				(justify mirror)
			)
		)
		(property "Value" "4K7R2F-GP"
			(at -0.064008 -3.993896 90)
			(unlocked yes)
			(layer "B.Fab")
			(hide yes)
			(effects
				(font
					(size 1.016 1.016)
					(thickness 0.1524)
				)
				(justify mirror)
			)
		)
		(property "Device Type" "R402H16"
			(at -0.064008 -5.517896 90)
			(unlocked yes)
			(layer "B.Fab")
			(hide yes)
			(effects
				(font
					(size 1.016 1.016)
					(thickness 0.1524)
				)
				(justify mirror)
			)
		)
		(duplicate_pad_numbers_are_jumpers no)
		(fp_line
			(start 0.508 -0.9398)
			(end 0.508 0.9398)
			(stroke
				(width 0.1524)
				(type default)
			)
			(layer "B.SilkS")
		)
		(fp_line
			(start -0.508 -0.9398)
			(end 0.508 -0.9398)
			(stroke
				(width 0.1524)
				(type default)
			)
			(layer "B.SilkS")
		)
		(fp_rect
			(start 0.508 0.9398)
			(end -0.508 -0.9398)
			(stroke
				(width 0)
				(type default)
			)
			(fill no)
			(layer "B.CrtYd")
		)
		(fp_rect
			(start 0.508 0.9398)
			(end -0.508 -0.9398)
			(stroke
				(width 0)
				(type default)
			)
			(fill no)
			(layer "B.Fab")
		)
		(pad "1" smd custom
			(at 0 -0.4445 270)
			(size 0.1397 0.1397)
			(layers "B.Cu" "B.Mask" "B.Paste")
			(net "GND")
			(options
				(clearance outline)
				(anchor circle)
			)
			(primitives
				(gr_poly
					(pts
						(arc
							(start -0.1778 0.2794)
							(mid -0.249642 0.249642)
							(end -0.2794 0.1778)
						)
						(arc
							(start -0.2794 -0.1778)
							(mid -0.249642 -0.249642)
							(end -0.1778 -0.2794)
						)
						(arc
							(start 0.1778 -0.2794)
							(mid 0.249642 -0.249642)
							(end 0.2794 -0.1778)
						)
						(arc
							(start 0.2794 0.1778)
							(mid 0.249642 0.249642)
							(end 0.1778 0.2794)
						)
					)
					(width 0)
					(fill yes)
				)
			)
		)
		(pad "2" smd custom
			(at 0 0.4445 270)
			(size 0.1397 0.1397)
			(layers "B.Cu" "B.Mask" "B.Paste")
			(net "NCSI_TXEN")
			(options
				(clearance outline)
				(anchor circle)
			)
			(primitives
				(gr_poly
					(pts
						(arc
							(start -0.1778 0.2794)
							(mid -0.249642 0.249642)
							(end -0.2794 0.1778)
						)
						(arc
							(start -0.2794 -0.1778)
							(mid -0.249642 -0.249642)
							(end -0.1778 -0.2794)
						)
						(arc
							(start 0.1778 -0.2794)
							(mid 0.249642 -0.249642)
							(end 0.2794 -0.1778)
						)
						(arc
							(start 0.2794 0.1778)
							(mid 0.249642 0.249642)
							(end 0.1778 0.2794)
						)
					)
					(width 0)
					(fill yes)
				)
			)
		)
	)
	(footprint ""
		(layer "B.Cu")
		(at 52.648612 -135.661654)
		(property "Reference" "R167"
			(at 0 0 0)
			(layer "B.SilkS")
			(hide yes)
			(effects
				(font
					(size 1.27 1.27)
				)
				(justify mirror)
			)
		)
		(property "Value" "0R2J-2-GP"
			(at -0.064008 -3.993896 0)
			(unlocked yes)
			(layer "B.Fab")
			(hide yes)
			(effects
				(font
					(size 1.016 1.016)
					(thickness 0.1524)
				)
				(justify mirror)
			)
		)
		(property "Device Type" "R402H16"
			(at -0.064008 -5.517896 0)
			(unlocked yes)
			(layer "B.Fab")
			(hide yes)
			(effects
				(font
					(size 1.016 1.016)
					(thickness 0.1524)
				)
				(justify mirror)
			)
		)
		(duplicate_pad_numbers_are_jumpers no)
		(fp_line
			(start -0.508 -0.9398)
			(end 0.508 -0.9398)
			(stroke
				(width 0.1524)
				(type default)
			)
			(layer "B.SilkS")
		)
		(fp_line
			(start 0.508 -0.9398)
			(end 0.508 0.9398)
			(stroke
				(width 0.1524)
				(type default)
			)
			(layer "B.SilkS")
		)
		(fp_rect
			(start 0.508 0.9398)
			(end -0.508 -0.9398)
			(stroke
				(width 0)
				(type default)
			)
			(fill no)
			(layer "B.CrtYd")
		)
		(fp_rect
			(start 0.508 0.9398)
			(end -0.508 -0.9398)
			(stroke
				(width 0)
				(type default)
			)
			(fill no)
			(layer "B.Fab")
		)
		(pad "1" smd custom
			(at 0 -0.4445 180)
			(size 0.1397 0.1397)
			(layers "B.Cu" "B.Mask" "B.Paste")
			(net "PWRBTN_OUT_N_R")
			(options
				(clearance outline)
				(anchor circle)
			)
			(primitives
				(gr_poly
					(pts
						(arc
							(start -0.1778 0.2794)
							(mid -0.249642 0.249642)
							(end -0.2794 0.1778)
						)
						(arc
							(start -0.2794 -0.1778)
							(mid -0.249642 -0.249642)
							(end -0.1778 -0.2794)
						)
						(arc
							(start 0.1778 -0.2794)
							(mid 0.249642 -0.249642)
							(end 0.2794 -0.1778)
						)
						(arc
							(start 0.2794 0.1778)
							(mid 0.249642 0.249642)
							(end 0.1778 0.2794)
						)
					)
					(width 0)
					(fill yes)
				)
			)
		)
		(pad "2" smd custom
			(at 0 0.4445 180)
			(size 0.1397 0.1397)
			(layers "B.Cu" "B.Mask" "B.Paste")
			(net "PWRBTN_OUT_N")
			(options
				(clearance outline)
				(anchor circle)
			)
			(primitives
				(gr_poly
					(pts
						(arc
							(start -0.1778 0.2794)
							(mid -0.249642 0.249642)
							(end -0.2794 0.1778)
						)
						(arc
							(start -0.2794 -0.1778)
							(mid -0.249642 -0.249642)
							(end -0.1778 -0.2794)
						)
						(arc
							(start 0.1778 -0.2794)
							(mid 0.249642 -0.249642)
							(end 0.2794 -0.1778)
						)
						(arc
							(start 0.2794 0.1778)
							(mid 0.249642 0.249642)
							(end 0.1778 0.2794)
						)
					)
					(width 0)
					(fill yes)
				)
			)
		)
	)
	(footprint ""
		(layer "B.Cu")
		(at 76.0984 -134.0866 90)
		(property "Reference" "C30"
			(at 0 0 90)
			(layer "B.SilkS")
			(hide yes)
			(effects
				(font
					(size 1.27 1.27)
				)
				(justify mirror)
			)
		)
		(property "Value" "SCD1U16V2KX-3GP"
			(at -1.1811 -2.7051 90)
			(unlocked yes)
			(layer "B.Fab")
			(hide yes)
			(effects
				(font
					(size 1.016 1.016)
					(thickness 0.1524)
				)
				(justify mirror)
			)
		)
		(property "Device Type" "C402H22"
			(at -1.1811 -4.2291 90)
			(unlocked yes)
			(layer "B.Fab")
			(hide yes)
			(effects
				(font
					(size 1.016 1.016)
					(thickness 0.1524)
				)
				(justify mirror)
			)
		)
		(duplicate_pad_numbers_are_jumpers no)
		(fp_rect
			(start 0.4318 0.9525)
			(end -0.4318 -0.9525)
			(stroke
				(width 0)
				(type default)
			)
			(fill no)
			(layer "B.CrtYd")
		)
		(fp_rect
			(start 0.4318 0.9525)
			(end -0.4318 -0.9525)
			(stroke
				(width 0)
				(type default)
			)
			(fill no)
			(layer "B.Fab")
		)
		(pad "1" smd custom
			(at 0 -0.4445 270)
			(size 0.1524 0.1524)
			(layers "B.Cu" "B.Mask" "B.Paste")
			(net "P3V3_STBY")
			(options
				(clearance outline)
				(anchor circle)
			)
			(primitives
				(gr_poly
					(pts
						(arc
							(start 0.3048 0.2032)
							(mid 0.275042 0.275042)
							(end 0.2032 0.3048)
						)
						(arc
							(start -0.2032 0.3048)
							(mid -0.275042 0.275042)
							(end -0.3048 0.2032)
						)
						(arc
							(start -0.3048 -0.2032)
							(mid -0.275042 -0.275042)
							(end -0.2032 -0.3048)
						)
						(arc
							(start 0.2032 -0.3048)
							(mid 0.275042 -0.275042)
							(end 0.3048 -0.2032)
						)
					)
					(width 0)
					(fill yes)
				)
			)
		)
		(pad "2" smd custom
			(at 0 0.4445 270)
			(size 0.1524 0.1524)
			(layers "B.Cu" "B.Mask" "B.Paste")
			(net "GND")
			(options
				(clearance outline)
				(anchor circle)
			)
			(primitives
				(gr_poly
					(pts
						(arc
							(start 0.3048 0.2032)
							(mid 0.275042 0.275042)
							(end 0.2032 0.3048)
						)
						(arc
							(start -0.2032 0.3048)
							(mid -0.275042 0.275042)
							(end -0.3048 0.2032)
						)
						(arc
							(start -0.3048 -0.2032)
							(mid -0.275042 -0.275042)
							(end -0.2032 -0.3048)
						)
						(arc
							(start 0.2032 -0.3048)
							(mid 0.275042 -0.275042)
							(end 0.3048 -0.2032)
						)
					)
					(width 0)
					(fill yes)
				)
			)
		)
	)
	(footprint ""
		(layer "B.Cu")
		(at 91.22029 -168.02227 -90)
		(property "Reference" "R419"
			(at 0 0 90)
			(layer "B.SilkS")
			(hide yes)
			(effects
				(font
					(size 1.27 1.27)
				)
				(justify mirror)
			)
		)
		(property "Value" "0R2J-2-GP"
			(at -0.064008 -3.993896 270)
			(unlocked yes)
			(layer "B.Fab")
			(hide yes)
			(effects
				(font
					(size 1.016 1.016)
					(thickness 0.1524)
				)
				(justify mirror)
			)
		)
		(property "Device Type" "R402H16"
			(at -0.064008 -5.517896 270)
			(unlocked yes)
			(layer "B.Fab")
			(hide yes)
			(effects
				(font
					(size 1.016 1.016)
					(thickness 0.1524)
				)
				(justify mirror)
			)
		)
		(duplicate_pad_numbers_are_jumpers no)
		(fp_line
			(start -0.508 -0.9398)
			(end 0.508 -0.9398)
			(stroke
				(width 0.1524)
				(type default)
			)
			(layer "B.SilkS")
		)
		(fp_line
			(start 0.508 -0.9398)
			(end 0.508 0.9398)
			(stroke
				(width 0.1524)
				(type default)
			)
			(layer "B.SilkS")
		)
		(fp_rect
			(start 0.508 0.9398)
			(end -0.508 -0.9398)
			(stroke
				(width 0)
				(type default)
			)
			(fill no)
			(layer "B.CrtYd")
		)
		(fp_rect
			(start 0.508 0.9398)
			(end -0.508 -0.9398)
			(stroke
				(width 0)
				(type default)
			)
			(fill no)
			(layer "B.Fab")
		)
		(pad "1" smd custom
			(at 0 -0.4445 90)
			(size 0.1397 0.1397)
			(layers "B.Cu" "B.Mask" "B.Paste")
			(net "UART_COMP_RX")
			(options
				(clearance outline)
				(anchor circle)
			)
			(primitives
				(gr_poly
					(pts
						(arc
							(start -0.1778 0.2794)
							(mid -0.249642 0.249642)
							(end -0.2794 0.1778)
						)
						(arc
							(start -0.2794 -0.1778)
							(mid -0.249642 -0.249642)
							(end -0.1778 -0.2794)
						)
						(arc
							(start 0.1778 -0.2794)
							(mid 0.249642 -0.249642)
							(end 0.2794 -0.1778)
						)
						(arc
							(start 0.2794 0.1778)
							(mid 0.249642 0.249642)
							(end 0.1778 0.2794)
						)
					)
					(width 0)
					(fill yes)
				)
			)
		)
		(pad "2" smd custom
			(at 0 0.4445 90)
			(size 0.1397 0.1397)
			(layers "B.Cu" "B.Mask" "B.Paste")
			(net "UART_COMP_R_RX")
			(options
				(clearance outline)
				(anchor circle)
			)
			(primitives
				(gr_poly
					(pts
						(arc
							(start -0.1778 0.2794)
							(mid -0.249642 0.249642)
							(end -0.2794 0.1778)
						)
						(arc
							(start -0.2794 -0.1778)
							(mid -0.249642 -0.249642)
							(end -0.1778 -0.2794)
						)
						(arc
							(start 0.1778 -0.2794)
							(mid 0.249642 -0.249642)
							(end 0.2794 -0.1778)
						)
						(arc
							(start 0.2794 0.1778)
							(mid 0.249642 0.249642)
							(end 0.1778 0.2794)
						)
					)
					(width 0)
					(fill yes)
				)
			)
		)
	)
	(footprint ""
		(layer "B.Cu")
		(at 36.531042 -155.916884)
		(property "Reference" "C519"
			(at 0 0 0)
			(layer "B.SilkS")
			(hide yes)
			(effects
				(font
					(size 1.27 1.27)
				)
				(justify mirror)
			)
		)
		(property "Value" "SCD1U25V2KX-2-GP"
			(at -1.1811 -2.7051 0)
			(unlocked yes)
			(layer "B.Fab")
			(hide yes)
			(effects
				(font
					(size 1.016 1.016)
					(thickness 0.1524)
				)
				(justify mirror)
			)
		)
		(property "Device Type" "C402H22"
			(at -1.1811 -4.2291 0)
			(unlocked yes)
			(layer "B.Fab")
			(hide yes)
			(effects
				(font
					(size 1.016 1.016)
					(thickness 0.1524)
				)
				(justify mirror)
			)
		)
		(duplicate_pad_numbers_are_jumpers no)
		(fp_rect
			(start 0.4318 0.9525)
			(end -0.4318 -0.9525)
			(stroke
				(width 0)
				(type default)
			)
			(fill no)
			(layer "B.CrtYd")
		)
		(fp_rect
			(start 0.4318 0.9525)
			(end -0.4318 -0.9525)
			(stroke
				(width 0)
				(type default)
			)
			(fill no)
			(layer "B.Fab")
		)
		(pad "1" smd custom
			(at 0 -0.4445 180)
			(size 0.1524 0.1524)
			(layers "B.Cu" "B.Mask" "B.Paste")
			(net "ADC_P1V2_STBY")
			(options
				(clearance outline)
				(anchor circle)
			)
			(primitives
				(gr_poly
					(pts
						(arc
							(start 0.3048 0.2032)
							(mid 0.275042 0.275042)
							(end 0.2032 0.3048)
						)
						(arc
							(start -0.2032 0.3048)
							(mid -0.275042 0.275042)
							(end -0.3048 0.2032)
						)
						(arc
							(start -0.3048 -0.2032)
							(mid -0.275042 -0.275042)
							(end -0.2032 -0.3048)
						)
						(arc
							(start 0.2032 -0.3048)
							(mid 0.275042 -0.275042)
							(end 0.3048 -0.2032)
						)
					)
					(width 0)
					(fill yes)
				)
			)
		)
		(pad "2" smd custom
			(at 0 0.4445 180)
			(size 0.1524 0.1524)
			(layers "B.Cu" "B.Mask" "B.Paste")
			(net "GND")
			(options
				(clearance outline)
				(anchor circle)
			)
			(primitives
				(gr_poly
					(pts
						(arc
							(start 0.3048 0.2032)
							(mid 0.275042 0.275042)
							(end 0.2032 0.3048)
						)
						(arc
							(start -0.2032 0.3048)
							(mid -0.275042 0.275042)
							(end -0.3048 0.2032)
						)
						(arc
							(start -0.3048 -0.2032)
							(mid -0.275042 -0.275042)
							(end -0.2032 -0.3048)
						)
						(arc
							(start 0.2032 -0.3048)
							(mid 0.275042 -0.275042)
							(end 0.3048 -0.2032)
						)
					)
					(width 0)
					(fill yes)
				)
			)
		)
	)
	(footprint ""
		(layer "B.Cu")
		(at 36.4998 -120.3452 180)
		(property "Reference" "R90"
			(at 0 0 0)
			(layer "B.SilkS")
			(hide yes)
			(effects
				(font
					(size 1.27 1.27)
				)
				(justify mirror)
			)
		)
		(property "Value" "2K2R2J-2-GP"
			(at -0.064008 -3.993896 180)
			(unlocked yes)
			(layer "B.Fab")
			(hide yes)
			(effects
				(font
					(size 1.016 1.016)
					(thickness 0.1524)
				)
				(justify mirror)
			)
		)
		(property "Device Type" "R402H16"
			(at -0.064008 -5.517896 180)
			(unlocked yes)
			(layer "B.Fab")
			(hide yes)
			(effects
				(font
					(size 1.016 1.016)
					(thickness 0.1524)
				)
				(justify mirror)
			)
		)
		(duplicate_pad_numbers_are_jumpers no)
		(fp_line
			(start 0.508 -0.9398)
			(end 0.508 0.9398)
			(stroke
				(width 0.1524)
				(type default)
			)
			(layer "B.SilkS")
		)
		(fp_line
			(start -0.508 -0.9398)
			(end 0.508 -0.9398)
			(stroke
				(width 0.1524)
				(type default)
			)
			(layer "B.SilkS")
		)
		(fp_rect
			(start 0.508 0.9398)
			(end -0.508 -0.9398)
			(stroke
				(width 0)
				(type default)
			)
			(fill no)
			(layer "B.CrtYd")
		)
		(fp_rect
			(start 0.508 0.9398)
			(end -0.508 -0.9398)
			(stroke
				(width 0)
				(type default)
			)
			(fill no)
			(layer "B.Fab")
		)
		(pad "1" smd custom
			(at 0 -0.4445)
			(size 0.1397 0.1397)
			(layers "B.Cu" "B.Mask" "B.Paste")
			(net "P3V3_STBY")
			(options
				(clearance outline)
				(anchor circle)
			)
			(primitives
				(gr_poly
					(pts
						(arc
							(start -0.1778 0.2794)
							(mid -0.249642 0.249642)
							(end -0.2794 0.1778)
						)
						(arc
							(start -0.2794 -0.1778)
							(mid -0.249642 -0.249642)
							(end -0.1778 -0.2794)
						)
						(arc
							(start 0.1778 -0.2794)
							(mid 0.249642 -0.249642)
							(end 0.2794 -0.1778)
						)
						(arc
							(start 0.2794 0.1778)
							(mid 0.249642 0.249642)
							(end 0.1778 0.2794)
						)
					)
					(width 0)
					(fill yes)
				)
			)
		)
		(pad "2" smd custom
			(at 0 0.4445)
			(size 0.1397 0.1397)
			(layers "B.Cu" "B.Mask" "B.Paste")
			(net "BMC_CPU_EN")
			(options
				(clearance outline)
				(anchor circle)
			)
			(primitives
				(gr_poly
					(pts
						(arc
							(start -0.1778 0.2794)
							(mid -0.249642 0.249642)
							(end -0.2794 0.1778)
						)
						(arc
							(start -0.2794 -0.1778)
							(mid -0.249642 -0.249642)
							(end -0.1778 -0.2794)
						)
						(arc
							(start 0.1778 -0.2794)
							(mid 0.249642 -0.249642)
							(end 0.2794 -0.1778)
						)
						(arc
							(start 0.2794 0.1778)
							(mid 0.249642 0.249642)
							(end 0.1778 0.2794)
						)
					)
					(width 0)
					(fill yes)
				)
			)
		)
	)
	(footprint ""
		(layer "B.Cu")
		(at 25.557226 -143.81099 180)
		(property "Reference" "C70"
			(at 0 0 0)
			(layer "B.SilkS")
			(hide yes)
			(effects
				(font
					(size 1.27 1.27)
				)
				(justify mirror)
			)
		)
		(property "Value" "SCD1U16V2KX-3GP"
			(at -1.1811 -2.7051 180)
			(unlocked yes)
			(layer "B.Fab")
			(hide yes)
			(effects
				(font
					(size 1.016 1.016)
					(thickness 0.1524)
				)
				(justify mirror)
			)
		)
		(property "Device Type" "C402H22"
			(at -1.1811 -4.2291 180)
			(unlocked yes)
			(layer "B.Fab")
			(hide yes)
			(effects
				(font
					(size 1.016 1.016)
					(thickness 0.1524)
				)
				(justify mirror)
			)
		)
		(duplicate_pad_numbers_are_jumpers no)
		(fp_rect
			(start 0.4318 0.9525)
			(end -0.4318 -0.9525)
			(stroke
				(width 0)
				(type default)
			)
			(fill no)
			(layer "B.CrtYd")
		)
		(fp_rect
			(start 0.4318 0.9525)
			(end -0.4318 -0.9525)
			(stroke
				(width 0)
				(type default)
			)
			(fill no)
			(layer "B.Fab")
		)
		(pad "1" smd custom
			(at 0 -0.4445)
			(size 0.1524 0.1524)
			(layers "B.Cu" "B.Mask" "B.Paste")
			(net "GND")
			(options
				(clearance outline)
				(anchor circle)
			)
			(primitives
				(gr_poly
					(pts
						(arc
							(start 0.3048 0.2032)
							(mid 0.275042 0.275042)
							(end 0.2032 0.3048)
						)
						(arc
							(start -0.2032 0.3048)
							(mid -0.275042 0.275042)
							(end -0.3048 0.2032)
						)
						(arc
							(start -0.3048 -0.2032)
							(mid -0.275042 -0.275042)
							(end -0.2032 -0.3048)
						)
						(arc
							(start 0.2032 -0.3048)
							(mid 0.275042 -0.275042)
							(end 0.3048 -0.2032)
						)
					)
					(width 0)
					(fill yes)
				)
			)
		)
		(pad "2" smd custom
			(at 0 0.4445)
			(size 0.1524 0.1524)
			(layers "B.Cu" "B.Mask" "B.Paste")
			(net "P1V2_STBY")
			(options
				(clearance outline)
				(anchor circle)
			)
			(primitives
				(gr_poly
					(pts
						(arc
							(start 0.3048 0.2032)
							(mid 0.275042 0.275042)
							(end 0.2032 0.3048)
						)
						(arc
							(start -0.2032 0.3048)
							(mid -0.275042 0.275042)
							(end -0.3048 0.2032)
						)
						(arc
							(start -0.3048 -0.2032)
							(mid -0.275042 -0.275042)
							(end -0.2032 -0.3048)
						)
						(arc
							(start 0.2032 -0.3048)
							(mid 0.275042 -0.275042)
							(end 0.3048 -0.2032)
						)
					)
					(width 0)
					(fill yes)
				)
			)
		)
	)
	(footprint ""
		(layer "B.Cu")
		(at 177.63871 -130.671062 180)
		(property "Reference" "C614"
			(at 0 0 0)
			(layer "B.SilkS")
			(hide yes)
			(effects
				(font
					(size 1.27 1.27)
				)
				(justify mirror)
			)
		)
		(property "Value" "SC10U6D3V5KX-4GP"
			(at 0.0762 -6.1214 180)
			(unlocked yes)
			(layer "B.Fab")
			(hide yes)
			(effects
				(font
					(size 1.016 1.016)
					(thickness 0.1524)
				)
				(justify mirror)
			)
		)
		(property "Device Type" "C805H58"
			(at 0.0762 -8.1534 180)
			(unlocked yes)
			(layer "B.Fab")
			(hide yes)
			(effects
				(font
					(size 1.016 1.016)
					(thickness 0.1524)
				)
				(justify mirror)
			)
		)
		(duplicate_pad_numbers_are_jumpers no)
		(fp_line
			(start -0.635 0)
			(end 0.635 0)
			(stroke
				(width 0.508)
				(type default)
			)
			(layer "B.SilkS")
		)
		(fp_rect
			(start 0.9652 1.778)
			(end -0.9652 -1.778)
			(stroke
				(width 0)
				(type default)
			)
			(fill no)
			(layer "B.CrtYd")
		)
		(fp_poly
			(pts
				(xy 0.9652 -1.778) (xy -0.9652 -1.778) (xy -0.9652 1.778) (xy 0.9652 1.778)
			)
			(stroke
				(width 0)
				(type default)
			)
			(fill no)
			(layer "B.Fab")
		)
		(pad "1" smd rect
			(at 0 -0.9652)
			(size 1.397 1.143)
			(layers "B.Cu" "B.Mask" "B.Paste")
			(net "P3V3_M2")
		)
		(pad "2" smd rect
			(at 0 0.9652)
			(size 1.397 1.143)
			(layers "B.Cu" "B.Mask" "B.Paste")
			(net "GND")
		)
	)
	(footprint ""
		(layer "B.Cu")
		(at 73.408794 -140.527024 90)
		(property "Reference" "C83"
			(at 0 0 90)
			(layer "B.SilkS")
			(hide yes)
			(effects
				(font
					(size 1.27 1.27)
				)
				(justify mirror)
			)
		)
		(property "Value" "SC1U16V3KX-5GP"
			(at 0 -2.8194 90)
			(unlocked yes)
			(layer "B.Fab")
			(hide yes)
			(effects
				(font
					(size 1.016 1.016)
					(thickness 0.1524)
				)
				(justify mirror)
			)
		)
		(property "Device Type" "C603H36"
			(at 0 -4.3434 90)
			(unlocked yes)
			(layer "B.Fab")
			(hide yes)
			(effects
				(font
					(size 1.016 1.016)
					(thickness 0.1524)
				)
				(justify mirror)
			)
		)
		(duplicate_pad_numbers_are_jumpers no)
		(fp_line
			(start -0.508 0)
			(end 0.508 0)
			(stroke
				(width 0.2032)
				(type default)
			)
			(layer "B.SilkS")
		)
		(fp_rect
			(start 0.5842 1.3335)
			(end -0.5842 -1.3335)
			(stroke
				(width 0)
				(type default)
			)
			(fill no)
			(layer "B.CrtYd")
		)
		(fp_rect
			(start 0.5842 1.3335)
			(end -0.5842 -1.3335)
			(stroke
				(width 0)
				(type default)
			)
			(fill no)
			(layer "B.Fab")
		)
		(pad "1" smd custom
			(at 0 -0.762 270)
			(size 0.2159 0.2159)
			(layers "B.Cu" "B.Mask" "B.Paste")
			(net "JTAG_BMC_TRST_N")
			(options
				(clearance outline)
				(anchor circle)
			)
			(primitives
				(gr_poly
					(pts
						(arc
							(start -0.3302 0.4318)
							(mid -0.402042 0.402042)
							(end -0.4318 0.3302)
						)
						(arc
							(start -0.4318 -0.3302)
							(mid -0.402042 -0.402042)
							(end -0.3302 -0.4318)
						)
						(arc
							(start 0.3302 -0.4318)
							(mid 0.402042 -0.402042)
							(end 0.4318 -0.3302)
						)
						(arc
							(start 0.4318 0.3302)
							(mid 0.402042 0.402042)
							(end 0.3302 0.4318)
						)
					)
					(width 0)
					(fill yes)
				)
			)
		)
		(pad "2" smd custom
			(at 0 0.762 270)
			(size 0.2159 0.2159)
			(layers "B.Cu" "B.Mask" "B.Paste")
			(net "GND")
			(options
				(clearance outline)
				(anchor circle)
			)
			(primitives
				(gr_poly
					(pts
						(arc
							(start -0.3302 0.4318)
							(mid -0.402042 0.402042)
							(end -0.4318 0.3302)
						)
						(arc
							(start -0.4318 -0.3302)
							(mid -0.402042 -0.402042)
							(end -0.3302 -0.4318)
						)
						(arc
							(start 0.3302 -0.4318)
							(mid 0.402042 -0.402042)
							(end 0.4318 -0.3302)
						)
						(arc
							(start 0.4318 0.3302)
							(mid 0.402042 0.402042)
							(end 0.3302 0.4318)
						)
					)
					(width 0)
					(fill yes)
				)
			)
		)
	)
	(footprint ""
		(layer "B.Cu")
		(at 129.286 -16.51 -90)
		(property "Reference" "R446"
			(at 0 0 90)
			(layer "B.SilkS")
			(hide yes)
			(effects
				(font
					(size 1.27 1.27)
				)
				(justify mirror)
			)
		)
		(property "Value" "49K9R2F-L-GP"
			(at -0.064008 -3.993896 270)
			(unlocked yes)
			(layer "B.Fab")
			(hide yes)
			(effects
				(font
					(size 1.016 1.016)
					(thickness 0.1524)
				)
				(justify mirror)
			)
		)
		(property "Device Type" "R402H16"
			(at -0.064008 -5.517896 270)
			(unlocked yes)
			(layer "B.Fab")
			(hide yes)
			(effects
				(font
					(size 1.016 1.016)
					(thickness 0.1524)
				)
				(justify mirror)
			)
		)
		(duplicate_pad_numbers_are_jumpers no)
		(fp_line
			(start -0.508 -0.9398)
			(end 0.508 -0.9398)
			(stroke
				(width 0.1524)
				(type default)
			)
			(layer "B.SilkS")
		)
		(fp_line
			(start 0.508 -0.9398)
			(end 0.508 0.9398)
			(stroke
				(width 0.1524)
				(type default)
			)
			(layer "B.SilkS")
		)
		(fp_rect
			(start 0.508 0.9398)
			(end -0.508 -0.9398)
			(stroke
				(width 0)
				(type default)
			)
			(fill no)
			(layer "B.CrtYd")
		)
		(fp_rect
			(start 0.508 0.9398)
			(end -0.508 -0.9398)
			(stroke
				(width 0)
				(type default)
			)
			(fill no)
			(layer "B.Fab")
		)
		(pad "1" smd custom
			(at 0 -0.4445 90)
			(size 0.1397 0.1397)
			(layers "B.Cu" "B.Mask" "B.Paste")
			(net "P12V_IOM")
			(options
				(clearance outline)
				(anchor circle)
			)
			(primitives
				(gr_poly
					(pts
						(arc
							(start -0.1778 0.2794)
							(mid -0.249642 0.249642)
							(end -0.2794 0.1778)
						)
						(arc
							(start -0.2794 -0.1778)
							(mid -0.249642 -0.249642)
							(end -0.1778 -0.2794)
						)
						(arc
							(start 0.1778 -0.2794)
							(mid 0.249642 -0.249642)
							(end 0.2794 -0.1778)
						)
						(arc
							(start 0.2794 0.1778)
							(mid 0.249642 0.249642)
							(end 0.1778 0.2794)
						)
					)
					(width 0)
					(fill yes)
				)
			)
		)
		(pad "2" smd custom
			(at 0 0.4445 90)
			(size 0.1397 0.1397)
			(layers "B.Cu" "B.Mask" "B.Paste")
			(net "MB0_CM_UV_R")
			(options
				(clearance outline)
				(anchor circle)
			)
			(primitives
				(gr_poly
					(pts
						(arc
							(start -0.1778 0.2794)
							(mid -0.249642 0.249642)
							(end -0.2794 0.1778)
						)
						(arc
							(start -0.2794 -0.1778)
							(mid -0.249642 -0.249642)
							(end -0.1778 -0.2794)
						)
						(arc
							(start 0.1778 -0.2794)
							(mid 0.249642 -0.249642)
							(end 0.2794 -0.1778)
						)
						(arc
							(start 0.2794 0.1778)
							(mid 0.249642 0.249642)
							(end 0.1778 0.2794)
						)
					)
					(width 0)
					(fill yes)
				)
			)
		)
	)
	(footprint ""
		(layer "B.Cu")
		(at 93.2688 -143.129 -90)
		(property "Reference" "Q26"
			(at 0 0 90)
			(layer "B.SilkS")
			(hide yes)
			(effects
				(font
					(size 1.27 1.27)
				)
				(justify mirror)
			)
		)
		(property "Value" "2N7002K-1-GP"
			(at -0.127 -8.9662 270)
			(unlocked yes)
			(layer "B.Fab")
			(hide yes)
			(effects
				(font
					(size 1.016 1.016)
					(thickness 0.1524)
				)
				(justify mirror)
			)
		)
		(property "Device Type" "SOT23DGS2D4H44"
			(at -0.127 -10.4902 270)
			(unlocked yes)
			(layer "B.Fab")
			(hide yes)
			(effects
				(font
					(size 1.016 1.016)
					(thickness 0.1524)
				)
				(justify mirror)
			)
		)
		(duplicate_pad_numbers_are_jumpers no)
		(fp_line
			(start -1.651 1.778)
			(end -1.651 -1.778)
			(stroke
				(width 0.1524)
				(type default)
			)
			(layer "B.SilkS")
		)
		(fp_line
			(start 1.651 1.778)
			(end -1.651 1.778)
			(stroke
				(width 0.1524)
				(type default)
			)
			(layer "B.SilkS")
		)
		(fp_line
			(start -1.651 -1.778)
			(end 1.651 -1.778)
			(stroke
				(width 0.1524)
				(type default)
			)
			(layer "B.SilkS")
		)
		(fp_line
			(start 1.651 -1.778)
			(end 1.651 1.778)
			(stroke
				(width 0.1524)
				(type default)
			)
			(layer "B.SilkS")
		)
		(fp_poly
			(pts
				(xy 1.778 1.8796) (xy 1.778 -1.8796) (xy -1.778 -1.8796) (xy -1.778 1.8796)
			)
			(stroke
				(width 0)
				(type default)
			)
			(fill no)
			(layer "B.CrtYd")
		)
		(fp_poly
			(pts
				(xy 1.778 1.8796) (xy 1.778 -1.8796) (xy -1.778 -1.8796) (xy -1.778 1.8796)
			)
			(stroke
				(width 0)
				(type default)
			)
			(fill no)
			(layer "B.Fab")
		)
		(pad "D" smd custom
			(at 0 -0.9525 90)
			(size 0.1905 0.1905)
			(layers "B.Cu" "B.Mask" "B.Paste")
			(net "DB_PRSNT_BMC_N")
			(options
				(clearance outline)
				(anchor circle)
			)
			(primitives
				(gr_poly
					(pts
						(arc
							(start -0.1778 -0.5715)
							(mid -0.321484 -0.511984)
							(end -0.381 -0.3683)
						)
						(arc
							(start -0.381 0.3683)
							(mid -0.321484 0.511984)
							(end -0.1778 0.5715)
						)
						(arc
							(start 0.1778 0.5715)
							(mid 0.321484 0.511984)
							(end 0.381 0.3683)
						)
						(arc
							(start 0.381 -0.3683)
							(mid 0.321484 -0.511984)
							(end 0.1778 -0.5715)
						)
					)
					(width 0)
					(fill yes)
				)
			)
		)
		(pad "G" smd custom
			(at 0.98425 0.9525 90)
			(size 0.1905 0.1905)
			(layers "B.Cu" "B.Mask" "B.Paste")
			(net "DEBUG_CARD_PRSNT")
			(options
				(clearance outline)
				(anchor circle)
			)
			(primitives
				(gr_poly
					(pts
						(arc
							(start -0.1778 -0.5715)
							(mid -0.321484 -0.511984)
							(end -0.381 -0.3683)
						)
						(arc
							(start -0.381 0.3683)
							(mid -0.321484 0.511984)
							(end -0.1778 0.5715)
						)
						(arc
							(start 0.1778 0.5715)
							(mid 0.321484 0.511984)
							(end 0.381 0.3683)
						)
						(arc
							(start 0.381 -0.3683)
							(mid 0.321484 -0.511984)
							(end 0.1778 -0.5715)
						)
					)
					(width 0)
					(fill yes)
				)
			)
		)
		(pad "S" smd custom
			(at -0.98425 0.9525 90)
			(size 0.1905 0.1905)
			(layers "B.Cu" "B.Mask" "B.Paste")
			(net "GND")
			(options
				(clearance outline)
				(anchor circle)
			)
			(primitives
				(gr_poly
					(pts
						(arc
							(start -0.1778 -0.5715)
							(mid -0.321484 -0.511984)
							(end -0.381 -0.3683)
						)
						(arc
							(start -0.381 0.3683)
							(mid -0.321484 0.511984)
							(end -0.1778 0.5715)
						)
						(arc
							(start 0.1778 0.5715)
							(mid 0.321484 0.511984)
							(end 0.381 0.3683)
						)
						(arc
							(start 0.381 -0.3683)
							(mid 0.321484 -0.511984)
							(end 0.1778 -0.5715)
						)
					)
					(width 0)
					(fill yes)
				)
			)
		)
	)
	(footprint ""
		(layer "B.Cu")
		(at 16.6116 -139.1412 180)
		(property "Reference" "C68"
			(at 0 0 0)
			(layer "B.SilkS")
			(hide yes)
			(effects
				(font
					(size 1.27 1.27)
				)
				(justify mirror)
			)
		)
		(property "Value" "SCD1U16V2KX-3GP"
			(at -1.1811 -2.7051 180)
			(unlocked yes)
			(layer "B.Fab")
			(hide yes)
			(effects
				(font
					(size 1.016 1.016)
					(thickness 0.1524)
				)
				(justify mirror)
			)
		)
		(property "Device Type" "C402H22"
			(at -1.1811 -4.2291 180)
			(unlocked yes)
			(layer "B.Fab")
			(hide yes)
			(effects
				(font
					(size 1.016 1.016)
					(thickness 0.1524)
				)
				(justify mirror)
			)
		)
		(duplicate_pad_numbers_are_jumpers no)
		(fp_rect
			(start 0.4318 0.9525)
			(end -0.4318 -0.9525)
			(stroke
				(width 0)
				(type default)
			)
			(fill no)
			(layer "B.CrtYd")
		)
		(fp_rect
			(start 0.4318 0.9525)
			(end -0.4318 -0.9525)
			(stroke
				(width 0)
				(type default)
			)
			(fill no)
			(layer "B.Fab")
		)
		(pad "1" smd custom
			(at 0 -0.4445)
			(size 0.1524 0.1524)
			(layers "B.Cu" "B.Mask" "B.Paste")
			(net "GND")
			(options
				(clearance outline)
				(anchor circle)
			)
			(primitives
				(gr_poly
					(pts
						(arc
							(start 0.3048 0.2032)
							(mid 0.275042 0.275042)
							(end 0.2032 0.3048)
						)
						(arc
							(start -0.2032 0.3048)
							(mid -0.275042 0.275042)
							(end -0.3048 0.2032)
						)
						(arc
							(start -0.3048 -0.2032)
							(mid -0.275042 -0.275042)
							(end -0.2032 -0.3048)
						)
						(arc
							(start 0.2032 -0.3048)
							(mid 0.275042 -0.275042)
							(end 0.3048 -0.2032)
						)
					)
					(width 0)
					(fill yes)
				)
			)
		)
		(pad "2" smd custom
			(at 0 0.4445)
			(size 0.1524 0.1524)
			(layers "B.Cu" "B.Mask" "B.Paste")
			(net "DDR_VREF")
			(options
				(clearance outline)
				(anchor circle)
			)
			(primitives
				(gr_poly
					(pts
						(arc
							(start 0.3048 0.2032)
							(mid 0.275042 0.275042)
							(end 0.2032 0.3048)
						)
						(arc
							(start -0.2032 0.3048)
							(mid -0.275042 0.275042)
							(end -0.3048 0.2032)
						)
						(arc
							(start -0.3048 -0.2032)
							(mid -0.275042 -0.275042)
							(end -0.2032 -0.3048)
						)
						(arc
							(start 0.2032 -0.3048)
							(mid 0.275042 -0.275042)
							(end 0.3048 -0.2032)
						)
					)
					(width 0)
					(fill yes)
				)
			)
		)
	)
	(footprint ""
		(layer "B.Cu")
		(at 222.452692 -99.449382 90)
		(property "Reference" "R832"
			(at 0 0 90)
			(layer "B.SilkS")
			(hide yes)
			(effects
				(font
					(size 1.27 1.27)
				)
				(justify mirror)
			)
		)
		(property "Value" "2D2R3-1-U-GP"
			(at 0.0254 -2.5146 90)
			(unlocked yes)
			(layer "B.Fab")
			(hide yes)
			(effects
				(font
					(size 1.016 1.016)
					(thickness 0.1524)
				)
				(justify mirror)
			)
		)
		(property "Device Type" "R603H22"
			(at 0.0254 -4.0386 90)
			(unlocked yes)
			(layer "B.Fab")
			(hide yes)
			(effects
				(font
					(size 1.016 1.016)
					(thickness 0.1524)
				)
				(justify mirror)
			)
		)
		(duplicate_pad_numbers_are_jumpers no)
		(fp_line
			(start 0.4826 0)
			(end 0.2032 0)
			(stroke
				(width 0.2032)
				(type default)
			)
			(layer "B.SilkS")
		)
		(fp_line
			(start -0.2032 0)
			(end -0.4826 0)
			(stroke
				(width 0.2032)
				(type default)
			)
			(layer "B.SilkS")
		)
		(fp_rect
			(start 0.5842 1.3335)
			(end -0.5842 -1.3335)
			(stroke
				(width 0)
				(type default)
			)
			(fill no)
			(layer "B.CrtYd")
		)
		(fp_rect
			(start 0.5842 1.3335)
			(end -0.5842 -1.3335)
			(stroke
				(width 0)
				(type default)
			)
			(fill no)
			(layer "B.Fab")
		)
		(pad "1" smd custom
			(at 0 -0.762 270)
			(size 0.2159 0.2159)
			(layers "B.Cu" "B.Mask" "B.Paste")
			(net "P12V_STBY_VDD_U81")
			(options
				(clearance outline)
				(anchor circle)
			)
			(primitives
				(gr_poly
					(pts
						(arc
							(start -0.3302 0.4318)
							(mid -0.402042 0.402042)
							(end -0.4318 0.3302)
						)
						(arc
							(start -0.4318 -0.3302)
							(mid -0.402042 -0.402042)
							(end -0.3302 -0.4318)
						)
						(arc
							(start 0.3302 -0.4318)
							(mid 0.402042 -0.402042)
							(end 0.4318 -0.3302)
						)
						(arc
							(start 0.4318 0.3302)
							(mid 0.402042 0.402042)
							(end 0.3302 0.4318)
						)
					)
					(width 0)
					(fill yes)
				)
			)
		)
		(pad "2" smd custom
			(at 0 0.762 270)
			(size 0.2159 0.2159)
			(layers "B.Cu" "B.Mask" "B.Paste")
			(net "P12V_STBY")
			(options
				(clearance outline)
				(anchor circle)
			)
			(primitives
				(gr_poly
					(pts
						(arc
							(start -0.3302 0.4318)
							(mid -0.402042 0.402042)
							(end -0.4318 0.3302)
						)
						(arc
							(start -0.4318 -0.3302)
							(mid -0.402042 -0.402042)
							(end -0.3302 -0.4318)
						)
						(arc
							(start 0.3302 -0.4318)
							(mid 0.402042 -0.402042)
							(end 0.4318 -0.3302)
						)
						(arc
							(start 0.4318 0.3302)
							(mid 0.402042 0.402042)
							(end 0.3302 0.4318)
						)
					)
					(width 0)
					(fill yes)
				)
			)
		)
	)
	(footprint ""
		(layer "B.Cu")
		(at 49.458372 -158.570676 180)
		(property "Reference" "R297"
			(at 0 0 0)
			(layer "B.SilkS")
			(hide yes)
			(effects
				(font
					(size 1.27 1.27)
				)
				(justify mirror)
			)
		)
		(property "Value" "0R2J-2-GP"
			(at -0.064008 -3.993896 180)
			(unlocked yes)
			(layer "B.Fab")
			(hide yes)
			(effects
				(font
					(size 1.016 1.016)
					(thickness 0.1524)
				)
				(justify mirror)
			)
		)
		(property "Device Type" "R402H16"
			(at -0.064008 -5.517896 180)
			(unlocked yes)
			(layer "B.Fab")
			(hide yes)
			(effects
				(font
					(size 1.016 1.016)
					(thickness 0.1524)
				)
				(justify mirror)
			)
		)
		(duplicate_pad_numbers_are_jumpers no)
		(fp_line
			(start 0.508 -0.9398)
			(end 0.508 0.9398)
			(stroke
				(width 0.1524)
				(type default)
			)
			(layer "B.SilkS")
		)
		(fp_line
			(start -0.508 -0.9398)
			(end 0.508 -0.9398)
			(stroke
				(width 0.1524)
				(type default)
			)
			(layer "B.SilkS")
		)
		(fp_rect
			(start 0.508 0.9398)
			(end -0.508 -0.9398)
			(stroke
				(width 0)
				(type default)
			)
			(fill no)
			(layer "B.CrtYd")
		)
		(fp_rect
			(start 0.508 0.9398)
			(end -0.508 -0.9398)
			(stroke
				(width 0)
				(type default)
			)
			(fill no)
			(layer "B.Fab")
		)
		(pad "1" smd custom
			(at 0 -0.4445)
			(size 0.1397 0.1397)
			(layers "B.Cu" "B.Mask" "B.Paste")
			(net "UART_BMC_R_TX")
			(options
				(clearance outline)
				(anchor circle)
			)
			(primitives
				(gr_poly
					(pts
						(arc
							(start -0.1778 0.2794)
							(mid -0.249642 0.249642)
							(end -0.2794 0.1778)
						)
						(arc
							(start -0.2794 -0.1778)
							(mid -0.249642 -0.249642)
							(end -0.1778 -0.2794)
						)
						(arc
							(start 0.1778 -0.2794)
							(mid 0.249642 -0.249642)
							(end 0.2794 -0.1778)
						)
						(arc
							(start 0.2794 0.1778)
							(mid 0.249642 0.249642)
							(end 0.1778 0.2794)
						)
					)
					(width 0)
					(fill yes)
				)
			)
		)
		(pad "2" smd custom
			(at 0 0.4445)
			(size 0.1397 0.1397)
			(layers "B.Cu" "B.Mask" "B.Paste")
			(net "UART_BMC_TX")
			(options
				(clearance outline)
				(anchor circle)
			)
			(primitives
				(gr_poly
					(pts
						(arc
							(start -0.1778 0.2794)
							(mid -0.249642 0.249642)
							(end -0.2794 0.1778)
						)
						(arc
							(start -0.2794 -0.1778)
							(mid -0.249642 -0.249642)
							(end -0.1778 -0.2794)
						)
						(arc
							(start 0.1778 -0.2794)
							(mid 0.249642 -0.249642)
							(end 0.2794 -0.1778)
						)
						(arc
							(start 0.2794 0.1778)
							(mid 0.249642 0.249642)
							(end 0.1778 0.2794)
						)
					)
					(width 0)
					(fill yes)
				)
			)
		)
	)
	(footprint ""
		(layer "B.Cu")
		(at 61.4172 -157.5308 180)
		(property "Reference" "L2"
			(at 0 0 0)
			(layer "B.SilkS")
			(hide yes)
			(effects
				(font
					(size 1.27 1.27)
				)
				(justify mirror)
			)
		)
		(property "Value" "MMZ2012S601ATA1N-GP"
			(at 0 -4.2418 180)
			(unlocked yes)
			(layer "B.Fab")
			(hide yes)
			(effects
				(font
					(size 1.016 1.016)
					(thickness 0.1524)
				)
				(justify mirror)
			)
		)
		(property "Device Type" "L805H42"
			(at 0 -5.7912 180)
			(unlocked yes)
			(layer "B.Fab")
			(hide yes)
			(effects
				(font
					(size 1.016 1.016)
					(thickness 0.1524)
				)
				(justify mirror)
			)
		)
		(duplicate_pad_numbers_are_jumpers no)
		(fp_line
			(start 0.889 1.7018)
			(end 0.889 -1.7018)
			(stroke
				(width 0.1524)
				(type default)
			)
			(layer "B.SilkS")
		)
		(fp_line
			(start 0.889 -1.7018)
			(end -0.889 -1.7018)
			(stroke
				(width 0.1524)
				(type default)
			)
			(layer "B.SilkS")
		)
		(fp_line
			(start -0.889 1.7018)
			(end 0.889 1.7018)
			(stroke
				(width 0.1524)
				(type default)
			)
			(layer "B.SilkS")
		)
		(fp_line
			(start -0.889 -1.7018)
			(end -0.889 1.7018)
			(stroke
				(width 0.1524)
				(type default)
			)
			(layer "B.SilkS")
		)
		(fp_rect
			(start 0.9652 1.778)
			(end -0.9652 -1.778)
			(stroke
				(width 0)
				(type default)
			)
			(fill no)
			(layer "B.CrtYd")
		)
		(fp_rect
			(start 0.9652 1.778)
			(end -0.9652 -1.778)
			(stroke
				(width 0)
				(type default)
			)
			(fill no)
			(layer "B.Fab")
		)
		(pad "1" smd rect
			(at 0 -0.9652)
			(size 1.397 1.143)
			(layers "B.Cu" "B.Mask" "B.Paste")
			(net "P3V3_STBY")
		)
		(pad "2" smd rect
			(at 0 0.9652)
			(size 1.397 1.143)
			(layers "B.Cu" "B.Mask" "B.Paste")
			(net "ADCAV33")
		)
	)
	(footprint ""
		(layer "B.Cu")
		(at 83.9724 -128.9304)
		(property "Reference" "R718"
			(at 0 0 0)
			(layer "B.SilkS")
			(hide yes)
			(effects
				(font
					(size 1.27 1.27)
				)
				(justify mirror)
			)
		)
		(property "Value" "0R2J-2-GP"
			(at -0.064008 -3.993896 0)
			(unlocked yes)
			(layer "B.Fab")
			(hide yes)
			(effects
				(font
					(size 1.016 1.016)
					(thickness 0.1524)
				)
				(justify mirror)
			)
		)
		(property "Device Type" "R402H16"
			(at -0.064008 -5.517896 0)
			(unlocked yes)
			(layer "B.Fab")
			(hide yes)
			(effects
				(font
					(size 1.016 1.016)
					(thickness 0.1524)
				)
				(justify mirror)
			)
		)
		(duplicate_pad_numbers_are_jumpers no)
		(fp_line
			(start -0.508 -0.9398)
			(end 0.508 -0.9398)
			(stroke
				(width 0.1524)
				(type default)
			)
			(layer "B.SilkS")
		)
		(fp_line
			(start 0.508 -0.9398)
			(end 0.508 0.9398)
			(stroke
				(width 0.1524)
				(type default)
			)
			(layer "B.SilkS")
		)
		(fp_rect
			(start 0.508 0.9398)
			(end -0.508 -0.9398)
			(stroke
				(width 0)
				(type default)
			)
			(fill no)
			(layer "B.CrtYd")
		)
		(fp_rect
			(start 0.508 0.9398)
			(end -0.508 -0.9398)
			(stroke
				(width 0)
				(type default)
			)
			(fill no)
			(layer "B.Fab")
		)
		(pad "1" smd custom
			(at 0 -0.4445 180)
			(size 0.1397 0.1397)
			(layers "B.Cu" "B.Mask" "B.Paste")
			(net "BMC_TO_EXP_RESET_OUT_R")
			(options
				(clearance outline)
				(anchor circle)
			)
			(primitives
				(gr_poly
					(pts
						(arc
							(start -0.1778 0.2794)
							(mid -0.249642 0.249642)
							(end -0.2794 0.1778)
						)
						(arc
							(start -0.2794 -0.1778)
							(mid -0.249642 -0.249642)
							(end -0.1778 -0.2794)
						)
						(arc
							(start 0.1778 -0.2794)
							(mid 0.249642 -0.249642)
							(end 0.2794 -0.1778)
						)
						(arc
							(start 0.2794 0.1778)
							(mid 0.249642 0.249642)
							(end 0.1778 0.2794)
						)
					)
					(width 0)
					(fill yes)
				)
			)
		)
		(pad "2" smd custom
			(at 0 0.4445 180)
			(size 0.1397 0.1397)
			(layers "B.Cu" "B.Mask" "B.Paste")
			(net "BMC_TO_EXP_RESET_OUT")
			(options
				(clearance outline)
				(anchor circle)
			)
			(primitives
				(gr_poly
					(pts
						(arc
							(start -0.1778 0.2794)
							(mid -0.249642 0.249642)
							(end -0.2794 0.1778)
						)
						(arc
							(start -0.2794 -0.1778)
							(mid -0.249642 -0.249642)
							(end -0.1778 -0.2794)
						)
						(arc
							(start 0.1778 -0.2794)
							(mid 0.249642 -0.249642)
							(end 0.2794 -0.1778)
						)
						(arc
							(start 0.2794 0.1778)
							(mid 0.249642 0.249642)
							(end 0.1778 0.2794)
						)
					)
					(width 0)
					(fill yes)
				)
			)
		)
	)
	(footprint ""
		(layer "B.Cu")
		(at 38.419278 -153.050748 -90)
		(property "Reference" "R321"
			(at 0 0 90)
			(layer "B.SilkS")
			(hide yes)
			(effects
				(font
					(size 1.27 1.27)
				)
				(justify mirror)
			)
		)
		(property "Value" "0R2J-2-GP"
			(at -0.064008 -3.993896 270)
			(unlocked yes)
			(layer "B.Fab")
			(hide yes)
			(effects
				(font
					(size 1.016 1.016)
					(thickness 0.1524)
				)
				(justify mirror)
			)
		)
		(property "Device Type" "R402H16"
			(at -0.064008 -5.517896 270)
			(unlocked yes)
			(layer "B.Fab")
			(hide yes)
			(effects
				(font
					(size 1.016 1.016)
					(thickness 0.1524)
				)
				(justify mirror)
			)
		)
		(duplicate_pad_numbers_are_jumpers no)
		(fp_line
			(start -0.508 -0.9398)
			(end 0.508 -0.9398)
			(stroke
				(width 0.1524)
				(type default)
			)
			(layer "B.SilkS")
		)
		(fp_line
			(start 0.508 -0.9398)
			(end 0.508 0.9398)
			(stroke
				(width 0.1524)
				(type default)
			)
			(layer "B.SilkS")
		)
		(fp_rect
			(start 0.508 0.9398)
			(end -0.508 -0.9398)
			(stroke
				(width 0)
				(type default)
			)
			(fill no)
			(layer "B.CrtYd")
		)
		(fp_rect
			(start 0.508 0.9398)
			(end -0.508 -0.9398)
			(stroke
				(width 0)
				(type default)
			)
			(fill no)
			(layer "B.Fab")
		)
		(pad "1" smd custom
			(at 0 -0.4445 90)
			(size 0.1397 0.1397)
			(layers "B.Cu" "B.Mask" "B.Paste")
			(net "SCC_B_HB_IN_R")
			(options
				(clearance outline)
				(anchor circle)
			)
			(primitives
				(gr_poly
					(pts
						(arc
							(start -0.1778 0.2794)
							(mid -0.249642 0.249642)
							(end -0.2794 0.1778)
						)
						(arc
							(start -0.2794 -0.1778)
							(mid -0.249642 -0.249642)
							(end -0.1778 -0.2794)
						)
						(arc
							(start 0.1778 -0.2794)
							(mid 0.249642 -0.249642)
							(end 0.2794 -0.1778)
						)
						(arc
							(start 0.2794 0.1778)
							(mid 0.249642 0.249642)
							(end 0.1778 0.2794)
						)
					)
					(width 0)
					(fill yes)
				)
			)
		)
		(pad "2" smd custom
			(at 0 0.4445 90)
			(size 0.1397 0.1397)
			(layers "B.Cu" "B.Mask" "B.Paste")
			(net "SCC_RMT_HEARTBEAT")
			(options
				(clearance outline)
				(anchor circle)
			)
			(primitives
				(gr_poly
					(pts
						(arc
							(start -0.1778 0.2794)
							(mid -0.249642 0.249642)
							(end -0.2794 0.1778)
						)
						(arc
							(start -0.2794 -0.1778)
							(mid -0.249642 -0.249642)
							(end -0.1778 -0.2794)
						)
						(arc
							(start 0.1778 -0.2794)
							(mid 0.249642 -0.249642)
							(end 0.2794 -0.1778)
						)
						(arc
							(start 0.2794 0.1778)
							(mid 0.249642 0.249642)
							(end 0.1778 0.2794)
						)
					)
					(width 0)
					(fill yes)
				)
			)
		)
	)
	(footprint ""
		(layer "B.Cu")
		(at 40.9956 -157.4546 -90)
		(property "Reference" "R326"
			(at 0 0 90)
			(layer "B.SilkS")
			(hide yes)
			(effects
				(font
					(size 1.27 1.27)
				)
				(justify mirror)
			)
		)
		(property "Value" "0R2J-2-GP"
			(at -0.064008 -3.993896 270)
			(unlocked yes)
			(layer "B.Fab")
			(hide yes)
			(effects
				(font
					(size 1.016 1.016)
					(thickness 0.1524)
				)
				(justify mirror)
			)
		)
		(property "Device Type" "R402H16"
			(at -0.064008 -5.517896 270)
			(unlocked yes)
			(layer "B.Fab")
			(hide yes)
			(effects
				(font
					(size 1.016 1.016)
					(thickness 0.1524)
				)
				(justify mirror)
			)
		)
		(duplicate_pad_numbers_are_jumpers no)
		(fp_line
			(start -0.508 -0.9398)
			(end 0.508 -0.9398)
			(stroke
				(width 0.1524)
				(type default)
			)
			(layer "B.SilkS")
		)
		(fp_line
			(start 0.508 -0.9398)
			(end 0.508 0.9398)
			(stroke
				(width 0.1524)
				(type default)
			)
			(layer "B.SilkS")
		)
		(fp_rect
			(start 0.508 0.9398)
			(end -0.508 -0.9398)
			(stroke
				(width 0)
				(type default)
			)
			(fill no)
			(layer "B.CrtYd")
		)
		(fp_rect
			(start 0.508 0.9398)
			(end -0.508 -0.9398)
			(stroke
				(width 0)
				(type default)
			)
			(fill no)
			(layer "B.Fab")
		)
		(pad "1" smd custom
			(at 0 -0.4445 90)
			(size 0.1397 0.1397)
			(layers "B.Cu" "B.Mask" "B.Paste")
			(net "BMC_LOC_HB")
			(options
				(clearance outline)
				(anchor circle)
			)
			(primitives
				(gr_poly
					(pts
						(arc
							(start -0.1778 0.2794)
							(mid -0.249642 0.249642)
							(end -0.2794 0.1778)
						)
						(arc
							(start -0.2794 -0.1778)
							(mid -0.249642 -0.249642)
							(end -0.1778 -0.2794)
						)
						(arc
							(start 0.1778 -0.2794)
							(mid 0.249642 -0.249642)
							(end 0.2794 -0.1778)
						)
						(arc
							(start 0.2794 0.1778)
							(mid 0.249642 0.249642)
							(end 0.1778 0.2794)
						)
					)
					(width 0)
					(fill yes)
				)
			)
		)
		(pad "2" smd custom
			(at 0 0.4445 90)
			(size 0.1397 0.1397)
			(layers "B.Cu" "B.Mask" "B.Paste")
			(net "BMC_LOC_HEARTBEAT")
			(options
				(clearance outline)
				(anchor circle)
			)
			(primitives
				(gr_poly
					(pts
						(arc
							(start -0.1778 0.2794)
							(mid -0.249642 0.249642)
							(end -0.2794 0.1778)
						)
						(arc
							(start -0.2794 -0.1778)
							(mid -0.249642 -0.249642)
							(end -0.1778 -0.2794)
						)
						(arc
							(start 0.1778 -0.2794)
							(mid 0.249642 -0.249642)
							(end 0.2794 -0.1778)
						)
						(arc
							(start 0.2794 0.1778)
							(mid 0.249642 0.249642)
							(end 0.1778 0.2794)
						)
					)
					(width 0)
					(fill yes)
				)
			)
		)
	)
	(footprint ""
		(layer "B.Cu")
		(at 56.716168 -144.018)
		(property "Reference" "TP79"
			(at 0 0 0)
			(layer "B.SilkS")
			(hide yes)
			(effects
				(font
					(size 1.27 1.27)
				)
				(justify mirror)
			)
		)
		(property "Value" "TPAD28-2-GP"
			(at 0.0127 -1.6637 0)
			(unlocked yes)
			(layer "B.Fab")
			(hide yes)
			(effects
				(font
					(size 1.016 1.016)
					(thickness 0.1524)
				)
				(justify mirror)
			)
		)
		(property "Device Type" "TPAD28"
			(at 0.0127 -3.1877 0)
			(unlocked yes)
			(layer "B.Fab")
			(hide yes)
			(effects
				(font
					(size 1.016 1.016)
					(thickness 0.1524)
				)
				(justify mirror)
			)
		)
		(duplicate_pad_numbers_are_jumpers no)
		(fp_poly
			(pts
				(arc
					(start 0.3556 0)
					(mid -0.3556 0)
					(end 0.3556 0)
				)
			)
			(stroke
				(width 0)
				(type default)
			)
			(fill no)
			(layer "B.CrtYd")
		)
		(fp_poly
			(pts
				(arc
					(start 0.6096 0)
					(mid -0.6096 0)
					(end 0.6096 0)
				)
			)
			(stroke
				(width 0)
				(type default)
			)
			(fill no)
			(layer "B.Fab")
		)
		(pad "1" smd circle
			(at 0 0 180)
			(size 0.7112 0.7112)
			(layers "B.Cu" "B.Mask" "B.Paste")
			(net "JTAG_BMC_TDI")
		)
	)
	(footprint ""
		(layer "B.Cu")
		(at 89.281 -148.79066)
		(property "Reference" "R96"
			(at 0 0 0)
			(layer "B.SilkS")
			(hide yes)
			(effects
				(font
					(size 1.27 1.27)
				)
				(justify mirror)
			)
		)
		(property "Value" "0R2J-2-GP"
			(at -0.064008 -3.993896 0)
			(unlocked yes)
			(layer "B.Fab")
			(hide yes)
			(effects
				(font
					(size 1.016 1.016)
					(thickness 0.1524)
				)
				(justify mirror)
			)
		)
		(property "Device Type" "R402H16"
			(at -0.064008 -5.517896 0)
			(unlocked yes)
			(layer "B.Fab")
			(hide yes)
			(effects
				(font
					(size 1.016 1.016)
					(thickness 0.1524)
				)
				(justify mirror)
			)
		)
		(duplicate_pad_numbers_are_jumpers no)
		(fp_line
			(start -0.508 -0.9398)
			(end 0.508 -0.9398)
			(stroke
				(width 0.1524)
				(type default)
			)
			(layer "B.SilkS")
		)
		(fp_line
			(start 0.508 -0.9398)
			(end 0.508 0.9398)
			(stroke
				(width 0.1524)
				(type default)
			)
			(layer "B.SilkS")
		)
		(fp_rect
			(start 0.508 0.9398)
			(end -0.508 -0.9398)
			(stroke
				(width 0)
				(type default)
			)
			(fill no)
			(layer "B.CrtYd")
		)
		(fp_rect
			(start 0.508 0.9398)
			(end -0.508 -0.9398)
			(stroke
				(width 0)
				(type default)
			)
			(fill no)
			(layer "B.Fab")
		)
		(pad "1" smd custom
			(at 0 -0.4445 180)
			(size 0.1397 0.1397)
			(layers "B.Cu" "B.Mask" "B.Paste")
			(net "I2C_BMC_COMP_SDA_R")
			(options
				(clearance outline)
				(anchor circle)
			)
			(primitives
				(gr_poly
					(pts
						(arc
							(start -0.1778 0.2794)
							(mid -0.249642 0.249642)
							(end -0.2794 0.1778)
						)
						(arc
							(start -0.2794 -0.1778)
							(mid -0.249642 -0.249642)
							(end -0.1778 -0.2794)
						)
						(arc
							(start 0.1778 -0.2794)
							(mid 0.249642 -0.249642)
							(end 0.2794 -0.1778)
						)
						(arc
							(start 0.2794 0.1778)
							(mid 0.249642 0.249642)
							(end 0.1778 0.2794)
						)
					)
					(width 0)
					(fill yes)
				)
			)
		)
		(pad "2" smd custom
			(at 0 0.4445 180)
			(size 0.1397 0.1397)
			(layers "B.Cu" "B.Mask" "B.Paste")
			(net "I2C_BMC_COMP_SDA")
			(options
				(clearance outline)
				(anchor circle)
			)
			(primitives
				(gr_poly
					(pts
						(arc
							(start -0.1778 0.2794)
							(mid -0.249642 0.249642)
							(end -0.2794 0.1778)
						)
						(arc
							(start -0.2794 -0.1778)
							(mid -0.249642 -0.249642)
							(end -0.1778 -0.2794)
						)
						(arc
							(start 0.1778 -0.2794)
							(mid 0.249642 -0.249642)
							(end 0.2794 -0.1778)
						)
						(arc
							(start 0.2794 0.1778)
							(mid 0.249642 0.249642)
							(end 0.1778 0.2794)
						)
					)
					(width 0)
					(fill yes)
				)
			)
		)
	)
	(footprint ""
		(layer "B.Cu")
		(at 56.896 -157.734 180)
		(property "Reference" "R399"
			(at 0 0 0)
			(layer "B.SilkS")
			(hide yes)
			(effects
				(font
					(size 1.27 1.27)
				)
				(justify mirror)
			)
		)
		(property "Value" "4K7R2F-GP"
			(at -0.064008 -3.993896 180)
			(unlocked yes)
			(layer "B.Fab")
			(hide yes)
			(effects
				(font
					(size 1.016 1.016)
					(thickness 0.1524)
				)
				(justify mirror)
			)
		)
		(property "Device Type" "R402H16"
			(at -0.064008 -5.517896 180)
			(unlocked yes)
			(layer "B.Fab")
			(hide yes)
			(effects
				(font
					(size 1.016 1.016)
					(thickness 0.1524)
				)
				(justify mirror)
			)
		)
		(duplicate_pad_numbers_are_jumpers no)
		(fp_line
			(start 0.508 -0.9398)
			(end 0.508 0.9398)
			(stroke
				(width 0.1524)
				(type default)
			)
			(layer "B.SilkS")
		)
		(fp_line
			(start -0.508 -0.9398)
			(end 0.508 -0.9398)
			(stroke
				(width 0.1524)
				(type default)
			)
			(layer "B.SilkS")
		)
		(fp_rect
			(start 0.508 0.9398)
			(end -0.508 -0.9398)
			(stroke
				(width 0)
				(type default)
			)
			(fill no)
			(layer "B.CrtYd")
		)
		(fp_rect
			(start 0.508 0.9398)
			(end -0.508 -0.9398)
			(stroke
				(width 0)
				(type default)
			)
			(fill no)
			(layer "B.Fab")
		)
		(pad "1" smd custom
			(at 0 -0.4445)
			(size 0.1397 0.1397)
			(layers "B.Cu" "B.Mask" "B.Paste")
			(net "GND")
			(options
				(clearance outline)
				(anchor circle)
			)
			(primitives
				(gr_poly
					(pts
						(arc
							(start -0.1778 0.2794)
							(mid -0.249642 0.249642)
							(end -0.2794 0.1778)
						)
						(arc
							(start -0.2794 -0.1778)
							(mid -0.249642 -0.249642)
							(end -0.1778 -0.2794)
						)
						(arc
							(start 0.1778 -0.2794)
							(mid 0.249642 -0.249642)
							(end 0.2794 -0.1778)
						)
						(arc
							(start 0.2794 0.1778)
							(mid 0.249642 0.249642)
							(end 0.1778 0.2794)
						)
					)
					(width 0)
					(fill yes)
				)
			)
		)
		(pad "2" smd custom
			(at 0 0.4445)
			(size 0.1397 0.1397)
			(layers "B.Cu" "B.Mask" "B.Paste")
			(net "MAC2_TXD3")
			(options
				(clearance outline)
				(anchor circle)
			)
			(primitives
				(gr_poly
					(pts
						(arc
							(start -0.1778 0.2794)
							(mid -0.249642 0.249642)
							(end -0.2794 0.1778)
						)
						(arc
							(start -0.2794 -0.1778)
							(mid -0.249642 -0.249642)
							(end -0.1778 -0.2794)
						)
						(arc
							(start 0.1778 -0.2794)
							(mid 0.249642 -0.249642)
							(end 0.2794 -0.1778)
						)
						(arc
							(start 0.2794 0.1778)
							(mid 0.249642 0.249642)
							(end 0.1778 0.2794)
						)
					)
					(width 0)
					(fill yes)
				)
			)
		)
	)
	(footprint ""
		(layer "B.Cu")
		(at 83.800442 -147.307046 90)
		(property "Reference" "C485"
			(at 0 0 90)
			(layer "B.SilkS")
			(hide yes)
			(effects
				(font
					(size 1.27 1.27)
				)
				(justify mirror)
			)
		)
		(property "Value" "SCD1U16V2KX-3GP"
			(at -1.1811 -2.7051 90)
			(unlocked yes)
			(layer "B.Fab")
			(hide yes)
			(effects
				(font
					(size 1.016 1.016)
					(thickness 0.1524)
				)
				(justify mirror)
			)
		)
		(property "Device Type" "C402H22"
			(at -1.1811 -4.2291 90)
			(unlocked yes)
			(layer "B.Fab")
			(hide yes)
			(effects
				(font
					(size 1.016 1.016)
					(thickness 0.1524)
				)
				(justify mirror)
			)
		)
		(duplicate_pad_numbers_are_jumpers no)
		(fp_rect
			(start 0.4318 0.9525)
			(end -0.4318 -0.9525)
			(stroke
				(width 0)
				(type default)
			)
			(fill no)
			(layer "B.CrtYd")
		)
		(fp_rect
			(start 0.4318 0.9525)
			(end -0.4318 -0.9525)
			(stroke
				(width 0)
				(type default)
			)
			(fill no)
			(layer "B.Fab")
		)
		(pad "1" smd custom
			(at 0 -0.4445 270)
			(size 0.1524 0.1524)
			(layers "B.Cu" "B.Mask" "B.Paste")
			(net "P3V3_STBY")
			(options
				(clearance outline)
				(anchor circle)
			)
			(primitives
				(gr_poly
					(pts
						(arc
							(start 0.3048 0.2032)
							(mid 0.275042 0.275042)
							(end 0.2032 0.3048)
						)
						(arc
							(start -0.2032 0.3048)
							(mid -0.275042 0.275042)
							(end -0.3048 0.2032)
						)
						(arc
							(start -0.3048 -0.2032)
							(mid -0.275042 -0.275042)
							(end -0.2032 -0.3048)
						)
						(arc
							(start 0.2032 -0.3048)
							(mid 0.275042 -0.275042)
							(end 0.3048 -0.2032)
						)
					)
					(width 0)
					(fill yes)
				)
			)
		)
		(pad "2" smd custom
			(at 0 0.4445 270)
			(size 0.1524 0.1524)
			(layers "B.Cu" "B.Mask" "B.Paste")
			(net "GND")
			(options
				(clearance outline)
				(anchor circle)
			)
			(primitives
				(gr_poly
					(pts
						(arc
							(start 0.3048 0.2032)
							(mid 0.275042 0.275042)
							(end 0.2032 0.3048)
						)
						(arc
							(start -0.2032 0.3048)
							(mid -0.275042 0.275042)
							(end -0.3048 0.2032)
						)
						(arc
							(start -0.3048 -0.2032)
							(mid -0.275042 -0.275042)
							(end -0.2032 -0.3048)
						)
						(arc
							(start 0.2032 -0.3048)
							(mid 0.275042 -0.275042)
							(end 0.3048 -0.2032)
						)
					)
					(width 0)
					(fill yes)
				)
			)
		)
	)
	(footprint ""
		(layer "B.Cu")
		(at 56.850026 -161.083752 90)
		(property "Reference" "C123"
			(at 0 0 90)
			(layer "B.SilkS")
			(hide yes)
			(effects
				(font
					(size 1.27 1.27)
				)
				(justify mirror)
			)
		)
		(property "Value" "SCD1U25V2KX-2-GP"
			(at -1.1811 -2.7051 90)
			(unlocked yes)
			(layer "B.Fab")
			(hide yes)
			(effects
				(font
					(size 1.016 1.016)
					(thickness 0.1524)
				)
				(justify mirror)
			)
		)
		(property "Device Type" "C402H22"
			(at -1.1811 -4.2291 90)
			(unlocked yes)
			(layer "B.Fab")
			(hide yes)
			(effects
				(font
					(size 1.016 1.016)
					(thickness 0.1524)
				)
				(justify mirror)
			)
		)
		(duplicate_pad_numbers_are_jumpers no)
		(fp_rect
			(start 0.4318 0.9525)
			(end -0.4318 -0.9525)
			(stroke
				(width 0)
				(type default)
			)
			(fill no)
			(layer "B.CrtYd")
		)
		(fp_rect
			(start 0.4318 0.9525)
			(end -0.4318 -0.9525)
			(stroke
				(width 0)
				(type default)
			)
			(fill no)
			(layer "B.Fab")
		)
		(pad "1" smd custom
			(at 0 -0.4445 270)
			(size 0.1524 0.1524)
			(layers "B.Cu" "B.Mask" "B.Paste")
			(net "ADC_P5V_STBY")
			(options
				(clearance outline)
				(anchor circle)
			)
			(primitives
				(gr_poly
					(pts
						(arc
							(start 0.3048 0.2032)
							(mid 0.275042 0.275042)
							(end 0.2032 0.3048)
						)
						(arc
							(start -0.2032 0.3048)
							(mid -0.275042 0.275042)
							(end -0.3048 0.2032)
						)
						(arc
							(start -0.3048 -0.2032)
							(mid -0.275042 -0.275042)
							(end -0.2032 -0.3048)
						)
						(arc
							(start 0.2032 -0.3048)
							(mid 0.275042 -0.275042)
							(end 0.3048 -0.2032)
						)
					)
					(width 0)
					(fill yes)
				)
			)
		)
		(pad "2" smd custom
			(at 0 0.4445 270)
			(size 0.1524 0.1524)
			(layers "B.Cu" "B.Mask" "B.Paste")
			(net "GND")
			(options
				(clearance outline)
				(anchor circle)
			)
			(primitives
				(gr_poly
					(pts
						(arc
							(start 0.3048 0.2032)
							(mid 0.275042 0.275042)
							(end 0.2032 0.3048)
						)
						(arc
							(start -0.2032 0.3048)
							(mid -0.275042 0.275042)
							(end -0.3048 0.2032)
						)
						(arc
							(start -0.3048 -0.2032)
							(mid -0.275042 -0.275042)
							(end -0.2032 -0.3048)
						)
						(arc
							(start 0.2032 -0.3048)
							(mid 0.275042 -0.275042)
							(end 0.3048 -0.2032)
						)
					)
					(width 0)
					(fill yes)
				)
			)
		)
	)
	(footprint ""
		(layer "B.Cu")
		(at 37.2618 -134.2136 180)
		(property "Reference" "R277"
			(at 0 0 0)
			(layer "B.SilkS")
			(hide yes)
			(effects
				(font
					(size 1.27 1.27)
				)
				(justify mirror)
			)
		)
		(property "Value" "33R2F-3-GP"
			(at -0.064008 -3.993896 180)
			(unlocked yes)
			(layer "B.Fab")
			(hide yes)
			(effects
				(font
					(size 1.016 1.016)
					(thickness 0.1524)
				)
				(justify mirror)
			)
		)
		(property "Device Type" "R402H16"
			(at -0.064008 -5.517896 180)
			(unlocked yes)
			(layer "B.Fab")
			(hide yes)
			(effects
				(font
					(size 1.016 1.016)
					(thickness 0.1524)
				)
				(justify mirror)
			)
		)
		(duplicate_pad_numbers_are_jumpers no)
		(fp_line
			(start 0.508 -0.9398)
			(end 0.508 0.9398)
			(stroke
				(width 0.1524)
				(type default)
			)
			(layer "B.SilkS")
		)
		(fp_line
			(start -0.508 -0.9398)
			(end 0.508 -0.9398)
			(stroke
				(width 0.1524)
				(type default)
			)
			(layer "B.SilkS")
		)
		(fp_rect
			(start 0.508 0.9398)
			(end -0.508 -0.9398)
			(stroke
				(width 0)
				(type default)
			)
			(fill no)
			(layer "B.CrtYd")
		)
		(fp_rect
			(start 0.508 0.9398)
			(end -0.508 -0.9398)
			(stroke
				(width 0)
				(type default)
			)
			(fill no)
			(layer "B.Fab")
		)
		(pad "1" smd custom
			(at 0 -0.4445)
			(size 0.1397 0.1397)
			(layers "B.Cu" "B.Mask" "B.Paste")
			(net "FLA_CS_1_R")
			(options
				(clearance outline)
				(anchor circle)
			)
			(primitives
				(gr_poly
					(pts
						(arc
							(start -0.1778 0.2794)
							(mid -0.249642 0.249642)
							(end -0.2794 0.1778)
						)
						(arc
							(start -0.2794 -0.1778)
							(mid -0.249642 -0.249642)
							(end -0.1778 -0.2794)
						)
						(arc
							(start 0.1778 -0.2794)
							(mid 0.249642 -0.249642)
							(end 0.2794 -0.1778)
						)
						(arc
							(start 0.2794 0.1778)
							(mid 0.249642 0.249642)
							(end 0.1778 0.2794)
						)
					)
					(width 0)
					(fill yes)
				)
			)
		)
		(pad "2" smd custom
			(at 0 0.4445)
			(size 0.1397 0.1397)
			(layers "B.Cu" "B.Mask" "B.Paste")
			(net "FLA_CS_1")
			(options
				(clearance outline)
				(anchor circle)
			)
			(primitives
				(gr_poly
					(pts
						(arc
							(start -0.1778 0.2794)
							(mid -0.249642 0.249642)
							(end -0.2794 0.1778)
						)
						(arc
							(start -0.2794 -0.1778)
							(mid -0.249642 -0.249642)
							(end -0.1778 -0.2794)
						)
						(arc
							(start 0.1778 -0.2794)
							(mid 0.249642 -0.249642)
							(end 0.2794 -0.1778)
						)
						(arc
							(start 0.2794 0.1778)
							(mid 0.249642 0.249642)
							(end 0.1778 0.2794)
						)
					)
					(width 0)
					(fill yes)
				)
			)
		)
	)
	(footprint ""
		(layer "B.Cu")
		(at 46.9138 -149.6822 180)
		(property "Reference" "R707"
			(at 0 0 0)
			(layer "B.SilkS")
			(hide yes)
			(effects
				(font
					(size 1.27 1.27)
				)
				(justify mirror)
			)
		)
		(property "Value" "4K7R2F-GP"
			(at -0.064008 -3.993896 180)
			(unlocked yes)
			(layer "B.Fab")
			(hide yes)
			(effects
				(font
					(size 1.016 1.016)
					(thickness 0.1524)
				)
				(justify mirror)
			)
		)
		(property "Device Type" "R402H16"
			(at -0.064008 -5.517896 180)
			(unlocked yes)
			(layer "B.Fab")
			(hide yes)
			(effects
				(font
					(size 1.016 1.016)
					(thickness 0.1524)
				)
				(justify mirror)
			)
		)
		(duplicate_pad_numbers_are_jumpers no)
		(fp_line
			(start 0.508 -0.9398)
			(end 0.508 0.9398)
			(stroke
				(width 0.1524)
				(type default)
			)
			(layer "B.SilkS")
		)
		(fp_line
			(start -0.508 -0.9398)
			(end 0.508 -0.9398)
			(stroke
				(width 0.1524)
				(type default)
			)
			(layer "B.SilkS")
		)
		(fp_rect
			(start 0.508 0.9398)
			(end -0.508 -0.9398)
			(stroke
				(width 0)
				(type default)
			)
			(fill no)
			(layer "B.CrtYd")
		)
		(fp_rect
			(start 0.508 0.9398)
			(end -0.508 -0.9398)
			(stroke
				(width 0)
				(type default)
			)
			(fill no)
			(layer "B.Fab")
		)
		(pad "1" smd custom
			(at 0 -0.4445)
			(size 0.1397 0.1397)
			(layers "B.Cu" "B.Mask" "B.Paste")
			(net "P3V3_STBY")
			(options
				(clearance outline)
				(anchor circle)
			)
			(primitives
				(gr_poly
					(pts
						(arc
							(start -0.1778 0.2794)
							(mid -0.249642 0.249642)
							(end -0.2794 0.1778)
						)
						(arc
							(start -0.2794 -0.1778)
							(mid -0.249642 -0.249642)
							(end -0.1778 -0.2794)
						)
						(arc
							(start 0.1778 -0.2794)
							(mid 0.249642 -0.249642)
							(end 0.2794 -0.1778)
						)
						(arc
							(start 0.2794 0.1778)
							(mid 0.249642 0.249642)
							(end 0.1778 0.2794)
						)
					)
					(width 0)
					(fill yes)
				)
			)
		)
		(pad "2" smd custom
			(at 0 0.4445)
			(size 0.1397 0.1397)
			(layers "B.Cu" "B.Mask" "B.Paste")
			(net "IOM_TYPE0")
			(options
				(clearance outline)
				(anchor circle)
			)
			(primitives
				(gr_poly
					(pts
						(arc
							(start -0.1778 0.2794)
							(mid -0.249642 0.249642)
							(end -0.2794 0.1778)
						)
						(arc
							(start -0.2794 -0.1778)
							(mid -0.249642 -0.249642)
							(end -0.1778 -0.2794)
						)
						(arc
							(start 0.1778 -0.2794)
							(mid 0.249642 -0.249642)
							(end 0.2794 -0.1778)
						)
						(arc
							(start 0.2794 0.1778)
							(mid 0.249642 0.249642)
							(end 0.1778 0.2794)
						)
					)
					(width 0)
					(fill yes)
				)
			)
		)
	)
	(footprint ""
		(layer "B.Cu")
		(at 57.963054 -130.700272)
		(property "Reference" "C116"
			(at 0 0 0)
			(layer "B.SilkS")
			(hide yes)
			(effects
				(font
					(size 1.27 1.27)
				)
				(justify mirror)
			)
		)
		(property "Value" "SC4D7U25V5KX-1-GP"
			(at 0.0762 -6.1214 0)
			(unlocked yes)
			(layer "B.Fab")
			(hide yes)
			(effects
				(font
					(size 1.016 1.016)
					(thickness 0.1524)
				)
				(justify mirror)
			)
		)
		(property "Device Type" "C805H58"
			(at 0.0762 -8.1534 0)
			(unlocked yes)
			(layer "B.Fab")
			(hide yes)
			(effects
				(font
					(size 1.016 1.016)
					(thickness 0.1524)
				)
				(justify mirror)
			)
		)
		(duplicate_pad_numbers_are_jumpers no)
		(fp_line
			(start -0.635 0)
			(end 0.635 0)
			(stroke
				(width 0.508)
				(type default)
			)
			(layer "B.SilkS")
		)
		(fp_rect
			(start 0.9652 1.778)
			(end -0.9652 -1.778)
			(stroke
				(width 0)
				(type default)
			)
			(fill no)
			(layer "B.CrtYd")
		)
		(fp_poly
			(pts
				(xy 0.9652 -1.778) (xy -0.9652 -1.778) (xy -0.9652 1.778) (xy 0.9652 1.778)
			)
			(stroke
				(width 0)
				(type default)
			)
			(fill no)
			(layer "B.Fab")
		)
		(pad "1" smd rect
			(at 0 -0.9652 180)
			(size 1.397 1.143)
			(layers "B.Cu" "B.Mask" "B.Paste")
			(net "P1V15_STBY")
		)
		(pad "2" smd rect
			(at 0 0.9652 180)
			(size 1.397 1.143)
			(layers "B.Cu" "B.Mask" "B.Paste")
			(net "GND")
		)
	)
	(footprint ""
		(layer "B.Cu")
		(at 45.3644 -122.8852)
		(property "Reference" "TP19"
			(at 0 0 0)
			(layer "B.SilkS")
			(hide yes)
			(effects
				(font
					(size 1.27 1.27)
				)
				(justify mirror)
			)
		)
		(property "Value" "TPAD32-GP"
			(at 0.0508 -1.6764 0)
			(unlocked yes)
			(layer "B.Fab")
			(hide yes)
			(effects
				(font
					(size 1.016 1.016)
					(thickness 0.1524)
				)
				(justify mirror)
			)
		)
		(property "Device Type" "TPAD32"
			(at 0.0508 -3.2004 0)
			(unlocked yes)
			(layer "B.Fab")
			(hide yes)
			(effects
				(font
					(size 1.016 1.016)
					(thickness 0.1524)
				)
				(justify mirror)
			)
		)
		(duplicate_pad_numbers_are_jumpers no)
		(fp_poly
			(pts
				(arc
					(start 0.4064 0)
					(mid -0.4064 0)
					(end 0.4064 0)
				)
			)
			(stroke
				(width 0)
				(type default)
			)
			(fill no)
			(layer "B.CrtYd")
		)
		(fp_poly
			(pts
				(arc
					(start 0.7112 0)
					(mid -0.7112 0)
					(end 0.7112 0)
				)
			)
			(stroke
				(width 0)
				(type default)
			)
			(fill no)
			(layer "B.Fab")
		)
		(pad "1" smd circle
			(at 0 0 180)
			(size 0.8128 0.8128)
			(layers "B.Cu" "B.Mask" "B.Paste")
			(net "TEMP_3_ALERT")
		)
	)
	(footprint ""
		(layer "B.Cu")
		(at 50.09642 -145.96618)
		(property "Reference" "C98"
			(at 0 0 0)
			(layer "B.SilkS")
			(hide yes)
			(effects
				(font
					(size 1.27 1.27)
				)
				(justify mirror)
			)
		)
		(property "Value" "SC1U16V3KX-5GP"
			(at 0 -2.8194 0)
			(unlocked yes)
			(layer "B.Fab")
			(hide yes)
			(effects
				(font
					(size 1.016 1.016)
					(thickness 0.1524)
				)
				(justify mirror)
			)
		)
		(property "Device Type" "C603H36"
			(at 0 -4.3434 0)
			(unlocked yes)
			(layer "B.Fab")
			(hide yes)
			(effects
				(font
					(size 1.016 1.016)
					(thickness 0.1524)
				)
				(justify mirror)
			)
		)
		(duplicate_pad_numbers_are_jumpers no)
		(fp_line
			(start -0.508 0)
			(end 0.508 0)
			(stroke
				(width 0.2032)
				(type default)
			)
			(layer "B.SilkS")
		)
		(fp_rect
			(start 0.5842 1.3335)
			(end -0.5842 -1.3335)
			(stroke
				(width 0)
				(type default)
			)
			(fill no)
			(layer "B.CrtYd")
		)
		(fp_rect
			(start 0.5842 1.3335)
			(end -0.5842 -1.3335)
			(stroke
				(width 0)
				(type default)
			)
			(fill no)
			(layer "B.Fab")
		)
		(pad "1" smd custom
			(at 0 -0.762 180)
			(size 0.2159 0.2159)
			(layers "B.Cu" "B.Mask" "B.Paste")
			(net "P3V3_STBY")
			(options
				(clearance outline)
				(anchor circle)
			)
			(primitives
				(gr_poly
					(pts
						(arc
							(start -0.3302 0.4318)
							(mid -0.402042 0.402042)
							(end -0.4318 0.3302)
						)
						(arc
							(start -0.4318 -0.3302)
							(mid -0.402042 -0.402042)
							(end -0.3302 -0.4318)
						)
						(arc
							(start 0.3302 -0.4318)
							(mid 0.402042 -0.402042)
							(end 0.4318 -0.3302)
						)
						(arc
							(start 0.4318 0.3302)
							(mid 0.402042 0.402042)
							(end 0.3302 0.4318)
						)
					)
					(width 0)
					(fill yes)
				)
			)
		)
		(pad "2" smd custom
			(at 0 0.762 180)
			(size 0.2159 0.2159)
			(layers "B.Cu" "B.Mask" "B.Paste")
			(net "GND")
			(options
				(clearance outline)
				(anchor circle)
			)
			(primitives
				(gr_poly
					(pts
						(arc
							(start -0.3302 0.4318)
							(mid -0.402042 0.402042)
							(end -0.4318 0.3302)
						)
						(arc
							(start -0.4318 -0.3302)
							(mid -0.402042 -0.402042)
							(end -0.3302 -0.4318)
						)
						(arc
							(start 0.3302 -0.4318)
							(mid 0.402042 -0.402042)
							(end 0.4318 -0.3302)
						)
						(arc
							(start 0.4318 0.3302)
							(mid 0.402042 0.402042)
							(end 0.3302 0.4318)
						)
					)
					(width 0)
					(fill yes)
				)
			)
		)
	)
	(footprint ""
		(layer "B.Cu")
		(at 55.372 -118.6942 90)
		(property "Reference" "C506"
			(at 0 0 90)
			(layer "B.SilkS")
			(hide yes)
			(effects
				(font
					(size 1.27 1.27)
				)
				(justify mirror)
			)
		)
		(property "Value" "SCD1U16V2KX-3GP"
			(at -1.1811 -2.7051 90)
			(unlocked yes)
			(layer "B.Fab")
			(hide yes)
			(effects
				(font
					(size 1.016 1.016)
					(thickness 0.1524)
				)
				(justify mirror)
			)
		)
		(property "Device Type" "C402H22"
			(at -1.1811 -4.2291 90)
			(unlocked yes)
			(layer "B.Fab")
			(hide yes)
			(effects
				(font
					(size 1.016 1.016)
					(thickness 0.1524)
				)
				(justify mirror)
			)
		)
		(duplicate_pad_numbers_are_jumpers no)
		(fp_rect
			(start 0.4318 0.9525)
			(end -0.4318 -0.9525)
			(stroke
				(width 0)
				(type default)
			)
			(fill no)
			(layer "B.CrtYd")
		)
		(fp_rect
			(start 0.4318 0.9525)
			(end -0.4318 -0.9525)
			(stroke
				(width 0)
				(type default)
			)
			(fill no)
			(layer "B.Fab")
		)
		(pad "1" smd custom
			(at 0 -0.4445 270)
			(size 0.1524 0.1524)
			(layers "B.Cu" "B.Mask" "B.Paste")
			(net "P3V3_STBY")
			(options
				(clearance outline)
				(anchor circle)
			)
			(primitives
				(gr_poly
					(pts
						(arc
							(start 0.3048 0.2032)
							(mid 0.275042 0.275042)
							(end 0.2032 0.3048)
						)
						(arc
							(start -0.2032 0.3048)
							(mid -0.275042 0.275042)
							(end -0.3048 0.2032)
						)
						(arc
							(start -0.3048 -0.2032)
							(mid -0.275042 -0.275042)
							(end -0.2032 -0.3048)
						)
						(arc
							(start 0.2032 -0.3048)
							(mid 0.275042 -0.275042)
							(end 0.3048 -0.2032)
						)
					)
					(width 0)
					(fill yes)
				)
			)
		)
		(pad "2" smd custom
			(at 0 0.4445 270)
			(size 0.1524 0.1524)
			(layers "B.Cu" "B.Mask" "B.Paste")
			(net "GND")
			(options
				(clearance outline)
				(anchor circle)
			)
			(primitives
				(gr_poly
					(pts
						(arc
							(start 0.3048 0.2032)
							(mid 0.275042 0.275042)
							(end 0.2032 0.3048)
						)
						(arc
							(start -0.2032 0.3048)
							(mid -0.275042 0.275042)
							(end -0.3048 0.2032)
						)
						(arc
							(start -0.3048 -0.2032)
							(mid -0.275042 -0.275042)
							(end -0.2032 -0.3048)
						)
						(arc
							(start 0.2032 -0.3048)
							(mid 0.275042 -0.275042)
							(end 0.3048 -0.2032)
						)
					)
					(width 0)
					(fill yes)
				)
			)
		)
	)
	(footprint ""
		(layer "B.Cu")
		(at 46.8376 -154.8384 180)
		(property "Reference" "R311"
			(at 0 0 0)
			(layer "B.SilkS")
			(hide yes)
			(effects
				(font
					(size 1.27 1.27)
				)
				(justify mirror)
			)
		)
		(property "Value" "4K7R2F-GP"
			(at -0.064008 -3.993896 180)
			(unlocked yes)
			(layer "B.Fab")
			(hide yes)
			(effects
				(font
					(size 1.016 1.016)
					(thickness 0.1524)
				)
				(justify mirror)
			)
		)
		(property "Device Type" "R402H16"
			(at -0.064008 -5.517896 180)
			(unlocked yes)
			(layer "B.Fab")
			(hide yes)
			(effects
				(font
					(size 1.016 1.016)
					(thickness 0.1524)
				)
				(justify mirror)
			)
		)
		(duplicate_pad_numbers_are_jumpers no)
		(fp_line
			(start 0.508 -0.9398)
			(end 0.508 0.9398)
			(stroke
				(width 0.1524)
				(type default)
			)
			(layer "B.SilkS")
		)
		(fp_line
			(start -0.508 -0.9398)
			(end 0.508 -0.9398)
			(stroke
				(width 0.1524)
				(type default)
			)
			(layer "B.SilkS")
		)
		(fp_rect
			(start 0.508 0.9398)
			(end -0.508 -0.9398)
			(stroke
				(width 0)
				(type default)
			)
			(fill no)
			(layer "B.CrtYd")
		)
		(fp_rect
			(start 0.508 0.9398)
			(end -0.508 -0.9398)
			(stroke
				(width 0)
				(type default)
			)
			(fill no)
			(layer "B.Fab")
		)
		(pad "1" smd custom
			(at 0 -0.4445)
			(size 0.1397 0.1397)
			(layers "B.Cu" "B.Mask" "B.Paste")
			(net "BOARD_REV_2")
			(options
				(clearance outline)
				(anchor circle)
			)
			(primitives
				(gr_poly
					(pts
						(arc
							(start -0.1778 0.2794)
							(mid -0.249642 0.249642)
							(end -0.2794 0.1778)
						)
						(arc
							(start -0.2794 -0.1778)
							(mid -0.249642 -0.249642)
							(end -0.1778 -0.2794)
						)
						(arc
							(start 0.1778 -0.2794)
							(mid 0.249642 -0.249642)
							(end 0.2794 -0.1778)
						)
						(arc
							(start 0.2794 0.1778)
							(mid 0.249642 0.249642)
							(end 0.1778 0.2794)
						)
					)
					(width 0)
					(fill yes)
				)
			)
		)
		(pad "2" smd custom
			(at 0 0.4445)
			(size 0.1397 0.1397)
			(layers "B.Cu" "B.Mask" "B.Paste")
			(net "P3V3_STBY")
			(options
				(clearance outline)
				(anchor circle)
			)
			(primitives
				(gr_poly
					(pts
						(arc
							(start -0.1778 0.2794)
							(mid -0.249642 0.249642)
							(end -0.2794 0.1778)
						)
						(arc
							(start -0.2794 -0.1778)
							(mid -0.249642 -0.249642)
							(end -0.1778 -0.2794)
						)
						(arc
							(start 0.1778 -0.2794)
							(mid 0.249642 -0.249642)
							(end 0.2794 -0.1778)
						)
						(arc
							(start 0.2794 0.1778)
							(mid 0.249642 0.249642)
							(end 0.1778 0.2794)
						)
					)
					(width 0)
					(fill yes)
				)
			)
		)
	)
	(footprint ""
		(layer "B.Cu")
		(at 63.8048 -144.0434 90)
		(property "Reference" "R196"
			(at 0 0 90)
			(layer "B.SilkS")
			(hide yes)
			(effects
				(font
					(size 1.27 1.27)
				)
				(justify mirror)
			)
		)
		(property "Value" "2K2R2F-GP"
			(at -0.064008 -3.993896 90)
			(unlocked yes)
			(layer "B.Fab")
			(hide yes)
			(effects
				(font
					(size 1.016 1.016)
					(thickness 0.1524)
				)
				(justify mirror)
			)
		)
		(property "Device Type" "R402H16"
			(at -0.064008 -5.517896 90)
			(unlocked yes)
			(layer "B.Fab")
			(hide yes)
			(effects
				(font
					(size 1.016 1.016)
					(thickness 0.1524)
				)
				(justify mirror)
			)
		)
		(duplicate_pad_numbers_are_jumpers no)
		(fp_line
			(start 0.508 -0.9398)
			(end 0.508 0.9398)
			(stroke
				(width 0.1524)
				(type default)
			)
			(layer "B.SilkS")
		)
		(fp_line
			(start -0.508 -0.9398)
			(end 0.508 -0.9398)
			(stroke
				(width 0.1524)
				(type default)
			)
			(layer "B.SilkS")
		)
		(fp_rect
			(start 0.508 0.9398)
			(end -0.508 -0.9398)
			(stroke
				(width 0)
				(type default)
			)
			(fill no)
			(layer "B.CrtYd")
		)
		(fp_rect
			(start 0.508 0.9398)
			(end -0.508 -0.9398)
			(stroke
				(width 0)
				(type default)
			)
			(fill no)
			(layer "B.Fab")
		)
		(pad "1" smd custom
			(at 0 -0.4445 270)
			(size 0.1397 0.1397)
			(layers "B.Cu" "B.Mask" "B.Paste")
			(net "I2C_EXP_LOC_SDA_OUT")
			(options
				(clearance outline)
				(anchor circle)
			)
			(primitives
				(gr_poly
					(pts
						(arc
							(start -0.1778 0.2794)
							(mid -0.249642 0.249642)
							(end -0.2794 0.1778)
						)
						(arc
							(start -0.2794 -0.1778)
							(mid -0.249642 -0.249642)
							(end -0.1778 -0.2794)
						)
						(arc
							(start 0.1778 -0.2794)
							(mid 0.249642 -0.249642)
							(end 0.2794 -0.1778)
						)
						(arc
							(start 0.2794 0.1778)
							(mid 0.249642 0.249642)
							(end 0.1778 0.2794)
						)
					)
					(width 0)
					(fill yes)
				)
			)
		)
		(pad "2" smd custom
			(at 0 0.4445 270)
			(size 0.1397 0.1397)
			(layers "B.Cu" "B.Mask" "B.Paste")
			(net "P3V3_STBY")
			(options
				(clearance outline)
				(anchor circle)
			)
			(primitives
				(gr_poly
					(pts
						(arc
							(start -0.1778 0.2794)
							(mid -0.249642 0.249642)
							(end -0.2794 0.1778)
						)
						(arc
							(start -0.2794 -0.1778)
							(mid -0.249642 -0.249642)
							(end -0.1778 -0.2794)
						)
						(arc
							(start 0.1778 -0.2794)
							(mid 0.249642 -0.249642)
							(end 0.2794 -0.1778)
						)
						(arc
							(start 0.2794 0.1778)
							(mid 0.249642 0.249642)
							(end 0.1778 0.2794)
						)
					)
					(width 0)
					(fill yes)
				)
			)
		)
	)
	(footprint ""
		(layer "B.Cu")
		(at 46.9138 -140.208)
		(property "Reference" "TP27"
			(at 0 0 0)
			(layer "B.SilkS")
			(hide yes)
			(effects
				(font
					(size 1.27 1.27)
				)
				(justify mirror)
			)
		)
		(property "Value" "TPAD28-2-GP"
			(at 0.0127 -1.6637 0)
			(unlocked yes)
			(layer "B.Fab")
			(hide yes)
			(effects
				(font
					(size 1.016 1.016)
					(thickness 0.1524)
				)
				(justify mirror)
			)
		)
		(property "Device Type" "TPAD28"
			(at 0.0127 -3.1877 0)
			(unlocked yes)
			(layer "B.Fab")
			(hide yes)
			(effects
				(font
					(size 1.016 1.016)
					(thickness 0.1524)
				)
				(justify mirror)
			)
		)
		(duplicate_pad_numbers_are_jumpers no)
		(fp_poly
			(pts
				(arc
					(start 0.3556 0)
					(mid -0.3556 0)
					(end 0.3556 0)
				)
			)
			(stroke
				(width 0)
				(type default)
			)
			(fill no)
			(layer "B.CrtYd")
		)
		(fp_poly
			(pts
				(arc
					(start 0.6096 0)
					(mid -0.6096 0)
					(end 0.6096 0)
				)
			)
			(stroke
				(width 0)
				(type default)
			)
			(fill no)
			(layer "B.Fab")
		)
		(pad "1" smd circle
			(at 0 0 180)
			(size 0.7112 0.7112)
			(layers "B.Cu" "B.Mask" "B.Paste")
			(net "TP_BMC_GPIOR1")
		)
	)
	(footprint ""
		(layer "B.Cu")
		(at 125.349 -14.351)
		(property "Reference" "C144"
			(at 0 0 0)
			(layer "B.SilkS")
			(hide yes)
			(effects
				(font
					(size 1.27 1.27)
				)
				(justify mirror)
			)
		)
		(property "Value" "SC1U16V3KX-5GP"
			(at 0 -2.8194 0)
			(unlocked yes)
			(layer "B.Fab")
			(hide yes)
			(effects
				(font
					(size 1.016 1.016)
					(thickness 0.1524)
				)
				(justify mirror)
			)
		)
		(property "Device Type" "C603H36"
			(at 0 -4.3434 0)
			(unlocked yes)
			(layer "B.Fab")
			(hide yes)
			(effects
				(font
					(size 1.016 1.016)
					(thickness 0.1524)
				)
				(justify mirror)
			)
		)
		(duplicate_pad_numbers_are_jumpers no)
		(fp_line
			(start -0.508 0)
			(end 0.508 0)
			(stroke
				(width 0.2032)
				(type default)
			)
			(layer "B.SilkS")
		)
		(fp_rect
			(start 0.5842 1.3335)
			(end -0.5842 -1.3335)
			(stroke
				(width 0)
				(type default)
			)
			(fill no)
			(layer "B.CrtYd")
		)
		(fp_rect
			(start 0.5842 1.3335)
			(end -0.5842 -1.3335)
			(stroke
				(width 0)
				(type default)
			)
			(fill no)
			(layer "B.Fab")
		)
		(pad "1" smd custom
			(at 0 -0.762 180)
			(size 0.2159 0.2159)
			(layers "B.Cu" "B.Mask" "B.Paste")
			(net "MB0_CM_OV_R")
			(options
				(clearance outline)
				(anchor circle)
			)
			(primitives
				(gr_poly
					(pts
						(arc
							(start -0.3302 0.4318)
							(mid -0.402042 0.402042)
							(end -0.4318 0.3302)
						)
						(arc
							(start -0.4318 -0.3302)
							(mid -0.402042 -0.402042)
							(end -0.3302 -0.4318)
						)
						(arc
							(start 0.3302 -0.4318)
							(mid 0.402042 -0.402042)
							(end 0.4318 -0.3302)
						)
						(arc
							(start 0.4318 0.3302)
							(mid 0.402042 0.402042)
							(end 0.3302 0.4318)
						)
					)
					(width 0)
					(fill yes)
				)
			)
		)
		(pad "2" smd custom
			(at 0 0.762 180)
			(size 0.2159 0.2159)
			(layers "B.Cu" "B.Mask" "B.Paste")
			(net "AGND_CURRENT_MON")
			(options
				(clearance outline)
				(anchor circle)
			)
			(primitives
				(gr_poly
					(pts
						(arc
							(start -0.3302 0.4318)
							(mid -0.402042 0.402042)
							(end -0.4318 0.3302)
						)
						(arc
							(start -0.4318 -0.3302)
							(mid -0.402042 -0.402042)
							(end -0.3302 -0.4318)
						)
						(arc
							(start 0.3302 -0.4318)
							(mid 0.402042 -0.402042)
							(end 0.4318 -0.3302)
						)
						(arc
							(start 0.4318 0.3302)
							(mid 0.402042 0.402042)
							(end 0.3302 0.4318)
						)
					)
					(width 0)
					(fill yes)
				)
			)
		)
	)
	(footprint ""
		(layer "B.Cu")
		(at 170.035728 -124.638308 -90)
		(property "Reference" "C619"
			(at 0 0 90)
			(layer "B.SilkS")
			(hide yes)
			(effects
				(font
					(size 1.27 1.27)
				)
				(justify mirror)
			)
		)
		(property "Value" "SCD1U16V2KX-3GP"
			(at -1.1811 -2.7051 270)
			(unlocked yes)
			(layer "B.Fab")
			(hide yes)
			(effects
				(font
					(size 1.016 1.016)
					(thickness 0.1524)
				)
				(justify mirror)
			)
		)
		(property "Device Type" "C402H22"
			(at -1.1811 -4.2291 270)
			(unlocked yes)
			(layer "B.Fab")
			(hide yes)
			(effects
				(font
					(size 1.016 1.016)
					(thickness 0.1524)
				)
				(justify mirror)
			)
		)
		(duplicate_pad_numbers_are_jumpers no)
		(fp_rect
			(start 0.4318 0.9525)
			(end -0.4318 -0.9525)
			(stroke
				(width 0)
				(type default)
			)
			(fill no)
			(layer "B.CrtYd")
		)
		(fp_rect
			(start 0.4318 0.9525)
			(end -0.4318 -0.9525)
			(stroke
				(width 0)
				(type default)
			)
			(fill no)
			(layer "B.Fab")
		)
		(pad "1" smd custom
			(at 0 -0.4445 90)
			(size 0.1524 0.1524)
			(layers "B.Cu" "B.Mask" "B.Paste")
			(net "P3V3_M2")
			(options
				(clearance outline)
				(anchor circle)
			)
			(primitives
				(gr_poly
					(pts
						(arc
							(start 0.3048 0.2032)
							(mid 0.275042 0.275042)
							(end 0.2032 0.3048)
						)
						(arc
							(start -0.2032 0.3048)
							(mid -0.275042 0.275042)
							(end -0.3048 0.2032)
						)
						(arc
							(start -0.3048 -0.2032)
							(mid -0.275042 -0.275042)
							(end -0.2032 -0.3048)
						)
						(arc
							(start 0.2032 -0.3048)
							(mid 0.275042 -0.275042)
							(end 0.3048 -0.2032)
						)
					)
					(width 0)
					(fill yes)
				)
			)
		)
		(pad "2" smd custom
			(at 0 0.4445 90)
			(size 0.1524 0.1524)
			(layers "B.Cu" "B.Mask" "B.Paste")
			(net "GND")
			(options
				(clearance outline)
				(anchor circle)
			)
			(primitives
				(gr_poly
					(pts
						(arc
							(start 0.3048 0.2032)
							(mid 0.275042 0.275042)
							(end 0.2032 0.3048)
						)
						(arc
							(start -0.2032 0.3048)
							(mid -0.275042 0.275042)
							(end -0.3048 0.2032)
						)
						(arc
							(start -0.3048 -0.2032)
							(mid -0.275042 -0.275042)
							(end -0.2032 -0.3048)
						)
						(arc
							(start 0.2032 -0.3048)
							(mid 0.275042 -0.275042)
							(end 0.3048 -0.2032)
						)
					)
					(width 0)
					(fill yes)
				)
			)
		)
	)
	(footprint ""
		(layer "B.Cu")
		(at 48.079406 -147.98675 90)
		(property "Reference" "C107"
			(at 0 0 90)
			(layer "B.SilkS")
			(hide yes)
			(effects
				(font
					(size 1.27 1.27)
				)
				(justify mirror)
			)
		)
		(property "Value" "SC1U16V3KX-5GP"
			(at 0 -2.8194 90)
			(unlocked yes)
			(layer "B.Fab")
			(hide yes)
			(effects
				(font
					(size 1.016 1.016)
					(thickness 0.1524)
				)
				(justify mirror)
			)
		)
		(property "Device Type" "C603H36"
			(at 0 -4.3434 90)
			(unlocked yes)
			(layer "B.Fab")
			(hide yes)
			(effects
				(font
					(size 1.016 1.016)
					(thickness 0.1524)
				)
				(justify mirror)
			)
		)
		(duplicate_pad_numbers_are_jumpers no)
		(fp_line
			(start -0.508 0)
			(end 0.508 0)
			(stroke
				(width 0.2032)
				(type default)
			)
			(layer "B.SilkS")
		)
		(fp_rect
			(start 0.5842 1.3335)
			(end -0.5842 -1.3335)
			(stroke
				(width 0)
				(type default)
			)
			(fill no)
			(layer "B.CrtYd")
		)
		(fp_rect
			(start 0.5842 1.3335)
			(end -0.5842 -1.3335)
			(stroke
				(width 0)
				(type default)
			)
			(fill no)
			(layer "B.Fab")
		)
		(pad "1" smd custom
			(at 0 -0.762 270)
			(size 0.2159 0.2159)
			(layers "B.Cu" "B.Mask" "B.Paste")
			(net "P1V15_STBY")
			(options
				(clearance outline)
				(anchor circle)
			)
			(primitives
				(gr_poly
					(pts
						(arc
							(start -0.3302 0.4318)
							(mid -0.402042 0.402042)
							(end -0.4318 0.3302)
						)
						(arc
							(start -0.4318 -0.3302)
							(mid -0.402042 -0.402042)
							(end -0.3302 -0.4318)
						)
						(arc
							(start 0.3302 -0.4318)
							(mid 0.402042 -0.402042)
							(end 0.4318 -0.3302)
						)
						(arc
							(start 0.4318 0.3302)
							(mid 0.402042 0.402042)
							(end 0.3302 0.4318)
						)
					)
					(width 0)
					(fill yes)
				)
			)
		)
		(pad "2" smd custom
			(at 0 0.762 270)
			(size 0.2159 0.2159)
			(layers "B.Cu" "B.Mask" "B.Paste")
			(net "GND")
			(options
				(clearance outline)
				(anchor circle)
			)
			(primitives
				(gr_poly
					(pts
						(arc
							(start -0.3302 0.4318)
							(mid -0.402042 0.402042)
							(end -0.4318 0.3302)
						)
						(arc
							(start -0.4318 -0.3302)
							(mid -0.402042 -0.402042)
							(end -0.3302 -0.4318)
						)
						(arc
							(start 0.3302 -0.4318)
							(mid 0.402042 -0.402042)
							(end 0.4318 -0.3302)
						)
						(arc
							(start 0.4318 0.3302)
							(mid 0.402042 0.402042)
							(end 0.3302 0.4318)
						)
					)
					(width 0)
					(fill yes)
				)
			)
		)
	)
	(footprint ""
		(layer "B.Cu")
		(at 124.95784 -9.622282 90)
		(property "Reference" "R449"
			(at 0 0 90)
			(layer "B.SilkS")
			(hide yes)
			(effects
				(font
					(size 1.27 1.27)
				)
				(justify mirror)
			)
		)
		(property "Value" "1KR2J-1-GP"
			(at -0.064008 -3.993896 90)
			(unlocked yes)
			(layer "B.Fab")
			(hide yes)
			(effects
				(font
					(size 1.016 1.016)
					(thickness 0.1524)
				)
				(justify mirror)
			)
		)
		(property "Device Type" "R402H16"
			(at -0.064008 -5.517896 90)
			(unlocked yes)
			(layer "B.Fab")
			(hide yes)
			(effects
				(font
					(size 1.016 1.016)
					(thickness 0.1524)
				)
				(justify mirror)
			)
		)
		(duplicate_pad_numbers_are_jumpers no)
		(fp_line
			(start 0.508 -0.9398)
			(end 0.508 0.9398)
			(stroke
				(width 0.1524)
				(type default)
			)
			(layer "B.SilkS")
		)
		(fp_line
			(start -0.508 -0.9398)
			(end 0.508 -0.9398)
			(stroke
				(width 0.1524)
				(type default)
			)
			(layer "B.SilkS")
		)
		(fp_rect
			(start 0.508 0.9398)
			(end -0.508 -0.9398)
			(stroke
				(width 0)
				(type default)
			)
			(fill no)
			(layer "B.CrtYd")
		)
		(fp_rect
			(start 0.508 0.9398)
			(end -0.508 -0.9398)
			(stroke
				(width 0)
				(type default)
			)
			(fill no)
			(layer "B.Fab")
		)
		(pad "1" smd custom
			(at 0 -0.4445 270)
			(size 0.1397 0.1397)
			(layers "B.Cu" "B.Mask" "B.Paste")
			(net "MB0_CM_VOUT_R")
			(options
				(clearance outline)
				(anchor circle)
			)
			(primitives
				(gr_poly
					(pts
						(arc
							(start -0.1778 0.2794)
							(mid -0.249642 0.249642)
							(end -0.2794 0.1778)
						)
						(arc
							(start -0.2794 -0.1778)
							(mid -0.249642 -0.249642)
							(end -0.1778 -0.2794)
						)
						(arc
							(start 0.1778 -0.2794)
							(mid 0.249642 -0.249642)
							(end 0.2794 -0.1778)
						)
						(arc
							(start 0.2794 0.1778)
							(mid 0.249642 0.249642)
							(end 0.1778 0.2794)
						)
					)
					(width 0)
					(fill yes)
				)
			)
		)
		(pad "2" smd custom
			(at 0 0.4445 270)
			(size 0.1397 0.1397)
			(layers "B.Cu" "B.Mask" "B.Paste")
			(net "P12V_STBY")
			(options
				(clearance outline)
				(anchor circle)
			)
			(primitives
				(gr_poly
					(pts
						(arc
							(start -0.1778 0.2794)
							(mid -0.249642 0.249642)
							(end -0.2794 0.1778)
						)
						(arc
							(start -0.2794 -0.1778)
							(mid -0.249642 -0.249642)
							(end -0.1778 -0.2794)
						)
						(arc
							(start 0.1778 -0.2794)
							(mid 0.249642 -0.249642)
							(end 0.2794 -0.1778)
						)
						(arc
							(start 0.2794 0.1778)
							(mid 0.249642 0.249642)
							(end 0.1778 0.2794)
						)
					)
					(width 0)
					(fill yes)
				)
			)
		)
	)
	(footprint ""
		(layer "B.Cu")
		(at 57.3786 -154.9146)
		(property "Reference" "R303"
			(at 0 0 0)
			(layer "B.SilkS")
			(hide yes)
			(effects
				(font
					(size 1.27 1.27)
				)
				(justify mirror)
			)
		)
		(property "Value" "47KR2F-GP"
			(at -0.064008 -3.993896 0)
			(unlocked yes)
			(layer "B.Fab")
			(hide yes)
			(effects
				(font
					(size 1.016 1.016)
					(thickness 0.1524)
				)
				(justify mirror)
			)
		)
		(property "Device Type" "R402H16"
			(at -0.064008 -5.517896 0)
			(unlocked yes)
			(layer "B.Fab")
			(hide yes)
			(effects
				(font
					(size 1.016 1.016)
					(thickness 0.1524)
				)
				(justify mirror)
			)
		)
		(duplicate_pad_numbers_are_jumpers no)
		(fp_line
			(start -0.508 -0.9398)
			(end 0.508 -0.9398)
			(stroke
				(width 0.1524)
				(type default)
			)
			(layer "B.SilkS")
		)
		(fp_line
			(start 0.508 -0.9398)
			(end 0.508 0.9398)
			(stroke
				(width 0.1524)
				(type default)
			)
			(layer "B.SilkS")
		)
		(fp_rect
			(start 0.508 0.9398)
			(end -0.508 -0.9398)
			(stroke
				(width 0)
				(type default)
			)
			(fill no)
			(layer "B.CrtYd")
		)
		(fp_rect
			(start 0.508 0.9398)
			(end -0.508 -0.9398)
			(stroke
				(width 0)
				(type default)
			)
			(fill no)
			(layer "B.Fab")
		)
		(pad "1" smd custom
			(at 0 -0.4445 180)
			(size 0.1397 0.1397)
			(layers "B.Cu" "B.Mask" "B.Paste")
			(net "GND")
			(options
				(clearance outline)
				(anchor circle)
			)
			(primitives
				(gr_poly
					(pts
						(arc
							(start -0.1778 0.2794)
							(mid -0.249642 0.249642)
							(end -0.2794 0.1778)
						)
						(arc
							(start -0.2794 -0.1778)
							(mid -0.249642 -0.249642)
							(end -0.1778 -0.2794)
						)
						(arc
							(start 0.1778 -0.2794)
							(mid 0.249642 -0.249642)
							(end 0.2794 -0.1778)
						)
						(arc
							(start 0.2794 0.1778)
							(mid 0.249642 0.249642)
							(end 0.1778 0.2794)
						)
					)
					(width 0)
					(fill yes)
				)
			)
		)
		(pad "2" smd custom
			(at 0 0.4445 180)
			(size 0.1397 0.1397)
			(layers "B.Cu" "B.Mask" "B.Paste")
			(net "BMC_RGMII_C2_C3_D1_D2_E6")
			(options
				(clearance outline)
				(anchor circle)
			)
			(primitives
				(gr_poly
					(pts
						(arc
							(start -0.1778 0.2794)
							(mid -0.249642 0.249642)
							(end -0.2794 0.1778)
						)
						(arc
							(start -0.2794 -0.1778)
							(mid -0.249642 -0.249642)
							(end -0.1778 -0.2794)
						)
						(arc
							(start 0.1778 -0.2794)
							(mid 0.249642 -0.249642)
							(end 0.2794 -0.1778)
						)
						(arc
							(start 0.2794 0.1778)
							(mid 0.249642 0.249642)
							(end 0.1778 0.2794)
						)
					)
					(width 0)
					(fill yes)
				)
			)
		)
	)
	(footprint ""
		(layer "B.Cu")
		(at 55.72125 -147.754594)
		(property "Reference" "TP82"
			(at 0 0 0)
			(layer "B.SilkS")
			(hide yes)
			(effects
				(font
					(size 1.27 1.27)
				)
				(justify mirror)
			)
		)
		(property "Value" "TPAD28-2-GP"
			(at 0.0127 -1.6637 0)
			(unlocked yes)
			(layer "B.Fab")
			(hide yes)
			(effects
				(font
					(size 1.016 1.016)
					(thickness 0.1524)
				)
				(justify mirror)
			)
		)
		(property "Device Type" "TPAD28"
			(at 0.0127 -3.1877 0)
			(unlocked yes)
			(layer "B.Fab")
			(hide yes)
			(effects
				(font
					(size 1.016 1.016)
					(thickness 0.1524)
				)
				(justify mirror)
			)
		)
		(duplicate_pad_numbers_are_jumpers no)
		(fp_poly
			(pts
				(arc
					(start 0.3556 0)
					(mid -0.3556 0)
					(end 0.3556 0)
				)
			)
			(stroke
				(width 0)
				(type default)
			)
			(fill no)
			(layer "B.CrtYd")
		)
		(fp_poly
			(pts
				(arc
					(start 0.6096 0)
					(mid -0.6096 0)
					(end 0.6096 0)
				)
			)
			(stroke
				(width 0)
				(type default)
			)
			(fill no)
			(layer "B.Fab")
		)
		(pad "1" smd circle
			(at 0 0 180)
			(size 0.7112 0.7112)
			(layers "B.Cu" "B.Mask" "B.Paste")
			(net "BMC0_JTAG_RTCK")
		)
	)
	(footprint ""
		(layer "B.Cu")
		(at 62.73292 -142.308072)
		(property "Reference" "R195"
			(at 0 0 0)
			(layer "B.SilkS")
			(hide yes)
			(effects
				(font
					(size 1.27 1.27)
				)
				(justify mirror)
			)
		)
		(property "Value" "2K2R2F-GP"
			(at -0.064008 -3.993896 0)
			(unlocked yes)
			(layer "B.Fab")
			(hide yes)
			(effects
				(font
					(size 1.016 1.016)
					(thickness 0.1524)
				)
				(justify mirror)
			)
		)
		(property "Device Type" "R402H16"
			(at -0.064008 -5.517896 0)
			(unlocked yes)
			(layer "B.Fab")
			(hide yes)
			(effects
				(font
					(size 1.016 1.016)
					(thickness 0.1524)
				)
				(justify mirror)
			)
		)
		(duplicate_pad_numbers_are_jumpers no)
		(fp_line
			(start -0.508 -0.9398)
			(end 0.508 -0.9398)
			(stroke
				(width 0.1524)
				(type default)
			)
			(layer "B.SilkS")
		)
		(fp_line
			(start 0.508 -0.9398)
			(end 0.508 0.9398)
			(stroke
				(width 0.1524)
				(type default)
			)
			(layer "B.SilkS")
		)
		(fp_rect
			(start 0.508 0.9398)
			(end -0.508 -0.9398)
			(stroke
				(width 0)
				(type default)
			)
			(fill no)
			(layer "B.CrtYd")
		)
		(fp_rect
			(start 0.508 0.9398)
			(end -0.508 -0.9398)
			(stroke
				(width 0)
				(type default)
			)
			(fill no)
			(layer "B.Fab")
		)
		(pad "1" smd custom
			(at 0 -0.4445 180)
			(size 0.1397 0.1397)
			(layers "B.Cu" "B.Mask" "B.Paste")
			(net "I2C_EXP_LOC_SCL_OUT")
			(options
				(clearance outline)
				(anchor circle)
			)
			(primitives
				(gr_poly
					(pts
						(arc
							(start -0.1778 0.2794)
							(mid -0.249642 0.249642)
							(end -0.2794 0.1778)
						)
						(arc
							(start -0.2794 -0.1778)
							(mid -0.249642 -0.249642)
							(end -0.1778 -0.2794)
						)
						(arc
							(start 0.1778 -0.2794)
							(mid 0.249642 -0.249642)
							(end 0.2794 -0.1778)
						)
						(arc
							(start 0.2794 0.1778)
							(mid 0.249642 0.249642)
							(end 0.1778 0.2794)
						)
					)
					(width 0)
					(fill yes)
				)
			)
		)
		(pad "2" smd custom
			(at 0 0.4445 180)
			(size 0.1397 0.1397)
			(layers "B.Cu" "B.Mask" "B.Paste")
			(net "P3V3_STBY")
			(options
				(clearance outline)
				(anchor circle)
			)
			(primitives
				(gr_poly
					(pts
						(arc
							(start -0.1778 0.2794)
							(mid -0.249642 0.249642)
							(end -0.2794 0.1778)
						)
						(arc
							(start -0.2794 -0.1778)
							(mid -0.249642 -0.249642)
							(end -0.1778 -0.2794)
						)
						(arc
							(start 0.1778 -0.2794)
							(mid 0.249642 -0.249642)
							(end 0.2794 -0.1778)
						)
						(arc
							(start 0.2794 0.1778)
							(mid 0.249642 0.249642)
							(end 0.1778 0.2794)
						)
					)
					(width 0)
					(fill yes)
				)
			)
		)
	)
	(footprint ""
		(layer "B.Cu")
		(at 92.45092 -138.2268 -90)
		(property "Reference" "R275"
			(at 0 0 90)
			(layer "B.SilkS")
			(hide yes)
			(effects
				(font
					(size 1.27 1.27)
				)
				(justify mirror)
			)
		)
		(property "Value" "100KR2F-L1-GP"
			(at -0.064008 -3.993896 270)
			(unlocked yes)
			(layer "B.Fab")
			(hide yes)
			(effects
				(font
					(size 1.016 1.016)
					(thickness 0.1524)
				)
				(justify mirror)
			)
		)
		(property "Device Type" "R402H16"
			(at -0.064008 -5.517896 270)
			(unlocked yes)
			(layer "B.Fab")
			(hide yes)
			(effects
				(font
					(size 1.016 1.016)
					(thickness 0.1524)
				)
				(justify mirror)
			)
		)
		(duplicate_pad_numbers_are_jumpers no)
		(fp_line
			(start -0.508 -0.9398)
			(end 0.508 -0.9398)
			(stroke
				(width 0.1524)
				(type default)
			)
			(layer "B.SilkS")
		)
		(fp_line
			(start 0.508 -0.9398)
			(end 0.508 0.9398)
			(stroke
				(width 0.1524)
				(type default)
			)
			(layer "B.SilkS")
		)
		(fp_rect
			(start 0.508 0.9398)
			(end -0.508 -0.9398)
			(stroke
				(width 0)
				(type default)
			)
			(fill no)
			(layer "B.CrtYd")
		)
		(fp_rect
			(start 0.508 0.9398)
			(end -0.508 -0.9398)
			(stroke
				(width 0)
				(type default)
			)
			(fill no)
			(layer "B.Fab")
		)
		(pad "1" smd custom
			(at 0 -0.4445 90)
			(size 0.1397 0.1397)
			(layers "B.Cu" "B.Mask" "B.Paste")
			(net "DEBUG_CARD_PRSNT")
			(options
				(clearance outline)
				(anchor circle)
			)
			(primitives
				(gr_poly
					(pts
						(arc
							(start -0.1778 0.2794)
							(mid -0.249642 0.249642)
							(end -0.2794 0.1778)
						)
						(arc
							(start -0.2794 -0.1778)
							(mid -0.249642 -0.249642)
							(end -0.1778 -0.2794)
						)
						(arc
							(start 0.1778 -0.2794)
							(mid 0.249642 -0.249642)
							(end 0.2794 -0.1778)
						)
						(arc
							(start 0.2794 0.1778)
							(mid 0.249642 0.249642)
							(end 0.1778 0.2794)
						)
					)
					(width 0)
					(fill yes)
				)
			)
		)
		(pad "2" smd custom
			(at 0 0.4445 90)
			(size 0.1397 0.1397)
			(layers "B.Cu" "B.Mask" "B.Paste")
			(net "GND")
			(options
				(clearance outline)
				(anchor circle)
			)
			(primitives
				(gr_poly
					(pts
						(arc
							(start -0.1778 0.2794)
							(mid -0.249642 0.249642)
							(end -0.2794 0.1778)
						)
						(arc
							(start -0.2794 -0.1778)
							(mid -0.249642 -0.249642)
							(end -0.1778 -0.2794)
						)
						(arc
							(start 0.1778 -0.2794)
							(mid 0.249642 -0.249642)
							(end 0.2794 -0.1778)
						)
						(arc
							(start 0.2794 0.1778)
							(mid 0.249642 0.249642)
							(end 0.1778 0.2794)
						)
					)
					(width 0)
					(fill yes)
				)
			)
		)
	)
	(footprint ""
		(layer "B.Cu")
		(at 177.80635 -113.280444 90)
		(property "Reference" "C634"
			(at 0 0 90)
			(layer "B.SilkS")
			(hide yes)
			(effects
				(font
					(size 1.27 1.27)
				)
				(justify mirror)
			)
		)
		(property "Value" "SCD1U16V2KX-3GP"
			(at -1.1811 -2.7051 90)
			(unlocked yes)
			(layer "B.Fab")
			(hide yes)
			(effects
				(font
					(size 1.016 1.016)
					(thickness 0.1524)
				)
				(justify mirror)
			)
		)
		(property "Device Type" "C402H22"
			(at -1.1811 -4.2291 90)
			(unlocked yes)
			(layer "B.Fab")
			(hide yes)
			(effects
				(font
					(size 1.016 1.016)
					(thickness 0.1524)
				)
				(justify mirror)
			)
		)
		(duplicate_pad_numbers_are_jumpers no)
		(fp_rect
			(start 0.4318 0.9525)
			(end -0.4318 -0.9525)
			(stroke
				(width 0)
				(type default)
			)
			(fill no)
			(layer "B.CrtYd")
		)
		(fp_rect
			(start 0.4318 0.9525)
			(end -0.4318 -0.9525)
			(stroke
				(width 0)
				(type default)
			)
			(fill no)
			(layer "B.Fab")
		)
		(pad "1" smd custom
			(at 0 -0.4445 270)
			(size 0.1524 0.1524)
			(layers "B.Cu" "B.Mask" "B.Paste")
			(net "U83_VREF2")
			(options
				(clearance outline)
				(anchor circle)
			)
			(primitives
				(gr_poly
					(pts
						(arc
							(start 0.3048 0.2032)
							(mid 0.275042 0.275042)
							(end 0.2032 0.3048)
						)
						(arc
							(start -0.2032 0.3048)
							(mid -0.275042 0.275042)
							(end -0.3048 0.2032)
						)
						(arc
							(start -0.3048 -0.2032)
							(mid -0.275042 -0.275042)
							(end -0.2032 -0.3048)
						)
						(arc
							(start 0.2032 -0.3048)
							(mid 0.275042 -0.275042)
							(end 0.3048 -0.2032)
						)
					)
					(width 0)
					(fill yes)
				)
			)
		)
		(pad "2" smd custom
			(at 0 0.4445 270)
			(size 0.1524 0.1524)
			(layers "B.Cu" "B.Mask" "B.Paste")
			(net "GND")
			(options
				(clearance outline)
				(anchor circle)
			)
			(primitives
				(gr_poly
					(pts
						(arc
							(start 0.3048 0.2032)
							(mid 0.275042 0.275042)
							(end 0.2032 0.3048)
						)
						(arc
							(start -0.2032 0.3048)
							(mid -0.275042 0.275042)
							(end -0.3048 0.2032)
						)
						(arc
							(start -0.3048 -0.2032)
							(mid -0.275042 -0.275042)
							(end -0.2032 -0.3048)
						)
						(arc
							(start 0.2032 -0.3048)
							(mid 0.275042 -0.275042)
							(end 0.3048 -0.2032)
						)
					)
					(width 0)
					(fill yes)
				)
			)
		)
	)
	(footprint ""
		(layer "B.Cu")
		(at 59.962796 -136.357614 90)
		(property "Reference" "TP205"
			(at 0 0 90)
			(layer "B.SilkS")
			(hide yes)
			(effects
				(font
					(size 1.27 1.27)
				)
				(justify mirror)
			)
		)
		(property "Value" "TPAD28-2-GP"
			(at 0.0127 -1.6637 90)
			(unlocked yes)
			(layer "B.Fab")
			(hide yes)
			(effects
				(font
					(size 1.016 1.016)
					(thickness 0.1524)
				)
				(justify mirror)
			)
		)
		(property "Device Type" "TPAD28"
			(at 0.0127 -3.1877 90)
			(unlocked yes)
			(layer "B.Fab")
			(hide yes)
			(effects
				(font
					(size 1.016 1.016)
					(thickness 0.1524)
				)
				(justify mirror)
			)
		)
		(duplicate_pad_numbers_are_jumpers no)
		(fp_poly
			(pts
				(arc
					(start 0 0.3556)
					(mid 0 -0.3556)
					(end 0 0.3556)
				)
			)
			(stroke
				(width 0)
				(type default)
			)
			(fill no)
			(layer "B.CrtYd")
		)
		(fp_poly
			(pts
				(arc
					(start 0 0.6096)
					(mid 0 -0.6096)
					(end 0 0.6096)
				)
			)
			(stroke
				(width 0)
				(type default)
			)
			(fill no)
			(layer "B.Fab")
		)
		(pad "1" smd circle
			(at 0 0 270)
			(size 0.7112 0.7112)
			(layers "B.Cu" "B.Mask" "B.Paste")
			(net "TP_BMC_EXT1_LED_B")
		)
	)
	(footprint ""
		(layer "B.Cu")
		(at 64.262 -154.8892 -90)
		(property "Reference" "C80"
			(at 0 0 90)
			(layer "B.SilkS")
			(hide yes)
			(effects
				(font
					(size 1.27 1.27)
				)
				(justify mirror)
			)
		)
		(property "Value" "SCD1U16V2KX-3GP"
			(at -1.1811 -2.7051 270)
			(unlocked yes)
			(layer "B.Fab")
			(hide yes)
			(effects
				(font
					(size 1.016 1.016)
					(thickness 0.1524)
				)
				(justify mirror)
			)
		)
		(property "Device Type" "C402H22"
			(at -1.1811 -4.2291 270)
			(unlocked yes)
			(layer "B.Fab")
			(hide yes)
			(effects
				(font
					(size 1.016 1.016)
					(thickness 0.1524)
				)
				(justify mirror)
			)
		)
		(duplicate_pad_numbers_are_jumpers no)
		(fp_rect
			(start 0.4318 0.9525)
			(end -0.4318 -0.9525)
			(stroke
				(width 0)
				(type default)
			)
			(fill no)
			(layer "B.CrtYd")
		)
		(fp_rect
			(start 0.4318 0.9525)
			(end -0.4318 -0.9525)
			(stroke
				(width 0)
				(type default)
			)
			(fill no)
			(layer "B.Fab")
		)
		(pad "1" smd custom
			(at 0 -0.4445 90)
			(size 0.1524 0.1524)
			(layers "B.Cu" "B.Mask" "B.Paste")
			(net "P3V3_STBY")
			(options
				(clearance outline)
				(anchor circle)
			)
			(primitives
				(gr_poly
					(pts
						(arc
							(start 0.3048 0.2032)
							(mid 0.275042 0.275042)
							(end 0.2032 0.3048)
						)
						(arc
							(start -0.2032 0.3048)
							(mid -0.275042 0.275042)
							(end -0.3048 0.2032)
						)
						(arc
							(start -0.3048 -0.2032)
							(mid -0.275042 -0.275042)
							(end -0.2032 -0.3048)
						)
						(arc
							(start 0.2032 -0.3048)
							(mid 0.275042 -0.275042)
							(end 0.3048 -0.2032)
						)
					)
					(width 0)
					(fill yes)
				)
			)
		)
		(pad "2" smd custom
			(at 0 0.4445 90)
			(size 0.1524 0.1524)
			(layers "B.Cu" "B.Mask" "B.Paste")
			(net "GND")
			(options
				(clearance outline)
				(anchor circle)
			)
			(primitives
				(gr_poly
					(pts
						(arc
							(start 0.3048 0.2032)
							(mid 0.275042 0.275042)
							(end 0.2032 0.3048)
						)
						(arc
							(start -0.2032 0.3048)
							(mid -0.275042 0.275042)
							(end -0.3048 0.2032)
						)
						(arc
							(start -0.3048 -0.2032)
							(mid -0.275042 -0.275042)
							(end -0.2032 -0.3048)
						)
						(arc
							(start 0.2032 -0.3048)
							(mid 0.275042 -0.275042)
							(end 0.3048 -0.2032)
						)
					)
					(width 0)
					(fill yes)
				)
			)
		)
	)
	(footprint ""
		(layer "B.Cu")
		(at 40.884856 -182.948072)
		(property "Reference" "C178"
			(at 0 0 0)
			(layer "B.SilkS")
			(hide yes)
			(effects
				(font
					(size 1.27 1.27)
				)
				(justify mirror)
			)
		)
		(property "Value" "SCD1U50V3KX-GP"
			(at 0 -2.8194 0)
			(unlocked yes)
			(layer "B.Fab")
			(hide yes)
			(effects
				(font
					(size 1.016 1.016)
					(thickness 0.1524)
				)
				(justify mirror)
			)
		)
		(property "Device Type" "C603H36"
			(at 0 -4.3434 0)
			(unlocked yes)
			(layer "B.Fab")
			(hide yes)
			(effects
				(font
					(size 1.016 1.016)
					(thickness 0.1524)
				)
				(justify mirror)
			)
		)
		(duplicate_pad_numbers_are_jumpers no)
		(fp_line
			(start -0.508 0)
			(end 0.508 0)
			(stroke
				(width 0.2032)
				(type default)
			)
			(layer "B.SilkS")
		)
		(fp_rect
			(start 0.5842 1.3335)
			(end -0.5842 -1.3335)
			(stroke
				(width 0)
				(type default)
			)
			(fill no)
			(layer "B.CrtYd")
		)
		(fp_rect
			(start 0.5842 1.3335)
			(end -0.5842 -1.3335)
			(stroke
				(width 0)
				(type default)
			)
			(fill no)
			(layer "B.Fab")
		)
		(pad "1" smd custom
			(at 0 -0.762 180)
			(size 0.2159 0.2159)
			(layers "B.Cu" "B.Mask" "B.Paste")
			(net "P3V3_VBST_RC")
			(options
				(clearance outline)
				(anchor circle)
			)
			(primitives
				(gr_poly
					(pts
						(arc
							(start -0.3302 0.4318)
							(mid -0.402042 0.402042)
							(end -0.4318 0.3302)
						)
						(arc
							(start -0.4318 -0.3302)
							(mid -0.402042 -0.402042)
							(end -0.3302 -0.4318)
						)
						(arc
							(start 0.3302 -0.4318)
							(mid 0.402042 -0.402042)
							(end 0.4318 -0.3302)
						)
						(arc
							(start 0.4318 0.3302)
							(mid 0.402042 0.402042)
							(end 0.3302 0.4318)
						)
					)
					(width 0)
					(fill yes)
				)
			)
		)
		(pad "2" smd custom
			(at 0 0.762 180)
			(size 0.2159 0.2159)
			(layers "B.Cu" "B.Mask" "B.Paste")
			(net "P3V3_STBY_LL")
			(options
				(clearance outline)
				(anchor circle)
			)
			(primitives
				(gr_poly
					(pts
						(arc
							(start -0.3302 0.4318)
							(mid -0.402042 0.402042)
							(end -0.4318 0.3302)
						)
						(arc
							(start -0.4318 -0.3302)
							(mid -0.402042 -0.402042)
							(end -0.3302 -0.4318)
						)
						(arc
							(start 0.3302 -0.4318)
							(mid 0.402042 -0.402042)
							(end 0.4318 -0.3302)
						)
						(arc
							(start 0.4318 0.3302)
							(mid 0.402042 0.402042)
							(end 0.3302 0.4318)
						)
					)
					(width 0)
					(fill yes)
				)
			)
		)
	)
	(footprint ""
		(layer "B.Cu")
		(at 47.23892 -132.09143 90)
		(property "Reference" "R183"
			(at 0 0 90)
			(layer "B.SilkS")
			(hide yes)
			(effects
				(font
					(size 1.27 1.27)
				)
				(justify mirror)
			)
		)
		(property "Value" "2K2R2F-GP"
			(at -0.064008 -3.993896 90)
			(unlocked yes)
			(layer "B.Fab")
			(hide yes)
			(effects
				(font
					(size 1.016 1.016)
					(thickness 0.1524)
				)
				(justify mirror)
			)
		)
		(property "Device Type" "R402H16"
			(at -0.064008 -5.517896 90)
			(unlocked yes)
			(layer "B.Fab")
			(hide yes)
			(effects
				(font
					(size 1.016 1.016)
					(thickness 0.1524)
				)
				(justify mirror)
			)
		)
		(duplicate_pad_numbers_are_jumpers no)
		(fp_line
			(start 0.508 -0.9398)
			(end 0.508 0.9398)
			(stroke
				(width 0.1524)
				(type default)
			)
			(layer "B.SilkS")
		)
		(fp_line
			(start -0.508 -0.9398)
			(end 0.508 -0.9398)
			(stroke
				(width 0.1524)
				(type default)
			)
			(layer "B.SilkS")
		)
		(fp_rect
			(start 0.508 0.9398)
			(end -0.508 -0.9398)
			(stroke
				(width 0)
				(type default)
			)
			(fill no)
			(layer "B.CrtYd")
		)
		(fp_rect
			(start 0.508 0.9398)
			(end -0.508 -0.9398)
			(stroke
				(width 0)
				(type default)
			)
			(fill no)
			(layer "B.Fab")
		)
		(pad "1" smd custom
			(at 0 -0.4445 270)
			(size 0.1397 0.1397)
			(layers "B.Cu" "B.Mask" "B.Paste")
			(net "I2C_IOM_SCL")
			(options
				(clearance outline)
				(anchor circle)
			)
			(primitives
				(gr_poly
					(pts
						(arc
							(start -0.1778 0.2794)
							(mid -0.249642 0.249642)
							(end -0.2794 0.1778)
						)
						(arc
							(start -0.2794 -0.1778)
							(mid -0.249642 -0.249642)
							(end -0.1778 -0.2794)
						)
						(arc
							(start 0.1778 -0.2794)
							(mid 0.249642 -0.249642)
							(end 0.2794 -0.1778)
						)
						(arc
							(start 0.2794 0.1778)
							(mid 0.249642 0.249642)
							(end 0.1778 0.2794)
						)
					)
					(width 0)
					(fill yes)
				)
			)
		)
		(pad "2" smd custom
			(at 0 0.4445 270)
			(size 0.1397 0.1397)
			(layers "B.Cu" "B.Mask" "B.Paste")
			(net "P3V3_STBY")
			(options
				(clearance outline)
				(anchor circle)
			)
			(primitives
				(gr_poly
					(pts
						(arc
							(start -0.1778 0.2794)
							(mid -0.249642 0.249642)
							(end -0.2794 0.1778)
						)
						(arc
							(start -0.2794 -0.1778)
							(mid -0.249642 -0.249642)
							(end -0.1778 -0.2794)
						)
						(arc
							(start 0.1778 -0.2794)
							(mid 0.249642 -0.249642)
							(end 0.2794 -0.1778)
						)
						(arc
							(start 0.2794 0.1778)
							(mid 0.249642 0.249642)
							(end 0.1778 0.2794)
						)
					)
					(width 0)
					(fill yes)
				)
			)
		)
	)
	(footprint ""
		(layer "B.Cu")
		(at 36.039298 -143.075914)
		(property "Reference" "C60"
			(at 0 0 0)
			(layer "B.SilkS")
			(hide yes)
			(effects
				(font
					(size 1.27 1.27)
				)
				(justify mirror)
			)
		)
		(property "Value" "SC1U16V3KX-5GP"
			(at 0 -2.8194 0)
			(unlocked yes)
			(layer "B.Fab")
			(hide yes)
			(effects
				(font
					(size 1.016 1.016)
					(thickness 0.1524)
				)
				(justify mirror)
			)
		)
		(property "Device Type" "C603H36"
			(at 0 -4.3434 0)
			(unlocked yes)
			(layer "B.Fab")
			(hide yes)
			(effects
				(font
					(size 1.016 1.016)
					(thickness 0.1524)
				)
				(justify mirror)
			)
		)
		(duplicate_pad_numbers_are_jumpers no)
		(fp_line
			(start -0.508 0)
			(end 0.508 0)
			(stroke
				(width 0.2032)
				(type default)
			)
			(layer "B.SilkS")
		)
		(fp_rect
			(start 0.5842 1.3335)
			(end -0.5842 -1.3335)
			(stroke
				(width 0)
				(type default)
			)
			(fill no)
			(layer "B.CrtYd")
		)
		(fp_rect
			(start 0.5842 1.3335)
			(end -0.5842 -1.3335)
			(stroke
				(width 0)
				(type default)
			)
			(fill no)
			(layer "B.Fab")
		)
		(pad "1" smd custom
			(at 0 -0.762 180)
			(size 0.2159 0.2159)
			(layers "B.Cu" "B.Mask" "B.Paste")
			(net "P1V2_STBY")
			(options
				(clearance outline)
				(anchor circle)
			)
			(primitives
				(gr_poly
					(pts
						(arc
							(start -0.3302 0.4318)
							(mid -0.402042 0.402042)
							(end -0.4318 0.3302)
						)
						(arc
							(start -0.4318 -0.3302)
							(mid -0.402042 -0.402042)
							(end -0.3302 -0.4318)
						)
						(arc
							(start 0.3302 -0.4318)
							(mid 0.402042 -0.402042)
							(end 0.4318 -0.3302)
						)
						(arc
							(start 0.4318 0.3302)
							(mid 0.402042 0.402042)
							(end 0.3302 0.4318)
						)
					)
					(width 0)
					(fill yes)
				)
			)
		)
		(pad "2" smd custom
			(at 0 0.762 180)
			(size 0.2159 0.2159)
			(layers "B.Cu" "B.Mask" "B.Paste")
			(net "GND")
			(options
				(clearance outline)
				(anchor circle)
			)
			(primitives
				(gr_poly
					(pts
						(arc
							(start -0.3302 0.4318)
							(mid -0.402042 0.402042)
							(end -0.4318 0.3302)
						)
						(arc
							(start -0.4318 -0.3302)
							(mid -0.402042 -0.402042)
							(end -0.3302 -0.4318)
						)
						(arc
							(start 0.3302 -0.4318)
							(mid 0.402042 -0.402042)
							(end 0.4318 -0.3302)
						)
						(arc
							(start 0.4318 0.3302)
							(mid 0.402042 0.402042)
							(end 0.3302 0.4318)
						)
					)
					(width 0)
					(fill yes)
				)
			)
		)
	)
	(footprint ""
		(layer "B.Cu")
		(at 132.6261 -17.30756)
		(property "Reference" "Q24"
			(at 0 0 0)
			(layer "B.SilkS")
			(hide yes)
			(effects
				(font
					(size 1.27 1.27)
				)
				(justify mirror)
			)
		)
		(property "Value" "2N7002K-1-GP"
			(at -0.127 -8.9662 0)
			(unlocked yes)
			(layer "B.Fab")
			(hide yes)
			(effects
				(font
					(size 1.016 1.016)
					(thickness 0.1524)
				)
				(justify mirror)
			)
		)
		(property "Device Type" "SOT23DGS2D4H44"
			(at -0.127 -10.4902 0)
			(unlocked yes)
			(layer "B.Fab")
			(hide yes)
			(effects
				(font
					(size 1.016 1.016)
					(thickness 0.1524)
				)
				(justify mirror)
			)
		)
		(duplicate_pad_numbers_are_jumpers no)
		(fp_line
			(start -1.651 -1.778)
			(end 1.651 -1.778)
			(stroke
				(width 0.1524)
				(type default)
			)
			(layer "B.SilkS")
		)
		(fp_line
			(start -1.651 1.778)
			(end -1.651 -1.778)
			(stroke
				(width 0.1524)
				(type default)
			)
			(layer "B.SilkS")
		)
		(fp_line
			(start 1.651 -1.778)
			(end 1.651 1.778)
			(stroke
				(width 0.1524)
				(type default)
			)
			(layer "B.SilkS")
		)
		(fp_line
			(start 1.651 1.778)
			(end -1.651 1.778)
			(stroke
				(width 0.1524)
				(type default)
			)
			(layer "B.SilkS")
		)
		(fp_poly
			(pts
				(xy 1.778 1.8796) (xy 1.778 -1.8796) (xy -1.778 -1.8796) (xy -1.778 1.8796)
			)
			(stroke
				(width 0)
				(type default)
			)
			(fill no)
			(layer "B.CrtYd")
		)
		(fp_poly
			(pts
				(xy 1.778 1.8796) (xy 1.778 -1.8796) (xy -1.778 -1.8796) (xy -1.778 1.8796)
			)
			(stroke
				(width 0)
				(type default)
			)
			(fill no)
			(layer "B.Fab")
		)
		(pad "D" smd custom
			(at 0 -0.9525 180)
			(size 0.1905 0.1905)
			(layers "B.Cu" "B.Mask" "B.Paste")
			(net "IOM_ADM1278_EN")
			(options
				(clearance outline)
				(anchor circle)
			)
			(primitives
				(gr_poly
					(pts
						(arc
							(start -0.1778 -0.5715)
							(mid -0.321484 -0.511984)
							(end -0.381 -0.3683)
						)
						(arc
							(start -0.381 0.3683)
							(mid -0.321484 0.511984)
							(end -0.1778 0.5715)
						)
						(arc
							(start 0.1778 0.5715)
							(mid 0.321484 0.511984)
							(end 0.381 0.3683)
						)
						(arc
							(start 0.381 -0.3683)
							(mid 0.321484 -0.511984)
							(end 0.1778 -0.5715)
						)
					)
					(width 0)
					(fill yes)
				)
			)
		)
		(pad "G" smd custom
			(at 0.98425 0.9525 180)
			(size 0.1905 0.1905)
			(layers "B.Cu" "B.Mask" "B.Paste")
			(net "IOM_MATED_N")
			(options
				(clearance outline)
				(anchor circle)
			)
			(primitives
				(gr_poly
					(pts
						(arc
							(start -0.1778 -0.5715)
							(mid -0.321484 -0.511984)
							(end -0.381 -0.3683)
						)
						(arc
							(start -0.381 0.3683)
							(mid -0.321484 0.511984)
							(end -0.1778 0.5715)
						)
						(arc
							(start 0.1778 0.5715)
							(mid 0.321484 0.511984)
							(end 0.381 0.3683)
						)
						(arc
							(start 0.381 -0.3683)
							(mid 0.321484 -0.511984)
							(end 0.1778 -0.5715)
						)
					)
					(width 0)
					(fill yes)
				)
			)
		)
		(pad "S" smd custom
			(at -0.98425 0.9525 180)
			(size 0.1905 0.1905)
			(layers "B.Cu" "B.Mask" "B.Paste")
			(net "GND")
			(options
				(clearance outline)
				(anchor circle)
			)
			(primitives
				(gr_poly
					(pts
						(arc
							(start -0.1778 -0.5715)
							(mid -0.321484 -0.511984)
							(end -0.381 -0.3683)
						)
						(arc
							(start -0.381 0.3683)
							(mid -0.321484 0.511984)
							(end -0.1778 0.5715)
						)
						(arc
							(start 0.1778 0.5715)
							(mid 0.321484 0.511984)
							(end 0.381 0.3683)
						)
						(arc
							(start 0.381 -0.3683)
							(mid 0.321484 -0.511984)
							(end 0.1778 -0.5715)
						)
					)
					(width 0)
					(fill yes)
				)
			)
		)
	)
	(footprint ""
		(layer "B.Cu")
		(at 42.533316 -134.410958 180)
		(property "Reference" "R374"
			(at 0 0 0)
			(layer "B.SilkS")
			(hide yes)
			(effects
				(font
					(size 1.27 1.27)
				)
				(justify mirror)
			)
		)
		(property "Value" "4K7R2F-GP"
			(at -0.064008 -3.993896 180)
			(unlocked yes)
			(layer "B.Fab")
			(hide yes)
			(effects
				(font
					(size 1.016 1.016)
					(thickness 0.1524)
				)
				(justify mirror)
			)
		)
		(property "Device Type" "R402H16"
			(at -0.064008 -5.517896 180)
			(unlocked yes)
			(layer "B.Fab")
			(hide yes)
			(effects
				(font
					(size 1.016 1.016)
					(thickness 0.1524)
				)
				(justify mirror)
			)
		)
		(duplicate_pad_numbers_are_jumpers no)
		(fp_line
			(start 0.508 -0.9398)
			(end 0.508 0.9398)
			(stroke
				(width 0.1524)
				(type default)
			)
			(layer "B.SilkS")
		)
		(fp_line
			(start -0.508 -0.9398)
			(end 0.508 -0.9398)
			(stroke
				(width 0.1524)
				(type default)
			)
			(layer "B.SilkS")
		)
		(fp_rect
			(start 0.508 0.9398)
			(end -0.508 -0.9398)
			(stroke
				(width 0)
				(type default)
			)
			(fill no)
			(layer "B.CrtYd")
		)
		(fp_rect
			(start 0.508 0.9398)
			(end -0.508 -0.9398)
			(stroke
				(width 0)
				(type default)
			)
			(fill no)
			(layer "B.Fab")
		)
		(pad "1" smd custom
			(at 0 -0.4445)
			(size 0.1397 0.1397)
			(layers "B.Cu" "B.Mask" "B.Paste")
			(net "P3V3_STBY")
			(options
				(clearance outline)
				(anchor circle)
			)
			(primitives
				(gr_poly
					(pts
						(arc
							(start -0.1778 0.2794)
							(mid -0.249642 0.249642)
							(end -0.2794 0.1778)
						)
						(arc
							(start -0.2794 -0.1778)
							(mid -0.249642 -0.249642)
							(end -0.1778 -0.2794)
						)
						(arc
							(start 0.1778 -0.2794)
							(mid 0.249642 -0.249642)
							(end 0.2794 -0.1778)
						)
						(arc
							(start 0.2794 0.1778)
							(mid 0.249642 0.249642)
							(end 0.1778 0.2794)
						)
					)
					(width 0)
					(fill yes)
				)
			)
		)
		(pad "2" smd custom
			(at 0 0.4445)
			(size 0.1397 0.1397)
			(layers "B.Cu" "B.Mask" "B.Paste")
			(net "BMC_GPIOS6")
			(options
				(clearance outline)
				(anchor circle)
			)
			(primitives
				(gr_poly
					(pts
						(arc
							(start -0.1778 0.2794)
							(mid -0.249642 0.249642)
							(end -0.2794 0.1778)
						)
						(arc
							(start -0.2794 -0.1778)
							(mid -0.249642 -0.249642)
							(end -0.1778 -0.2794)
						)
						(arc
							(start 0.1778 -0.2794)
							(mid 0.249642 -0.249642)
							(end 0.2794 -0.1778)
						)
						(arc
							(start 0.2794 0.1778)
							(mid 0.249642 0.249642)
							(end 0.1778 0.2794)
						)
					)
					(width 0)
					(fill yes)
				)
			)
		)
	)
	(footprint ""
		(layer "B.Cu")
		(at 60.2488 -150.749 -90)
		(property "Reference" "R398"
			(at 0 0 90)
			(layer "B.SilkS")
			(hide yes)
			(effects
				(font
					(size 1.27 1.27)
				)
				(justify mirror)
			)
		)
		(property "Value" "4K7R2F-GP"
			(at -0.064008 -3.993896 270)
			(unlocked yes)
			(layer "B.Fab")
			(hide yes)
			(effects
				(font
					(size 1.016 1.016)
					(thickness 0.1524)
				)
				(justify mirror)
			)
		)
		(property "Device Type" "R402H16"
			(at -0.064008 -5.517896 270)
			(unlocked yes)
			(layer "B.Fab")
			(hide yes)
			(effects
				(font
					(size 1.016 1.016)
					(thickness 0.1524)
				)
				(justify mirror)
			)
		)
		(duplicate_pad_numbers_are_jumpers no)
		(fp_line
			(start -0.508 -0.9398)
			(end 0.508 -0.9398)
			(stroke
				(width 0.1524)
				(type default)
			)
			(layer "B.SilkS")
		)
		(fp_line
			(start 0.508 -0.9398)
			(end 0.508 0.9398)
			(stroke
				(width 0.1524)
				(type default)
			)
			(layer "B.SilkS")
		)
		(fp_rect
			(start 0.508 0.9398)
			(end -0.508 -0.9398)
			(stroke
				(width 0)
				(type default)
			)
			(fill no)
			(layer "B.CrtYd")
		)
		(fp_rect
			(start 0.508 0.9398)
			(end -0.508 -0.9398)
			(stroke
				(width 0)
				(type default)
			)
			(fill no)
			(layer "B.Fab")
		)
		(pad "1" smd custom
			(at 0 -0.4445 90)
			(size 0.1397 0.1397)
			(layers "B.Cu" "B.Mask" "B.Paste")
			(net "GND")
			(options
				(clearance outline)
				(anchor circle)
			)
			(primitives
				(gr_poly
					(pts
						(arc
							(start -0.1778 0.2794)
							(mid -0.249642 0.249642)
							(end -0.2794 0.1778)
						)
						(arc
							(start -0.2794 -0.1778)
							(mid -0.249642 -0.249642)
							(end -0.1778 -0.2794)
						)
						(arc
							(start 0.1778 -0.2794)
							(mid 0.249642 -0.249642)
							(end 0.2794 -0.1778)
						)
						(arc
							(start 0.2794 0.1778)
							(mid 0.249642 0.249642)
							(end 0.1778 0.2794)
						)
					)
					(width 0)
					(fill yes)
				)
			)
		)
		(pad "2" smd custom
			(at 0 0.4445 90)
			(size 0.1397 0.1397)
			(layers "B.Cu" "B.Mask" "B.Paste")
			(net "MAC2_TXD2")
			(options
				(clearance outline)
				(anchor circle)
			)
			(primitives
				(gr_poly
					(pts
						(arc
							(start -0.1778 0.2794)
							(mid -0.249642 0.249642)
							(end -0.2794 0.1778)
						)
						(arc
							(start -0.2794 -0.1778)
							(mid -0.249642 -0.249642)
							(end -0.1778 -0.2794)
						)
						(arc
							(start 0.1778 -0.2794)
							(mid 0.249642 -0.249642)
							(end 0.2794 -0.1778)
						)
						(arc
							(start 0.2794 0.1778)
							(mid 0.249642 0.249642)
							(end 0.1778 0.2794)
						)
					)
					(width 0)
					(fill yes)
				)
			)
		)
	)
	(footprint ""
		(layer "B.Cu")
		(at 47.854616 -161.59226 90)
		(property "Reference" "R281"
			(at 0 0 90)
			(layer "B.SilkS")
			(hide yes)
			(effects
				(font
					(size 1.27 1.27)
				)
				(justify mirror)
			)
		)
		(property "Value" "0R2J-2-GP"
			(at -0.064008 -3.993896 90)
			(unlocked yes)
			(layer "B.Fab")
			(hide yes)
			(effects
				(font
					(size 1.016 1.016)
					(thickness 0.1524)
				)
				(justify mirror)
			)
		)
		(property "Device Type" "R402H16"
			(at -0.064008 -5.517896 90)
			(unlocked yes)
			(layer "B.Fab")
			(hide yes)
			(effects
				(font
					(size 1.016 1.016)
					(thickness 0.1524)
				)
				(justify mirror)
			)
		)
		(duplicate_pad_numbers_are_jumpers no)
		(fp_line
			(start 0.508 -0.9398)
			(end 0.508 0.9398)
			(stroke
				(width 0.1524)
				(type default)
			)
			(layer "B.SilkS")
		)
		(fp_line
			(start -0.508 -0.9398)
			(end 0.508 -0.9398)
			(stroke
				(width 0.1524)
				(type default)
			)
			(layer "B.SilkS")
		)
		(fp_rect
			(start 0.508 0.9398)
			(end -0.508 -0.9398)
			(stroke
				(width 0)
				(type default)
			)
			(fill no)
			(layer "B.CrtYd")
		)
		(fp_rect
			(start 0.508 0.9398)
			(end -0.508 -0.9398)
			(stroke
				(width 0)
				(type default)
			)
			(fill no)
			(layer "B.Fab")
		)
		(pad "1" smd custom
			(at 0 -0.4445 270)
			(size 0.1397 0.1397)
			(layers "B.Cu" "B.Mask" "B.Paste")
			(net "I2C_MEZZ_OOB_SDA")
			(options
				(clearance outline)
				(anchor circle)
			)
			(primitives
				(gr_poly
					(pts
						(arc
							(start -0.1778 0.2794)
							(mid -0.249642 0.249642)
							(end -0.2794 0.1778)
						)
						(arc
							(start -0.2794 -0.1778)
							(mid -0.249642 -0.249642)
							(end -0.1778 -0.2794)
						)
						(arc
							(start 0.1778 -0.2794)
							(mid 0.249642 -0.249642)
							(end 0.2794 -0.1778)
						)
						(arc
							(start 0.2794 0.1778)
							(mid 0.249642 0.249642)
							(end 0.1778 0.2794)
						)
					)
					(width 0)
					(fill yes)
				)
			)
		)
		(pad "2" smd custom
			(at 0 0.4445 270)
			(size 0.1397 0.1397)
			(layers "B.Cu" "B.Mask" "B.Paste")
			(net "BMC_SMB5_DAT")
			(options
				(clearance outline)
				(anchor circle)
			)
			(primitives
				(gr_poly
					(pts
						(arc
							(start -0.1778 0.2794)
							(mid -0.249642 0.249642)
							(end -0.2794 0.1778)
						)
						(arc
							(start -0.2794 -0.1778)
							(mid -0.249642 -0.249642)
							(end -0.1778 -0.2794)
						)
						(arc
							(start 0.1778 -0.2794)
							(mid 0.249642 -0.249642)
							(end 0.2794 -0.1778)
						)
						(arc
							(start 0.2794 0.1778)
							(mid 0.249642 0.249642)
							(end 0.1778 0.2794)
						)
					)
					(width 0)
					(fill yes)
				)
			)
		)
	)
	(footprint ""
		(layer "B.Cu")
		(at 54.153054 -144.994122 90)
		(property "Reference" "TP83"
			(at 0 0 90)
			(layer "B.SilkS")
			(hide yes)
			(effects
				(font
					(size 1.27 1.27)
				)
				(justify mirror)
			)
		)
		(property "Value" "TPAD28-2-GP"
			(at 0.0127 -1.6637 90)
			(unlocked yes)
			(layer "B.Fab")
			(hide yes)
			(effects
				(font
					(size 1.016 1.016)
					(thickness 0.1524)
				)
				(justify mirror)
			)
		)
		(property "Device Type" "TPAD28"
			(at 0.0127 -3.1877 90)
			(unlocked yes)
			(layer "B.Fab")
			(hide yes)
			(effects
				(font
					(size 1.016 1.016)
					(thickness 0.1524)
				)
				(justify mirror)
			)
		)
		(duplicate_pad_numbers_are_jumpers no)
		(fp_poly
			(pts
				(arc
					(start 0 0.3556)
					(mid 0 -0.3556)
					(end 0 0.3556)
				)
			)
			(stroke
				(width 0)
				(type default)
			)
			(fill no)
			(layer "B.CrtYd")
		)
		(fp_poly
			(pts
				(arc
					(start 0 0.6096)
					(mid 0 -0.6096)
					(end 0 0.6096)
				)
			)
			(stroke
				(width 0)
				(type default)
			)
			(fill no)
			(layer "B.Fab")
		)
		(pad "1" smd circle
			(at 0 0 270)
			(size 0.7112 0.7112)
			(layers "B.Cu" "B.Mask" "B.Paste")
			(net "JTAG_BMC_TDO")
		)
	)
	(footprint ""
		(layer "B.Cu")
		(at 116.74094 -8.97636)
		(property "Reference" "R524"
			(at 0 0 0)
			(layer "B.SilkS")
			(hide yes)
			(effects
				(font
					(size 1.27 1.27)
				)
				(justify mirror)
			)
		)
		(property "Value" "0R2J-2-GP"
			(at -0.064008 -3.993896 0)
			(unlocked yes)
			(layer "B.Fab")
			(hide yes)
			(effects
				(font
					(size 1.016 1.016)
					(thickness 0.1524)
				)
				(justify mirror)
			)
		)
		(property "Device Type" "R402H16"
			(at -0.064008 -5.517896 0)
			(unlocked yes)
			(layer "B.Fab")
			(hide yes)
			(effects
				(font
					(size 1.016 1.016)
					(thickness 0.1524)
				)
				(justify mirror)
			)
		)
		(duplicate_pad_numbers_are_jumpers no)
		(fp_line
			(start -0.508 -0.9398)
			(end 0.508 -0.9398)
			(stroke
				(width 0.1524)
				(type default)
			)
			(layer "B.SilkS")
		)
		(fp_line
			(start 0.508 -0.9398)
			(end 0.508 0.9398)
			(stroke
				(width 0.1524)
				(type default)
			)
			(layer "B.SilkS")
		)
		(fp_rect
			(start 0.508 0.9398)
			(end -0.508 -0.9398)
			(stroke
				(width 0)
				(type default)
			)
			(fill no)
			(layer "B.CrtYd")
		)
		(fp_rect
			(start 0.508 0.9398)
			(end -0.508 -0.9398)
			(stroke
				(width 0)
				(type default)
			)
			(fill no)
			(layer "B.Fab")
		)
		(pad "1" smd custom
			(at 0 -0.4445 180)
			(size 0.1397 0.1397)
			(layers "B.Cu" "B.Mask" "B.Paste")
			(net "IOM_ADM1278_EN")
			(options
				(clearance outline)
				(anchor circle)
			)
			(primitives
				(gr_poly
					(pts
						(arc
							(start -0.1778 0.2794)
							(mid -0.249642 0.249642)
							(end -0.2794 0.1778)
						)
						(arc
							(start -0.2794 -0.1778)
							(mid -0.249642 -0.249642)
							(end -0.1778 -0.2794)
						)
						(arc
							(start 0.1778 -0.2794)
							(mid 0.249642 -0.249642)
							(end 0.2794 -0.1778)
						)
						(arc
							(start 0.2794 0.1778)
							(mid 0.249642 0.249642)
							(end 0.1778 0.2794)
						)
					)
					(width 0)
					(fill yes)
				)
			)
		)
		(pad "2" smd custom
			(at 0 0.4445 180)
			(size 0.1397 0.1397)
			(layers "B.Cu" "B.Mask" "B.Paste")
			(net "MB0_HS_ENABLE")
			(options
				(clearance outline)
				(anchor circle)
			)
			(primitives
				(gr_poly
					(pts
						(arc
							(start -0.1778 0.2794)
							(mid -0.249642 0.249642)
							(end -0.2794 0.1778)
						)
						(arc
							(start -0.2794 -0.1778)
							(mid -0.249642 -0.249642)
							(end -0.1778 -0.2794)
						)
						(arc
							(start 0.1778 -0.2794)
							(mid 0.249642 -0.249642)
							(end 0.2794 -0.1778)
						)
						(arc
							(start 0.2794 0.1778)
							(mid 0.249642 0.249642)
							(end 0.1778 0.2794)
						)
					)
					(width 0)
					(fill yes)
				)
			)
		)
	)
	(footprint ""
		(layer "B.Cu")
		(at 23.440644 -131.007358 180)
		(property "Reference" "R249"
			(at 0 0 0)
			(layer "B.SilkS")
			(hide yes)
			(effects
				(font
					(size 1.27 1.27)
				)
				(justify mirror)
			)
		)
		(property "Value" "120R2F-GP"
			(at -0.064008 -3.993896 180)
			(unlocked yes)
			(layer "B.Fab")
			(hide yes)
			(effects
				(font
					(size 1.016 1.016)
					(thickness 0.1524)
				)
				(justify mirror)
			)
		)
		(property "Device Type" "R402H16"
			(at -0.064008 -5.517896 180)
			(unlocked yes)
			(layer "B.Fab")
			(hide yes)
			(effects
				(font
					(size 1.016 1.016)
					(thickness 0.1524)
				)
				(justify mirror)
			)
		)
		(duplicate_pad_numbers_are_jumpers no)
		(fp_line
			(start 0.508 -0.9398)
			(end 0.508 0.9398)
			(stroke
				(width 0.1524)
				(type default)
			)
			(layer "B.SilkS")
		)
		(fp_line
			(start -0.508 -0.9398)
			(end 0.508 -0.9398)
			(stroke
				(width 0.1524)
				(type default)
			)
			(layer "B.SilkS")
		)
		(fp_rect
			(start 0.508 0.9398)
			(end -0.508 -0.9398)
			(stroke
				(width 0)
				(type default)
			)
			(fill no)
			(layer "B.CrtYd")
		)
		(fp_rect
			(start 0.508 0.9398)
			(end -0.508 -0.9398)
			(stroke
				(width 0)
				(type default)
			)
			(fill no)
			(layer "B.Fab")
		)
		(pad "1" smd custom
			(at 0 -0.4445)
			(size 0.1397 0.1397)
			(layers "B.Cu" "B.Mask" "B.Paste")
			(net "MEMA_7")
			(options
				(clearance outline)
				(anchor circle)
			)
			(primitives
				(gr_poly
					(pts
						(arc
							(start -0.1778 0.2794)
							(mid -0.249642 0.249642)
							(end -0.2794 0.1778)
						)
						(arc
							(start -0.2794 -0.1778)
							(mid -0.249642 -0.249642)
							(end -0.1778 -0.2794)
						)
						(arc
							(start 0.1778 -0.2794)
							(mid 0.249642 -0.249642)
							(end 0.2794 -0.1778)
						)
						(arc
							(start 0.2794 0.1778)
							(mid 0.249642 0.249642)
							(end 0.1778 0.2794)
						)
					)
					(width 0)
					(fill yes)
				)
			)
		)
		(pad "2" smd custom
			(at 0 0.4445)
			(size 0.1397 0.1397)
			(layers "B.Cu" "B.Mask" "B.Paste")
			(net "P1V2_STBY")
			(options
				(clearance outline)
				(anchor circle)
			)
			(primitives
				(gr_poly
					(pts
						(arc
							(start -0.1778 0.2794)
							(mid -0.249642 0.249642)
							(end -0.2794 0.1778)
						)
						(arc
							(start -0.2794 -0.1778)
							(mid -0.249642 -0.249642)
							(end -0.1778 -0.2794)
						)
						(arc
							(start 0.1778 -0.2794)
							(mid 0.249642 -0.249642)
							(end 0.2794 -0.1778)
						)
						(arc
							(start 0.2794 0.1778)
							(mid 0.249642 0.249642)
							(end 0.1778 0.2794)
						)
					)
					(width 0)
					(fill yes)
				)
			)
		)
	)
	(footprint ""
		(layer "B.Cu")
		(at 64.0842 -147.066 180)
		(property "Reference" "R201"
			(at 0 0 0)
			(layer "B.SilkS")
			(hide yes)
			(effects
				(font
					(size 1.27 1.27)
				)
				(justify mirror)
			)
		)
		(property "Value" "2K2R2F-GP"
			(at -0.064008 -3.993896 180)
			(unlocked yes)
			(layer "B.Fab")
			(hide yes)
			(effects
				(font
					(size 1.016 1.016)
					(thickness 0.1524)
				)
				(justify mirror)
			)
		)
		(property "Device Type" "R402H16"
			(at -0.064008 -5.517896 180)
			(unlocked yes)
			(layer "B.Fab")
			(hide yes)
			(effects
				(font
					(size 1.016 1.016)
					(thickness 0.1524)
				)
				(justify mirror)
			)
		)
		(duplicate_pad_numbers_are_jumpers no)
		(fp_line
			(start 0.508 -0.9398)
			(end 0.508 0.9398)
			(stroke
				(width 0.1524)
				(type default)
			)
			(layer "B.SilkS")
		)
		(fp_line
			(start -0.508 -0.9398)
			(end 0.508 -0.9398)
			(stroke
				(width 0.1524)
				(type default)
			)
			(layer "B.SilkS")
		)
		(fp_rect
			(start 0.508 0.9398)
			(end -0.508 -0.9398)
			(stroke
				(width 0)
				(type default)
			)
			(fill no)
			(layer "B.CrtYd")
		)
		(fp_rect
			(start 0.508 0.9398)
			(end -0.508 -0.9398)
			(stroke
				(width 0)
				(type default)
			)
			(fill no)
			(layer "B.Fab")
		)
		(pad "1" smd custom
			(at 0 -0.4445)
			(size 0.1397 0.1397)
			(layers "B.Cu" "B.Mask" "B.Paste")
			(net "I2C_MEZZ_FRU_SENSOR_SCL")
			(options
				(clearance outline)
				(anchor circle)
			)
			(primitives
				(gr_poly
					(pts
						(arc
							(start -0.1778 0.2794)
							(mid -0.249642 0.249642)
							(end -0.2794 0.1778)
						)
						(arc
							(start -0.2794 -0.1778)
							(mid -0.249642 -0.249642)
							(end -0.1778 -0.2794)
						)
						(arc
							(start 0.1778 -0.2794)
							(mid 0.249642 -0.249642)
							(end 0.2794 -0.1778)
						)
						(arc
							(start 0.2794 0.1778)
							(mid 0.249642 0.249642)
							(end 0.1778 0.2794)
						)
					)
					(width 0)
					(fill yes)
				)
			)
		)
		(pad "2" smd custom
			(at 0 0.4445)
			(size 0.1397 0.1397)
			(layers "B.Cu" "B.Mask" "B.Paste")
			(net "P3V3_STBY")
			(options
				(clearance outline)
				(anchor circle)
			)
			(primitives
				(gr_poly
					(pts
						(arc
							(start -0.1778 0.2794)
							(mid -0.249642 0.249642)
							(end -0.2794 0.1778)
						)
						(arc
							(start -0.2794 -0.1778)
							(mid -0.249642 -0.249642)
							(end -0.1778 -0.2794)
						)
						(arc
							(start 0.1778 -0.2794)
							(mid 0.249642 -0.249642)
							(end 0.2794 -0.1778)
						)
						(arc
							(start 0.2794 0.1778)
							(mid 0.249642 0.249642)
							(end 0.1778 0.2794)
						)
					)
					(width 0)
					(fill yes)
				)
			)
		)
	)
	(footprint ""
		(layer "B.Cu")
		(at 220.101414 -100.682044 180)
		(property "Reference" "C647"
			(at 0 0 0)
			(layer "B.SilkS")
			(hide yes)
			(effects
				(font
					(size 1.27 1.27)
				)
				(justify mirror)
			)
		)
		(property "Value" "SC4D7U25V5KX-1-GP"
			(at 0.0762 -6.1214 180)
			(unlocked yes)
			(layer "B.Fab")
			(hide yes)
			(effects
				(font
					(size 1.016 1.016)
					(thickness 0.1524)
				)
				(justify mirror)
			)
		)
		(property "Device Type" "C805H58"
			(at 0.0762 -8.1534 180)
			(unlocked yes)
			(layer "B.Fab")
			(hide yes)
			(effects
				(font
					(size 1.016 1.016)
					(thickness 0.1524)
				)
				(justify mirror)
			)
		)
		(duplicate_pad_numbers_are_jumpers no)
		(fp_line
			(start -0.635 0)
			(end 0.635 0)
			(stroke
				(width 0.508)
				(type default)
			)
			(layer "B.SilkS")
		)
		(fp_rect
			(start 0.9652 1.778)
			(end -0.9652 -1.778)
			(stroke
				(width 0)
				(type default)
			)
			(fill no)
			(layer "B.CrtYd")
		)
		(fp_poly
			(pts
				(xy 0.9652 -1.778) (xy -0.9652 -1.778) (xy -0.9652 1.778) (xy 0.9652 1.778)
			)
			(stroke
				(width 0)
				(type default)
			)
			(fill no)
			(layer "B.Fab")
		)
		(pad "1" smd rect
			(at 0 -0.9652)
			(size 1.397 1.143)
			(layers "B.Cu" "B.Mask" "B.Paste")
			(net "P12V_STBY_VDD_U81")
		)
		(pad "2" smd rect
			(at 0 0.9652)
			(size 1.397 1.143)
			(layers "B.Cu" "B.Mask" "B.Paste")
			(net "GND")
		)
	)
	(footprint ""
		(layer "B.Cu")
		(at 199.813418 -130.391408 180)
		(property "Reference" "C608"
			(at 0 0 0)
			(layer "B.SilkS")
			(hide yes)
			(effects
				(font
					(size 1.27 1.27)
				)
				(justify mirror)
			)
		)
		(property "Value" "SCD1U16V2KX-3GP"
			(at -1.1811 -2.7051 180)
			(unlocked yes)
			(layer "B.Fab")
			(hide yes)
			(effects
				(font
					(size 1.016 1.016)
					(thickness 0.1524)
				)
				(justify mirror)
			)
		)
		(property "Device Type" "C402H22"
			(at -1.1811 -4.2291 180)
			(unlocked yes)
			(layer "B.Fab")
			(hide yes)
			(effects
				(font
					(size 1.016 1.016)
					(thickness 0.1524)
				)
				(justify mirror)
			)
		)
		(duplicate_pad_numbers_are_jumpers no)
		(fp_rect
			(start 0.4318 0.9525)
			(end -0.4318 -0.9525)
			(stroke
				(width 0)
				(type default)
			)
			(fill no)
			(layer "B.CrtYd")
		)
		(fp_rect
			(start 0.4318 0.9525)
			(end -0.4318 -0.9525)
			(stroke
				(width 0)
				(type default)
			)
			(fill no)
			(layer "B.Fab")
		)
		(pad "1" smd custom
			(at 0 -0.4445)
			(size 0.1524 0.1524)
			(layers "B.Cu" "B.Mask" "B.Paste")
			(net "P3V3_M2")
			(options
				(clearance outline)
				(anchor circle)
			)
			(primitives
				(gr_poly
					(pts
						(arc
							(start 0.3048 0.2032)
							(mid 0.275042 0.275042)
							(end 0.2032 0.3048)
						)
						(arc
							(start -0.2032 0.3048)
							(mid -0.275042 0.275042)
							(end -0.3048 0.2032)
						)
						(arc
							(start -0.3048 -0.2032)
							(mid -0.275042 -0.275042)
							(end -0.2032 -0.3048)
						)
						(arc
							(start 0.2032 -0.3048)
							(mid 0.275042 -0.275042)
							(end 0.3048 -0.2032)
						)
					)
					(width 0)
					(fill yes)
				)
			)
		)
		(pad "2" smd custom
			(at 0 0.4445)
			(size 0.1524 0.1524)
			(layers "B.Cu" "B.Mask" "B.Paste")
			(net "GND")
			(options
				(clearance outline)
				(anchor circle)
			)
			(primitives
				(gr_poly
					(pts
						(arc
							(start 0.3048 0.2032)
							(mid 0.275042 0.275042)
							(end 0.2032 0.3048)
						)
						(arc
							(start -0.2032 0.3048)
							(mid -0.275042 0.275042)
							(end -0.3048 0.2032)
						)
						(arc
							(start -0.3048 -0.2032)
							(mid -0.275042 -0.275042)
							(end -0.2032 -0.3048)
						)
						(arc
							(start 0.2032 -0.3048)
							(mid 0.275042 -0.275042)
							(end 0.3048 -0.2032)
						)
					)
					(width 0)
					(fill yes)
				)
			)
		)
	)
	(footprint ""
		(layer "B.Cu")
		(at 124.9553 -8.580374 -90)
		(property "Reference" "R433"
			(at 0 0 90)
			(layer "B.SilkS")
			(hide yes)
			(effects
				(font
					(size 1.27 1.27)
				)
				(justify mirror)
			)
		)
		(property "Value" "39K2R2F-L-GP"
			(at -0.064008 -3.993896 270)
			(unlocked yes)
			(layer "B.Fab")
			(hide yes)
			(effects
				(font
					(size 1.016 1.016)
					(thickness 0.1524)
				)
				(justify mirror)
			)
		)
		(property "Device Type" "R402H16"
			(at -0.064008 -5.517896 270)
			(unlocked yes)
			(layer "B.Fab")
			(hide yes)
			(effects
				(font
					(size 1.016 1.016)
					(thickness 0.1524)
				)
				(justify mirror)
			)
		)
		(duplicate_pad_numbers_are_jumpers no)
		(fp_line
			(start -0.508 -0.9398)
			(end 0.508 -0.9398)
			(stroke
				(width 0.1524)
				(type default)
			)
			(layer "B.SilkS")
		)
		(fp_line
			(start 0.508 -0.9398)
			(end 0.508 0.9398)
			(stroke
				(width 0.1524)
				(type default)
			)
			(layer "B.SilkS")
		)
		(fp_rect
			(start 0.508 0.9398)
			(end -0.508 -0.9398)
			(stroke
				(width 0)
				(type default)
			)
			(fill no)
			(layer "B.CrtYd")
		)
		(fp_rect
			(start 0.508 0.9398)
			(end -0.508 -0.9398)
			(stroke
				(width 0)
				(type default)
			)
			(fill no)
			(layer "B.Fab")
		)
		(pad "1" smd custom
			(at 0 -0.4445 90)
			(size 0.1397 0.1397)
			(layers "B.Cu" "B.Mask" "B.Paste")
			(net "P12V_STBY")
			(options
				(clearance outline)
				(anchor circle)
			)
			(primitives
				(gr_poly
					(pts
						(arc
							(start -0.1778 0.2794)
							(mid -0.249642 0.249642)
							(end -0.2794 0.1778)
						)
						(arc
							(start -0.2794 -0.1778)
							(mid -0.249642 -0.249642)
							(end -0.1778 -0.2794)
						)
						(arc
							(start 0.1778 -0.2794)
							(mid 0.249642 -0.249642)
							(end 0.2794 -0.1778)
						)
						(arc
							(start 0.2794 0.1778)
							(mid 0.249642 0.249642)
							(end 0.1778 0.2794)
						)
					)
					(width 0)
					(fill yes)
				)
			)
		)
		(pad "2" smd custom
			(at 0 0.4445 90)
			(size 0.1397 0.1397)
			(layers "B.Cu" "B.Mask" "B.Paste")
			(net "P12V_IOM_PGOOD")
			(options
				(clearance outline)
				(anchor circle)
			)
			(primitives
				(gr_poly
					(pts
						(arc
							(start -0.1778 0.2794)
							(mid -0.249642 0.249642)
							(end -0.2794 0.1778)
						)
						(arc
							(start -0.2794 -0.1778)
							(mid -0.249642 -0.249642)
							(end -0.1778 -0.2794)
						)
						(arc
							(start 0.1778 -0.2794)
							(mid 0.249642 -0.249642)
							(end 0.2794 -0.1778)
						)
						(arc
							(start 0.2794 0.1778)
							(mid 0.249642 0.249642)
							(end 0.1778 0.2794)
						)
					)
					(width 0)
					(fill yes)
				)
			)
		)
	)
	(footprint ""
		(layer "B.Cu")
		(at 51.562 -132.08)
		(property "Reference" "C113"
			(at 0 0 0)
			(layer "B.SilkS")
			(hide yes)
			(effects
				(font
					(size 1.27 1.27)
				)
				(justify mirror)
			)
		)
		(property "Value" "SC1U16V3KX-5GP"
			(at 0 -2.8194 0)
			(unlocked yes)
			(layer "B.Fab")
			(hide yes)
			(effects
				(font
					(size 1.016 1.016)
					(thickness 0.1524)
				)
				(justify mirror)
			)
		)
		(property "Device Type" "C603H36"
			(at 0 -4.3434 0)
			(unlocked yes)
			(layer "B.Fab")
			(hide yes)
			(effects
				(font
					(size 1.016 1.016)
					(thickness 0.1524)
				)
				(justify mirror)
			)
		)
		(duplicate_pad_numbers_are_jumpers no)
		(fp_line
			(start -0.508 0)
			(end 0.508 0)
			(stroke
				(width 0.2032)
				(type default)
			)
			(layer "B.SilkS")
		)
		(fp_rect
			(start 0.5842 1.3335)
			(end -0.5842 -1.3335)
			(stroke
				(width 0)
				(type default)
			)
			(fill no)
			(layer "B.CrtYd")
		)
		(fp_rect
			(start 0.5842 1.3335)
			(end -0.5842 -1.3335)
			(stroke
				(width 0)
				(type default)
			)
			(fill no)
			(layer "B.Fab")
		)
		(pad "1" smd custom
			(at 0 -0.762 180)
			(size 0.2159 0.2159)
			(layers "B.Cu" "B.Mask" "B.Paste")
			(net "P1V15_STBY")
			(options
				(clearance outline)
				(anchor circle)
			)
			(primitives
				(gr_poly
					(pts
						(arc
							(start -0.3302 0.4318)
							(mid -0.402042 0.402042)
							(end -0.4318 0.3302)
						)
						(arc
							(start -0.4318 -0.3302)
							(mid -0.402042 -0.402042)
							(end -0.3302 -0.4318)
						)
						(arc
							(start 0.3302 -0.4318)
							(mid 0.402042 -0.402042)
							(end 0.4318 -0.3302)
						)
						(arc
							(start 0.4318 0.3302)
							(mid 0.402042 0.402042)
							(end 0.3302 0.4318)
						)
					)
					(width 0)
					(fill yes)
				)
			)
		)
		(pad "2" smd custom
			(at 0 0.762 180)
			(size 0.2159 0.2159)
			(layers "B.Cu" "B.Mask" "B.Paste")
			(net "GND")
			(options
				(clearance outline)
				(anchor circle)
			)
			(primitives
				(gr_poly
					(pts
						(arc
							(start -0.3302 0.4318)
							(mid -0.402042 0.402042)
							(end -0.4318 0.3302)
						)
						(arc
							(start -0.4318 -0.3302)
							(mid -0.402042 -0.402042)
							(end -0.3302 -0.4318)
						)
						(arc
							(start 0.3302 -0.4318)
							(mid 0.402042 -0.402042)
							(end 0.4318 -0.3302)
						)
						(arc
							(start 0.4318 0.3302)
							(mid 0.402042 0.402042)
							(end 0.3302 0.4318)
						)
					)
					(width 0)
					(fill yes)
				)
			)
		)
	)
	(footprint ""
		(layer "B.Cu")
		(at 10.200132 -138.145774 90)
		(property "Reference" "R246"
			(at 0 0 90)
			(layer "B.SilkS")
			(hide yes)
			(effects
				(font
					(size 1.27 1.27)
				)
				(justify mirror)
			)
		)
		(property "Value" "120R2F-GP"
			(at -0.064008 -3.993896 90)
			(unlocked yes)
			(layer "B.Fab")
			(hide yes)
			(effects
				(font
					(size 1.016 1.016)
					(thickness 0.1524)
				)
				(justify mirror)
			)
		)
		(property "Device Type" "R402H16"
			(at -0.064008 -5.517896 90)
			(unlocked yes)
			(layer "B.Fab")
			(hide yes)
			(effects
				(font
					(size 1.016 1.016)
					(thickness 0.1524)
				)
				(justify mirror)
			)
		)
		(duplicate_pad_numbers_are_jumpers no)
		(fp_line
			(start 0.508 -0.9398)
			(end 0.508 0.9398)
			(stroke
				(width 0.1524)
				(type default)
			)
			(layer "B.SilkS")
		)
		(fp_line
			(start -0.508 -0.9398)
			(end 0.508 -0.9398)
			(stroke
				(width 0.1524)
				(type default)
			)
			(layer "B.SilkS")
		)
		(fp_rect
			(start 0.508 0.9398)
			(end -0.508 -0.9398)
			(stroke
				(width 0)
				(type default)
			)
			(fill no)
			(layer "B.CrtYd")
		)
		(fp_rect
			(start 0.508 0.9398)
			(end -0.508 -0.9398)
			(stroke
				(width 0)
				(type default)
			)
			(fill no)
			(layer "B.Fab")
		)
		(pad "1" smd custom
			(at 0 -0.4445 270)
			(size 0.1397 0.1397)
			(layers "B.Cu" "B.Mask" "B.Paste")
			(net "GND")
			(options
				(clearance outline)
				(anchor circle)
			)
			(primitives
				(gr_poly
					(pts
						(arc
							(start -0.1778 0.2794)
							(mid -0.249642 0.249642)
							(end -0.2794 0.1778)
						)
						(arc
							(start -0.2794 -0.1778)
							(mid -0.249642 -0.249642)
							(end -0.1778 -0.2794)
						)
						(arc
							(start 0.1778 -0.2794)
							(mid 0.249642 -0.249642)
							(end 0.2794 -0.1778)
						)
						(arc
							(start 0.2794 0.1778)
							(mid 0.249642 0.249642)
							(end 0.1778 0.2794)
						)
					)
					(width 0)
					(fill yes)
				)
			)
		)
		(pad "2" smd custom
			(at 0 0.4445 270)
			(size 0.1397 0.1397)
			(layers "B.Cu" "B.Mask" "B.Paste")
			(net "MEMA_6")
			(options
				(clearance outline)
				(anchor circle)
			)
			(primitives
				(gr_poly
					(pts
						(arc
							(start -0.1778 0.2794)
							(mid -0.249642 0.249642)
							(end -0.2794 0.1778)
						)
						(arc
							(start -0.2794 -0.1778)
							(mid -0.249642 -0.249642)
							(end -0.1778 -0.2794)
						)
						(arc
							(start 0.1778 -0.2794)
							(mid 0.249642 -0.249642)
							(end 0.2794 -0.1778)
						)
						(arc
							(start 0.2794 0.1778)
							(mid 0.249642 0.249642)
							(end 0.1778 0.2794)
						)
					)
					(width 0)
					(fill yes)
				)
			)
		)
	)
	(footprint ""
		(layer "B.Cu")
		(at 56.3372 -154.94)
		(property "Reference" "R304"
			(at 0 0 0)
			(layer "B.SilkS")
			(hide yes)
			(effects
				(font
					(size 1.27 1.27)
				)
				(justify mirror)
			)
		)
		(property "Value" "47KR2F-GP"
			(at -0.064008 -3.993896 0)
			(unlocked yes)
			(layer "B.Fab")
			(hide yes)
			(effects
				(font
					(size 1.016 1.016)
					(thickness 0.1524)
				)
				(justify mirror)
			)
		)
		(property "Device Type" "R402H16"
			(at -0.064008 -5.517896 0)
			(unlocked yes)
			(layer "B.Fab")
			(hide yes)
			(effects
				(font
					(size 1.016 1.016)
					(thickness 0.1524)
				)
				(justify mirror)
			)
		)
		(duplicate_pad_numbers_are_jumpers no)
		(fp_line
			(start -0.508 -0.9398)
			(end 0.508 -0.9398)
			(stroke
				(width 0.1524)
				(type default)
			)
			(layer "B.SilkS")
		)
		(fp_line
			(start 0.508 -0.9398)
			(end 0.508 0.9398)
			(stroke
				(width 0.1524)
				(type default)
			)
			(layer "B.SilkS")
		)
		(fp_rect
			(start 0.508 0.9398)
			(end -0.508 -0.9398)
			(stroke
				(width 0)
				(type default)
			)
			(fill no)
			(layer "B.CrtYd")
		)
		(fp_rect
			(start 0.508 0.9398)
			(end -0.508 -0.9398)
			(stroke
				(width 0)
				(type default)
			)
			(fill no)
			(layer "B.Fab")
		)
		(pad "1" smd custom
			(at 0 -0.4445 180)
			(size 0.1397 0.1397)
			(layers "B.Cu" "B.Mask" "B.Paste")
			(net "GND")
			(options
				(clearance outline)
				(anchor circle)
			)
			(primitives
				(gr_poly
					(pts
						(arc
							(start -0.1778 0.2794)
							(mid -0.249642 0.249642)
							(end -0.2794 0.1778)
						)
						(arc
							(start -0.2794 -0.1778)
							(mid -0.249642 -0.249642)
							(end -0.1778 -0.2794)
						)
						(arc
							(start 0.1778 -0.2794)
							(mid 0.249642 -0.249642)
							(end 0.2794 -0.1778)
						)
						(arc
							(start 0.2794 0.1778)
							(mid 0.249642 0.249642)
							(end 0.1778 0.2794)
						)
					)
					(width 0)
					(fill yes)
				)
			)
		)
		(pad "2" smd custom
			(at 0 0.4445 180)
			(size 0.1397 0.1397)
			(layers "B.Cu" "B.Mask" "B.Paste")
			(net "BMC_RGMII_A4_D3")
			(options
				(clearance outline)
				(anchor circle)
			)
			(primitives
				(gr_poly
					(pts
						(arc
							(start -0.1778 0.2794)
							(mid -0.249642 0.249642)
							(end -0.2794 0.1778)
						)
						(arc
							(start -0.2794 -0.1778)
							(mid -0.249642 -0.249642)
							(end -0.1778 -0.2794)
						)
						(arc
							(start 0.1778 -0.2794)
							(mid 0.249642 -0.249642)
							(end 0.2794 -0.1778)
						)
						(arc
							(start 0.2794 0.1778)
							(mid 0.249642 0.249642)
							(end 0.1778 0.2794)
						)
					)
					(width 0)
					(fill yes)
				)
			)
		)
	)
	(footprint ""
		(layer "B.Cu")
		(at 17.749012 -129.051558 180)
		(property "Reference" "R240"
			(at 0 0 0)
			(layer "B.SilkS")
			(hide yes)
			(effects
				(font
					(size 1.27 1.27)
				)
				(justify mirror)
			)
		)
		(property "Value" "120R2F-GP"
			(at -0.064008 -3.993896 180)
			(unlocked yes)
			(layer "B.Fab")
			(hide yes)
			(effects
				(font
					(size 1.016 1.016)
					(thickness 0.1524)
				)
				(justify mirror)
			)
		)
		(property "Device Type" "R402H16"
			(at -0.064008 -5.517896 180)
			(unlocked yes)
			(layer "B.Fab")
			(hide yes)
			(effects
				(font
					(size 1.016 1.016)
					(thickness 0.1524)
				)
				(justify mirror)
			)
		)
		(duplicate_pad_numbers_are_jumpers no)
		(fp_line
			(start 0.508 -0.9398)
			(end 0.508 0.9398)
			(stroke
				(width 0.1524)
				(type default)
			)
			(layer "B.SilkS")
		)
		(fp_line
			(start -0.508 -0.9398)
			(end 0.508 -0.9398)
			(stroke
				(width 0.1524)
				(type default)
			)
			(layer "B.SilkS")
		)
		(fp_rect
			(start 0.508 0.9398)
			(end -0.508 -0.9398)
			(stroke
				(width 0)
				(type default)
			)
			(fill no)
			(layer "B.CrtYd")
		)
		(fp_rect
			(start 0.508 0.9398)
			(end -0.508 -0.9398)
			(stroke
				(width 0)
				(type default)
			)
			(fill no)
			(layer "B.Fab")
		)
		(pad "1" smd custom
			(at 0 -0.4445)
			(size 0.1397 0.1397)
			(layers "B.Cu" "B.Mask" "B.Paste")
			(net "GND")
			(options
				(clearance outline)
				(anchor circle)
			)
			(primitives
				(gr_poly
					(pts
						(arc
							(start -0.1778 0.2794)
							(mid -0.249642 0.249642)
							(end -0.2794 0.1778)
						)
						(arc
							(start -0.2794 -0.1778)
							(mid -0.249642 -0.249642)
							(end -0.1778 -0.2794)
						)
						(arc
							(start 0.1778 -0.2794)
							(mid 0.249642 -0.249642)
							(end 0.2794 -0.1778)
						)
						(arc
							(start 0.2794 0.1778)
							(mid 0.249642 0.249642)
							(end 0.1778 0.2794)
						)
					)
					(width 0)
					(fill yes)
				)
			)
		)
		(pad "2" smd custom
			(at 0 0.4445)
			(size 0.1397 0.1397)
			(layers "B.Cu" "B.Mask" "B.Paste")
			(net "MEMA_3")
			(options
				(clearance outline)
				(anchor circle)
			)
			(primitives
				(gr_poly
					(pts
						(arc
							(start -0.1778 0.2794)
							(mid -0.249642 0.249642)
							(end -0.2794 0.1778)
						)
						(arc
							(start -0.2794 -0.1778)
							(mid -0.249642 -0.249642)
							(end -0.1778 -0.2794)
						)
						(arc
							(start 0.1778 -0.2794)
							(mid 0.249642 -0.249642)
							(end 0.2794 -0.1778)
						)
						(arc
							(start 0.2794 0.1778)
							(mid 0.249642 0.249642)
							(end 0.1778 0.2794)
						)
					)
					(width 0)
					(fill yes)
				)
			)
		)
	)
	(footprint ""
		(layer "B.Cu")
		(at 32.5374 -160.2232 90)
		(property "Reference" "R705"
			(at 0 0 90)
			(layer "B.SilkS")
			(hide yes)
			(effects
				(font
					(size 1.27 1.27)
				)
				(justify mirror)
			)
		)
		(property "Value" "4K7R2F-GP"
			(at -0.064008 -3.993896 90)
			(unlocked yes)
			(layer "B.Fab")
			(hide yes)
			(effects
				(font
					(size 1.016 1.016)
					(thickness 0.1524)
				)
				(justify mirror)
			)
		)
		(property "Device Type" "R402H16"
			(at -0.064008 -5.517896 90)
			(unlocked yes)
			(layer "B.Fab")
			(hide yes)
			(effects
				(font
					(size 1.016 1.016)
					(thickness 0.1524)
				)
				(justify mirror)
			)
		)
		(duplicate_pad_numbers_are_jumpers no)
		(fp_line
			(start 0.508 -0.9398)
			(end 0.508 0.9398)
			(stroke
				(width 0.1524)
				(type default)
			)
			(layer "B.SilkS")
		)
		(fp_line
			(start -0.508 -0.9398)
			(end 0.508 -0.9398)
			(stroke
				(width 0.1524)
				(type default)
			)
			(layer "B.SilkS")
		)
		(fp_rect
			(start 0.508 0.9398)
			(end -0.508 -0.9398)
			(stroke
				(width 0)
				(type default)
			)
			(fill no)
			(layer "B.CrtYd")
		)
		(fp_rect
			(start 0.508 0.9398)
			(end -0.508 -0.9398)
			(stroke
				(width 0)
				(type default)
			)
			(fill no)
			(layer "B.Fab")
		)
		(pad "1" smd custom
			(at 0 -0.4445 270)
			(size 0.1397 0.1397)
			(layers "B.Cu" "B.Mask" "B.Paste")
			(net "P3V3_STBY")
			(options
				(clearance outline)
				(anchor circle)
			)
			(primitives
				(gr_poly
					(pts
						(arc
							(start -0.1778 0.2794)
							(mid -0.249642 0.249642)
							(end -0.2794 0.1778)
						)
						(arc
							(start -0.2794 -0.1778)
							(mid -0.249642 -0.249642)
							(end -0.1778 -0.2794)
						)
						(arc
							(start 0.1778 -0.2794)
							(mid 0.249642 -0.249642)
							(end 0.2794 -0.1778)
						)
						(arc
							(start 0.2794 0.1778)
							(mid 0.249642 0.249642)
							(end 0.1778 0.2794)
						)
					)
					(width 0)
					(fill yes)
				)
			)
		)
		(pad "2" smd custom
			(at 0 0.4445 270)
			(size 0.1397 0.1397)
			(layers "B.Cu" "B.Mask" "B.Paste")
			(net "IOM_TYPE2")
			(options
				(clearance outline)
				(anchor circle)
			)
			(primitives
				(gr_poly
					(pts
						(arc
							(start -0.1778 0.2794)
							(mid -0.249642 0.249642)
							(end -0.2794 0.1778)
						)
						(arc
							(start -0.2794 -0.1778)
							(mid -0.249642 -0.249642)
							(end -0.1778 -0.2794)
						)
						(arc
							(start 0.1778 -0.2794)
							(mid 0.249642 -0.249642)
							(end 0.2794 -0.1778)
						)
						(arc
							(start 0.2794 0.1778)
							(mid 0.249642 0.249642)
							(end 0.1778 0.2794)
						)
					)
					(width 0)
					(fill yes)
				)
			)
		)
	)
	(footprint ""
		(layer "B.Cu")
		(at 39.345362 -154.548332)
		(property "Reference" "TP64"
			(at 0 0 0)
			(layer "B.SilkS")
			(hide yes)
			(effects
				(font
					(size 1.27 1.27)
				)
				(justify mirror)
			)
		)
		(property "Value" "TPAD28-2-GP"
			(at 0.0127 -1.6637 0)
			(unlocked yes)
			(layer "B.Fab")
			(hide yes)
			(effects
				(font
					(size 1.016 1.016)
					(thickness 0.1524)
				)
				(justify mirror)
			)
		)
		(property "Device Type" "TPAD28"
			(at 0.0127 -3.1877 0)
			(unlocked yes)
			(layer "B.Fab")
			(hide yes)
			(effects
				(font
					(size 1.016 1.016)
					(thickness 0.1524)
				)
				(justify mirror)
			)
		)
		(duplicate_pad_numbers_are_jumpers no)
		(fp_poly
			(pts
				(arc
					(start 0.3556 0)
					(mid -0.3556 0)
					(end 0.3556 0)
				)
			)
			(stroke
				(width 0)
				(type default)
			)
			(fill no)
			(layer "B.CrtYd")
		)
		(fp_poly
			(pts
				(arc
					(start 0.6096 0)
					(mid -0.6096 0)
					(end 0.6096 0)
				)
			)
			(stroke
				(width 0)
				(type default)
			)
			(fill no)
			(layer "B.Fab")
		)
		(pad "1" smd circle
			(at 0 0 180)
			(size 0.7112 0.7112)
			(layers "B.Cu" "B.Mask" "B.Paste")
			(net "TP_BMC_GPION4")
		)
	)
	(footprint ""
		(layer "B.Cu")
		(at 45.593 -153.1112)
		(property "Reference" "TP191"
			(at 0 0 0)
			(layer "B.SilkS")
			(hide yes)
			(effects
				(font
					(size 1.27 1.27)
				)
				(justify mirror)
			)
		)
		(property "Value" "TPAD28-2-GP"
			(at 0.0127 -1.6637 0)
			(unlocked yes)
			(layer "B.Fab")
			(hide yes)
			(effects
				(font
					(size 1.016 1.016)
					(thickness 0.1524)
				)
				(justify mirror)
			)
		)
		(property "Device Type" "TPAD28"
			(at 0.0127 -3.1877 0)
			(unlocked yes)
			(layer "B.Fab")
			(hide yes)
			(effects
				(font
					(size 1.016 1.016)
					(thickness 0.1524)
				)
				(justify mirror)
			)
		)
		(duplicate_pad_numbers_are_jumpers no)
		(fp_poly
			(pts
				(arc
					(start 0.3556 0)
					(mid -0.3556 0)
					(end 0.3556 0)
				)
			)
			(stroke
				(width 0)
				(type default)
			)
			(fill no)
			(layer "B.CrtYd")
		)
		(fp_poly
			(pts
				(arc
					(start 0.6096 0)
					(mid -0.6096 0)
					(end 0.6096 0)
				)
			)
			(stroke
				(width 0)
				(type default)
			)
			(fill no)
			(layer "B.Fab")
		)
		(pad "1" smd circle
			(at 0 0 180)
			(size 0.7112 0.7112)
			(layers "B.Cu" "B.Mask" "B.Paste")
			(net "TP_BMC_GPIOL5")
		)
	)
	(footprint ""
		(layer "B.Cu")
		(at 25.3238 -180.8988 -90)
		(property "Reference" "R483"
			(at 0 0 90)
			(layer "B.SilkS")
			(hide yes)
			(effects
				(font
					(size 1.27 1.27)
				)
				(justify mirror)
			)
		)
		(property "Value" "2D2R3J-2-GP"
			(at 0.0254 -2.5146 270)
			(unlocked yes)
			(layer "B.Fab")
			(hide yes)
			(effects
				(font
					(size 1.016 1.016)
					(thickness 0.1524)
				)
				(justify mirror)
			)
		)
		(property "Device Type" "R603H22"
			(at 0.0254 -4.0386 270)
			(unlocked yes)
			(layer "B.Fab")
			(hide yes)
			(effects
				(font
					(size 1.016 1.016)
					(thickness 0.1524)
				)
				(justify mirror)
			)
		)
		(duplicate_pad_numbers_are_jumpers no)
		(fp_line
			(start -0.2032 0)
			(end -0.4826 0)
			(stroke
				(width 0.2032)
				(type default)
			)
			(layer "B.SilkS")
		)
		(fp_line
			(start 0.4826 0)
			(end 0.2032 0)
			(stroke
				(width 0.2032)
				(type default)
			)
			(layer "B.SilkS")
		)
		(fp_rect
			(start 0.5842 1.3335)
			(end -0.5842 -1.3335)
			(stroke
				(width 0)
				(type default)
			)
			(fill no)
			(layer "B.CrtYd")
		)
		(fp_rect
			(start 0.5842 1.3335)
			(end -0.5842 -1.3335)
			(stroke
				(width 0)
				(type default)
			)
			(fill no)
			(layer "B.Fab")
		)
		(pad "1" smd custom
			(at 0 -0.762 90)
			(size 0.2159 0.2159)
			(layers "B.Cu" "B.Mask" "B.Paste")
			(net "P12V_STBY_VDD_PU2")
			(options
				(clearance outline)
				(anchor circle)
			)
			(primitives
				(gr_poly
					(pts
						(arc
							(start -0.3302 0.4318)
							(mid -0.402042 0.402042)
							(end -0.4318 0.3302)
						)
						(arc
							(start -0.4318 -0.3302)
							(mid -0.402042 -0.402042)
							(end -0.3302 -0.4318)
						)
						(arc
							(start 0.3302 -0.4318)
							(mid 0.402042 -0.402042)
							(end 0.4318 -0.3302)
						)
						(arc
							(start 0.4318 0.3302)
							(mid 0.402042 0.402042)
							(end 0.3302 0.4318)
						)
					)
					(width 0)
					(fill yes)
				)
			)
		)
		(pad "2" smd custom
			(at 0 0.762 90)
			(size 0.2159 0.2159)
			(layers "B.Cu" "B.Mask" "B.Paste")
			(net "P12V_STBY")
			(options
				(clearance outline)
				(anchor circle)
			)
			(primitives
				(gr_poly
					(pts
						(arc
							(start -0.3302 0.4318)
							(mid -0.402042 0.402042)
							(end -0.4318 0.3302)
						)
						(arc
							(start -0.4318 -0.3302)
							(mid -0.402042 -0.402042)
							(end -0.3302 -0.4318)
						)
						(arc
							(start 0.3302 -0.4318)
							(mid 0.402042 -0.402042)
							(end 0.4318 -0.3302)
						)
						(arc
							(start 0.4318 0.3302)
							(mid 0.402042 0.402042)
							(end 0.3302 0.4318)
						)
					)
					(width 0)
					(fill yes)
				)
			)
		)
	)
	(footprint ""
		(layer "B.Cu")
		(at 50.91557 -158.956756 -90)
		(property "Reference" "R400"
			(at 0 0 90)
			(layer "B.SilkS")
			(hide yes)
			(effects
				(font
					(size 1.27 1.27)
				)
				(justify mirror)
			)
		)
		(property "Value" "4K7R2F-GP"
			(at -0.064008 -3.993896 270)
			(unlocked yes)
			(layer "B.Fab")
			(hide yes)
			(effects
				(font
					(size 1.016 1.016)
					(thickness 0.1524)
				)
				(justify mirror)
			)
		)
		(property "Device Type" "R402H16"
			(at -0.064008 -5.517896 270)
			(unlocked yes)
			(layer "B.Fab")
			(hide yes)
			(effects
				(font
					(size 1.016 1.016)
					(thickness 0.1524)
				)
				(justify mirror)
			)
		)
		(duplicate_pad_numbers_are_jumpers no)
		(fp_line
			(start -0.508 -0.9398)
			(end 0.508 -0.9398)
			(stroke
				(width 0.1524)
				(type default)
			)
			(layer "B.SilkS")
		)
		(fp_line
			(start 0.508 -0.9398)
			(end 0.508 0.9398)
			(stroke
				(width 0.1524)
				(type default)
			)
			(layer "B.SilkS")
		)
		(fp_rect
			(start 0.508 0.9398)
			(end -0.508 -0.9398)
			(stroke
				(width 0)
				(type default)
			)
			(fill no)
			(layer "B.CrtYd")
		)
		(fp_rect
			(start 0.508 0.9398)
			(end -0.508 -0.9398)
			(stroke
				(width 0)
				(type default)
			)
			(fill no)
			(layer "B.Fab")
		)
		(pad "1" smd custom
			(at 0 -0.4445 90)
			(size 0.1397 0.1397)
			(layers "B.Cu" "B.Mask" "B.Paste")
			(net "GND")
			(options
				(clearance outline)
				(anchor circle)
			)
			(primitives
				(gr_poly
					(pts
						(arc
							(start -0.1778 0.2794)
							(mid -0.249642 0.249642)
							(end -0.2794 0.1778)
						)
						(arc
							(start -0.2794 -0.1778)
							(mid -0.249642 -0.249642)
							(end -0.1778 -0.2794)
						)
						(arc
							(start 0.1778 -0.2794)
							(mid 0.249642 -0.249642)
							(end 0.2794 -0.1778)
						)
						(arc
							(start 0.2794 0.1778)
							(mid 0.249642 0.249642)
							(end 0.1778 0.2794)
						)
					)
					(width 0)
					(fill yes)
				)
			)
		)
		(pad "2" smd custom
			(at 0 0.4445 90)
			(size 0.1397 0.1397)
			(layers "B.Cu" "B.Mask" "B.Paste")
			(net "UART_BMC_TX")
			(options
				(clearance outline)
				(anchor circle)
			)
			(primitives
				(gr_poly
					(pts
						(arc
							(start -0.1778 0.2794)
							(mid -0.249642 0.249642)
							(end -0.2794 0.1778)
						)
						(arc
							(start -0.2794 -0.1778)
							(mid -0.249642 -0.249642)
							(end -0.1778 -0.2794)
						)
						(arc
							(start 0.1778 -0.2794)
							(mid 0.249642 -0.249642)
							(end 0.2794 -0.1778)
						)
						(arc
							(start 0.2794 0.1778)
							(mid 0.249642 0.249642)
							(end 0.1778 0.2794)
						)
					)
					(width 0)
					(fill yes)
				)
			)
		)
	)
	(footprint ""
		(layer "B.Cu")
		(at 43.9928 -134.7978 90)
		(property "Reference" "R372"
			(at 0 0 90)
			(layer "B.SilkS")
			(hide yes)
			(effects
				(font
					(size 1.27 1.27)
				)
				(justify mirror)
			)
		)
		(property "Value" "4K7R2F-GP"
			(at -0.064008 -3.993896 90)
			(unlocked yes)
			(layer "B.Fab")
			(hide yes)
			(effects
				(font
					(size 1.016 1.016)
					(thickness 0.1524)
				)
				(justify mirror)
			)
		)
		(property "Device Type" "R402H16"
			(at -0.064008 -5.517896 90)
			(unlocked yes)
			(layer "B.Fab")
			(hide yes)
			(effects
				(font
					(size 1.016 1.016)
					(thickness 0.1524)
				)
				(justify mirror)
			)
		)
		(duplicate_pad_numbers_are_jumpers no)
		(fp_line
			(start 0.508 -0.9398)
			(end 0.508 0.9398)
			(stroke
				(width 0.1524)
				(type default)
			)
			(layer "B.SilkS")
		)
		(fp_line
			(start -0.508 -0.9398)
			(end 0.508 -0.9398)
			(stroke
				(width 0.1524)
				(type default)
			)
			(layer "B.SilkS")
		)
		(fp_rect
			(start 0.508 0.9398)
			(end -0.508 -0.9398)
			(stroke
				(width 0)
				(type default)
			)
			(fill no)
			(layer "B.CrtYd")
		)
		(fp_rect
			(start 0.508 0.9398)
			(end -0.508 -0.9398)
			(stroke
				(width 0)
				(type default)
			)
			(fill no)
			(layer "B.Fab")
		)
		(pad "1" smd custom
			(at 0 -0.4445 270)
			(size 0.1397 0.1397)
			(layers "B.Cu" "B.Mask" "B.Paste")
			(net "P3V3_STBY")
			(options
				(clearance outline)
				(anchor circle)
			)
			(primitives
				(gr_poly
					(pts
						(arc
							(start -0.1778 0.2794)
							(mid -0.249642 0.249642)
							(end -0.2794 0.1778)
						)
						(arc
							(start -0.2794 -0.1778)
							(mid -0.249642 -0.249642)
							(end -0.1778 -0.2794)
						)
						(arc
							(start 0.1778 -0.2794)
							(mid 0.249642 -0.249642)
							(end 0.2794 -0.1778)
						)
						(arc
							(start 0.2794 0.1778)
							(mid 0.249642 0.249642)
							(end 0.1778 0.2794)
						)
					)
					(width 0)
					(fill yes)
				)
			)
		)
		(pad "2" smd custom
			(at 0 0.4445 270)
			(size 0.1397 0.1397)
			(layers "B.Cu" "B.Mask" "B.Paste")
			(net "BMC_GPIOS4")
			(options
				(clearance outline)
				(anchor circle)
			)
			(primitives
				(gr_poly
					(pts
						(arc
							(start -0.1778 0.2794)
							(mid -0.249642 0.249642)
							(end -0.2794 0.1778)
						)
						(arc
							(start -0.2794 -0.1778)
							(mid -0.249642 -0.249642)
							(end -0.1778 -0.2794)
						)
						(arc
							(start 0.1778 -0.2794)
							(mid 0.249642 -0.249642)
							(end 0.2794 -0.1778)
						)
						(arc
							(start 0.2794 0.1778)
							(mid 0.249642 0.249642)
							(end 0.1778 0.2794)
						)
					)
					(width 0)
					(fill yes)
				)
			)
		)
	)
	(footprint ""
		(layer "B.Cu")
		(at 197.926706 -133.61924 180)
		(property "Reference" "C625"
			(at 0 0 0)
			(layer "B.SilkS")
			(hide yes)
			(effects
				(font
					(size 1.27 1.27)
				)
				(justify mirror)
			)
		)
		(property "Value" "SC10U6D3V5KX-4GP"
			(at 0.0762 -6.1214 180)
			(unlocked yes)
			(layer "B.Fab")
			(hide yes)
			(effects
				(font
					(size 1.016 1.016)
					(thickness 0.1524)
				)
				(justify mirror)
			)
		)
		(property "Device Type" "C805H58"
			(at 0.0762 -8.1534 180)
			(unlocked yes)
			(layer "B.Fab")
			(hide yes)
			(effects
				(font
					(size 1.016 1.016)
					(thickness 0.1524)
				)
				(justify mirror)
			)
		)
		(duplicate_pad_numbers_are_jumpers no)
		(fp_line
			(start -0.635 0)
			(end 0.635 0)
			(stroke
				(width 0.508)
				(type default)
			)
			(layer "B.SilkS")
		)
		(fp_rect
			(start 0.9652 1.778)
			(end -0.9652 -1.778)
			(stroke
				(width 0)
				(type default)
			)
			(fill no)
			(layer "B.CrtYd")
		)
		(fp_poly
			(pts
				(xy 0.9652 -1.778) (xy -0.9652 -1.778) (xy -0.9652 1.778) (xy 0.9652 1.778)
			)
			(stroke
				(width 0)
				(type default)
			)
			(fill no)
			(layer "B.Fab")
		)
		(pad "1" smd rect
			(at 0 -0.9652)
			(size 1.397 1.143)
			(layers "B.Cu" "B.Mask" "B.Paste")
			(net "P3V3_M2")
		)
		(pad "2" smd rect
			(at 0 0.9652)
			(size 1.397 1.143)
			(layers "B.Cu" "B.Mask" "B.Paste")
			(net "GND")
		)
	)
	(footprint ""
		(layer "B.Cu")
		(at 10.174732 -136.716516 90)
		(property "Reference" "R250"
			(at 0 0 90)
			(layer "B.SilkS")
			(hide yes)
			(effects
				(font
					(size 1.27 1.27)
				)
				(justify mirror)
			)
		)
		(property "Value" "120R2F-GP"
			(at -0.064008 -3.993896 90)
			(unlocked yes)
			(layer "B.Fab")
			(hide yes)
			(effects
				(font
					(size 1.016 1.016)
					(thickness 0.1524)
				)
				(justify mirror)
			)
		)
		(property "Device Type" "R402H16"
			(at -0.064008 -5.517896 90)
			(unlocked yes)
			(layer "B.Fab")
			(hide yes)
			(effects
				(font
					(size 1.016 1.016)
					(thickness 0.1524)
				)
				(justify mirror)
			)
		)
		(duplicate_pad_numbers_are_jumpers no)
		(fp_line
			(start 0.508 -0.9398)
			(end 0.508 0.9398)
			(stroke
				(width 0.1524)
				(type default)
			)
			(layer "B.SilkS")
		)
		(fp_line
			(start -0.508 -0.9398)
			(end 0.508 -0.9398)
			(stroke
				(width 0.1524)
				(type default)
			)
			(layer "B.SilkS")
		)
		(fp_rect
			(start 0.508 0.9398)
			(end -0.508 -0.9398)
			(stroke
				(width 0)
				(type default)
			)
			(fill no)
			(layer "B.CrtYd")
		)
		(fp_rect
			(start 0.508 0.9398)
			(end -0.508 -0.9398)
			(stroke
				(width 0)
				(type default)
			)
			(fill no)
			(layer "B.Fab")
		)
		(pad "1" smd custom
			(at 0 -0.4445 270)
			(size 0.1397 0.1397)
			(layers "B.Cu" "B.Mask" "B.Paste")
			(net "GND")
			(options
				(clearance outline)
				(anchor circle)
			)
			(primitives
				(gr_poly
					(pts
						(arc
							(start -0.1778 0.2794)
							(mid -0.249642 0.249642)
							(end -0.2794 0.1778)
						)
						(arc
							(start -0.2794 -0.1778)
							(mid -0.249642 -0.249642)
							(end -0.1778 -0.2794)
						)
						(arc
							(start 0.1778 -0.2794)
							(mid 0.249642 -0.249642)
							(end 0.2794 -0.1778)
						)
						(arc
							(start 0.2794 0.1778)
							(mid 0.249642 0.249642)
							(end 0.1778 0.2794)
						)
					)
					(width 0)
					(fill yes)
				)
			)
		)
		(pad "2" smd custom
			(at 0 0.4445 270)
			(size 0.1397 0.1397)
			(layers "B.Cu" "B.Mask" "B.Paste")
			(net "MEMA_8")
			(options
				(clearance outline)
				(anchor circle)
			)
			(primitives
				(gr_poly
					(pts
						(arc
							(start -0.1778 0.2794)
							(mid -0.249642 0.249642)
							(end -0.2794 0.1778)
						)
						(arc
							(start -0.2794 -0.1778)
							(mid -0.249642 -0.249642)
							(end -0.1778 -0.2794)
						)
						(arc
							(start 0.1778 -0.2794)
							(mid 0.249642 -0.249642)
							(end 0.2794 -0.1778)
						)
						(arc
							(start 0.2794 0.1778)
							(mid 0.249642 0.249642)
							(end 0.1778 0.2794)
						)
					)
					(width 0)
					(fill yes)
				)
			)
		)
	)
	(footprint ""
		(layer "B.Cu")
		(at 10.20445 -133.85673 90)
		(property "Reference" "R242"
			(at 0 0 90)
			(layer "B.SilkS")
			(hide yes)
			(effects
				(font
					(size 1.27 1.27)
				)
				(justify mirror)
			)
		)
		(property "Value" "120R2F-GP"
			(at -0.064008 -3.993896 90)
			(unlocked yes)
			(layer "B.Fab")
			(hide yes)
			(effects
				(font
					(size 1.016 1.016)
					(thickness 0.1524)
				)
				(justify mirror)
			)
		)
		(property "Device Type" "R402H16"
			(at -0.064008 -5.517896 90)
			(unlocked yes)
			(layer "B.Fab")
			(hide yes)
			(effects
				(font
					(size 1.016 1.016)
					(thickness 0.1524)
				)
				(justify mirror)
			)
		)
		(duplicate_pad_numbers_are_jumpers no)
		(fp_line
			(start 0.508 -0.9398)
			(end 0.508 0.9398)
			(stroke
				(width 0.1524)
				(type default)
			)
			(layer "B.SilkS")
		)
		(fp_line
			(start -0.508 -0.9398)
			(end 0.508 -0.9398)
			(stroke
				(width 0.1524)
				(type default)
			)
			(layer "B.SilkS")
		)
		(fp_rect
			(start 0.508 0.9398)
			(end -0.508 -0.9398)
			(stroke
				(width 0)
				(type default)
			)
			(fill no)
			(layer "B.CrtYd")
		)
		(fp_rect
			(start 0.508 0.9398)
			(end -0.508 -0.9398)
			(stroke
				(width 0)
				(type default)
			)
			(fill no)
			(layer "B.Fab")
		)
		(pad "1" smd custom
			(at 0 -0.4445 270)
			(size 0.1397 0.1397)
			(layers "B.Cu" "B.Mask" "B.Paste")
			(net "GND")
			(options
				(clearance outline)
				(anchor circle)
			)
			(primitives
				(gr_poly
					(pts
						(arc
							(start -0.1778 0.2794)
							(mid -0.249642 0.249642)
							(end -0.2794 0.1778)
						)
						(arc
							(start -0.2794 -0.1778)
							(mid -0.249642 -0.249642)
							(end -0.1778 -0.2794)
						)
						(arc
							(start 0.1778 -0.2794)
							(mid 0.249642 -0.249642)
							(end 0.2794 -0.1778)
						)
						(arc
							(start 0.2794 0.1778)
							(mid 0.249642 0.249642)
							(end 0.1778 0.2794)
						)
					)
					(width 0)
					(fill yes)
				)
			)
		)
		(pad "2" smd custom
			(at 0 0.4445 270)
			(size 0.1397 0.1397)
			(layers "B.Cu" "B.Mask" "B.Paste")
			(net "MEMA_4")
			(options
				(clearance outline)
				(anchor circle)
			)
			(primitives
				(gr_poly
					(pts
						(arc
							(start -0.1778 0.2794)
							(mid -0.249642 0.249642)
							(end -0.2794 0.1778)
						)
						(arc
							(start -0.2794 -0.1778)
							(mid -0.249642 -0.249642)
							(end -0.1778 -0.2794)
						)
						(arc
							(start 0.1778 -0.2794)
							(mid 0.249642 -0.249642)
							(end 0.2794 -0.1778)
						)
						(arc
							(start 0.2794 0.1778)
							(mid 0.249642 0.249642)
							(end 0.1778 0.2794)
						)
					)
					(width 0)
					(fill yes)
				)
			)
		)
	)
	(footprint ""
		(layer "B.Cu")
		(at 12.11199 -141.008862 90)
		(property "Reference" "R255"
			(at 0 0 90)
			(layer "B.SilkS")
			(hide yes)
			(effects
				(font
					(size 1.27 1.27)
				)
				(justify mirror)
			)
		)
		(property "Value" "120R2F-GP"
			(at -0.064008 -3.993896 90)
			(unlocked yes)
			(layer "B.Fab")
			(hide yes)
			(effects
				(font
					(size 1.016 1.016)
					(thickness 0.1524)
				)
				(justify mirror)
			)
		)
		(property "Device Type" "R402H16"
			(at -0.064008 -5.517896 90)
			(unlocked yes)
			(layer "B.Fab")
			(hide yes)
			(effects
				(font
					(size 1.016 1.016)
					(thickness 0.1524)
				)
				(justify mirror)
			)
		)
		(duplicate_pad_numbers_are_jumpers no)
		(fp_line
			(start 0.508 -0.9398)
			(end 0.508 0.9398)
			(stroke
				(width 0.1524)
				(type default)
			)
			(layer "B.SilkS")
		)
		(fp_line
			(start -0.508 -0.9398)
			(end 0.508 -0.9398)
			(stroke
				(width 0.1524)
				(type default)
			)
			(layer "B.SilkS")
		)
		(fp_rect
			(start 0.508 0.9398)
			(end -0.508 -0.9398)
			(stroke
				(width 0)
				(type default)
			)
			(fill no)
			(layer "B.CrtYd")
		)
		(fp_rect
			(start 0.508 0.9398)
			(end -0.508 -0.9398)
			(stroke
				(width 0)
				(type default)
			)
			(fill no)
			(layer "B.Fab")
		)
		(pad "1" smd custom
			(at 0 -0.4445 270)
			(size 0.1397 0.1397)
			(layers "B.Cu" "B.Mask" "B.Paste")
			(net "MEMA_10")
			(options
				(clearance outline)
				(anchor circle)
			)
			(primitives
				(gr_poly
					(pts
						(arc
							(start -0.1778 0.2794)
							(mid -0.249642 0.249642)
							(end -0.2794 0.1778)
						)
						(arc
							(start -0.2794 -0.1778)
							(mid -0.249642 -0.249642)
							(end -0.1778 -0.2794)
						)
						(arc
							(start 0.1778 -0.2794)
							(mid 0.249642 -0.249642)
							(end 0.2794 -0.1778)
						)
						(arc
							(start 0.2794 0.1778)
							(mid 0.249642 0.249642)
							(end 0.1778 0.2794)
						)
					)
					(width 0)
					(fill yes)
				)
			)
		)
		(pad "2" smd custom
			(at 0 0.4445 270)
			(size 0.1397 0.1397)
			(layers "B.Cu" "B.Mask" "B.Paste")
			(net "P1V2_STBY")
			(options
				(clearance outline)
				(anchor circle)
			)
			(primitives
				(gr_poly
					(pts
						(arc
							(start -0.1778 0.2794)
							(mid -0.249642 0.249642)
							(end -0.2794 0.1778)
						)
						(arc
							(start -0.2794 -0.1778)
							(mid -0.249642 -0.249642)
							(end -0.1778 -0.2794)
						)
						(arc
							(start 0.1778 -0.2794)
							(mid 0.249642 -0.249642)
							(end 0.2794 -0.1778)
						)
						(arc
							(start 0.2794 0.1778)
							(mid 0.249642 0.249642)
							(end 0.1778 0.2794)
						)
					)
					(width 0)
					(fill yes)
				)
			)
		)
	)
	(footprint ""
		(layer "B.Cu")
		(at 25.334976 -141.03096 -90)
		(property "Reference" "R223"
			(at 0 0 90)
			(layer "B.SilkS")
			(hide yes)
			(effects
				(font
					(size 1.27 1.27)
				)
				(justify mirror)
			)
		)
		(property "Value" "120R2F-GP"
			(at -0.064008 -3.993896 270)
			(unlocked yes)
			(layer "B.Fab")
			(hide yes)
			(effects
				(font
					(size 1.016 1.016)
					(thickness 0.1524)
				)
				(justify mirror)
			)
		)
		(property "Device Type" "R402H16"
			(at -0.064008 -5.517896 270)
			(unlocked yes)
			(layer "B.Fab")
			(hide yes)
			(effects
				(font
					(size 1.016 1.016)
					(thickness 0.1524)
				)
				(justify mirror)
			)
		)
		(duplicate_pad_numbers_are_jumpers no)
		(fp_line
			(start -0.508 -0.9398)
			(end 0.508 -0.9398)
			(stroke
				(width 0.1524)
				(type default)
			)
			(layer "B.SilkS")
		)
		(fp_line
			(start 0.508 -0.9398)
			(end 0.508 0.9398)
			(stroke
				(width 0.1524)
				(type default)
			)
			(layer "B.SilkS")
		)
		(fp_rect
			(start 0.508 0.9398)
			(end -0.508 -0.9398)
			(stroke
				(width 0)
				(type default)
			)
			(fill no)
			(layer "B.CrtYd")
		)
		(fp_rect
			(start 0.508 0.9398)
			(end -0.508 -0.9398)
			(stroke
				(width 0)
				(type default)
			)
			(fill no)
			(layer "B.Fab")
		)
		(pad "1" smd custom
			(at 0 -0.4445 90)
			(size 0.1397 0.1397)
			(layers "B.Cu" "B.Mask" "B.Paste")
			(net "MEMRASN")
			(options
				(clearance outline)
				(anchor circle)
			)
			(primitives
				(gr_poly
					(pts
						(arc
							(start -0.1778 0.2794)
							(mid -0.249642 0.249642)
							(end -0.2794 0.1778)
						)
						(arc
							(start -0.2794 -0.1778)
							(mid -0.249642 -0.249642)
							(end -0.1778 -0.2794)
						)
						(arc
							(start 0.1778 -0.2794)
							(mid 0.249642 -0.249642)
							(end 0.2794 -0.1778)
						)
						(arc
							(start 0.2794 0.1778)
							(mid 0.249642 0.249642)
							(end 0.1778 0.2794)
						)
					)
					(width 0)
					(fill yes)
				)
			)
		)
		(pad "2" smd custom
			(at 0 0.4445 90)
			(size 0.1397 0.1397)
			(layers "B.Cu" "B.Mask" "B.Paste")
			(net "P1V2_STBY")
			(options
				(clearance outline)
				(anchor circle)
			)
			(primitives
				(gr_poly
					(pts
						(arc
							(start -0.1778 0.2794)
							(mid -0.249642 0.249642)
							(end -0.2794 0.1778)
						)
						(arc
							(start -0.2794 -0.1778)
							(mid -0.249642 -0.249642)
							(end -0.1778 -0.2794)
						)
						(arc
							(start 0.1778 -0.2794)
							(mid 0.249642 -0.249642)
							(end 0.2794 -0.1778)
						)
						(arc
							(start 0.2794 0.1778)
							(mid 0.249642 0.249642)
							(end 0.1778 0.2794)
						)
					)
					(width 0)
					(fill yes)
				)
			)
		)
	)
	(footprint ""
		(layer "B.Cu")
		(at 46.65218 -134.636764 180)
		(property "Reference" "R152"
			(at 0 0 0)
			(layer "B.SilkS")
			(hide yes)
			(effects
				(font
					(size 1.27 1.27)
				)
				(justify mirror)
			)
		)
		(property "Value" "0R2J-2-GP"
			(at -0.064008 -3.993896 180)
			(unlocked yes)
			(layer "B.Fab")
			(hide yes)
			(effects
				(font
					(size 1.016 1.016)
					(thickness 0.1524)
				)
				(justify mirror)
			)
		)
		(property "Device Type" "R402H16"
			(at -0.064008 -5.517896 180)
			(unlocked yes)
			(layer "B.Fab")
			(hide yes)
			(effects
				(font
					(size 1.016 1.016)
					(thickness 0.1524)
				)
				(justify mirror)
			)
		)
		(duplicate_pad_numbers_are_jumpers no)
		(fp_line
			(start 0.508 -0.9398)
			(end 0.508 0.9398)
			(stroke
				(width 0.1524)
				(type default)
			)
			(layer "B.SilkS")
		)
		(fp_line
			(start -0.508 -0.9398)
			(end 0.508 -0.9398)
			(stroke
				(width 0.1524)
				(type default)
			)
			(layer "B.SilkS")
		)
		(fp_rect
			(start 0.508 0.9398)
			(end -0.508 -0.9398)
			(stroke
				(width 0)
				(type default)
			)
			(fill no)
			(layer "B.CrtYd")
		)
		(fp_rect
			(start 0.508 0.9398)
			(end -0.508 -0.9398)
			(stroke
				(width 0)
				(type default)
			)
			(fill no)
			(layer "B.Fab")
		)
		(pad "1" smd custom
			(at 0 -0.4445)
			(size 0.1397 0.1397)
			(layers "B.Cu" "B.Mask" "B.Paste")
			(net "I2C_IOM_SCL")
			(options
				(clearance outline)
				(anchor circle)
			)
			(primitives
				(gr_poly
					(pts
						(arc
							(start -0.1778 0.2794)
							(mid -0.249642 0.249642)
							(end -0.2794 0.1778)
						)
						(arc
							(start -0.2794 -0.1778)
							(mid -0.249642 -0.249642)
							(end -0.1778 -0.2794)
						)
						(arc
							(start 0.1778 -0.2794)
							(mid 0.249642 -0.249642)
							(end 0.2794 -0.1778)
						)
						(arc
							(start 0.2794 0.1778)
							(mid 0.249642 0.249642)
							(end 0.1778 0.2794)
						)
					)
					(width 0)
					(fill yes)
				)
			)
		)
		(pad "2" smd custom
			(at 0 0.4445)
			(size 0.1397 0.1397)
			(layers "B.Cu" "B.Mask" "B.Paste")
			(net "BMC_SMB1_CLK")
			(options
				(clearance outline)
				(anchor circle)
			)
			(primitives
				(gr_poly
					(pts
						(arc
							(start -0.1778 0.2794)
							(mid -0.249642 0.249642)
							(end -0.2794 0.1778)
						)
						(arc
							(start -0.2794 -0.1778)
							(mid -0.249642 -0.249642)
							(end -0.1778 -0.2794)
						)
						(arc
							(start 0.1778 -0.2794)
							(mid 0.249642 -0.249642)
							(end 0.2794 -0.1778)
						)
						(arc
							(start 0.2794 0.1778)
							(mid 0.249642 0.249642)
							(end 0.1778 0.2794)
						)
					)
					(width 0)
					(fill yes)
				)
			)
		)
	)
	(footprint ""
		(layer "B.Cu")
		(at 219.82303 -53.89499 -90)
		(property "Reference" "C157"
			(at 0 0 90)
			(layer "B.SilkS")
			(hide yes)
			(effects
				(font
					(size 1.27 1.27)
				)
				(justify mirror)
			)
		)
		(property "Value" "SC4D7U25V5KX-1-GP"
			(at 0.0762 -6.1214 270)
			(unlocked yes)
			(layer "B.Fab")
			(hide yes)
			(effects
				(font
					(size 1.016 1.016)
					(thickness 0.1524)
				)
				(justify mirror)
			)
		)
		(property "Device Type" "C805H58"
			(at 0.0762 -8.1534 270)
			(unlocked yes)
			(layer "B.Fab")
			(hide yes)
			(effects
				(font
					(size 1.016 1.016)
					(thickness 0.1524)
				)
				(justify mirror)
			)
		)
		(duplicate_pad_numbers_are_jumpers no)
		(fp_line
			(start -0.635 0)
			(end 0.635 0)
			(stroke
				(width 0.508)
				(type default)
			)
			(layer "B.SilkS")
		)
		(fp_rect
			(start 0.9652 1.778)
			(end -0.9652 -1.778)
			(stroke
				(width 0)
				(type default)
			)
			(fill no)
			(layer "B.CrtYd")
		)
		(fp_poly
			(pts
				(xy 0.9652 -1.778) (xy -0.9652 -1.778) (xy -0.9652 1.778) (xy 0.9652 1.778)
			)
			(stroke
				(width 0)
				(type default)
			)
			(fill no)
			(layer "B.Fab")
		)
		(pad "1" smd rect
			(at 0 -0.9652 90)
			(size 1.397 1.143)
			(layers "B.Cu" "B.Mask" "B.Paste")
			(net "P5V_VDD")
		)
		(pad "2" smd rect
			(at 0 0.9652 90)
			(size 1.397 1.143)
			(layers "B.Cu" "B.Mask" "B.Paste")
			(net "GND")
		)
	)
	(footprint ""
		(layer "B.Cu")
		(at 69.3166 -148.844)
		(property "Reference" "R381"
			(at 0 0 0)
			(layer "B.SilkS")
			(hide yes)
			(effects
				(font
					(size 1.27 1.27)
				)
				(justify mirror)
			)
		)
		(property "Value" "4K7R2F-GP"
			(at -0.064008 -3.993896 0)
			(unlocked yes)
			(layer "B.Fab")
			(hide yes)
			(effects
				(font
					(size 1.016 1.016)
					(thickness 0.1524)
				)
				(justify mirror)
			)
		)
		(property "Device Type" "R402H16"
			(at -0.064008 -5.517896 0)
			(unlocked yes)
			(layer "B.Fab")
			(hide yes)
			(effects
				(font
					(size 1.016 1.016)
					(thickness 0.1524)
				)
				(justify mirror)
			)
		)
		(duplicate_pad_numbers_are_jumpers no)
		(fp_line
			(start -0.508 -0.9398)
			(end 0.508 -0.9398)
			(stroke
				(width 0.1524)
				(type default)
			)
			(layer "B.SilkS")
		)
		(fp_line
			(start 0.508 -0.9398)
			(end 0.508 0.9398)
			(stroke
				(width 0.1524)
				(type default)
			)
			(layer "B.SilkS")
		)
		(fp_rect
			(start 0.508 0.9398)
			(end -0.508 -0.9398)
			(stroke
				(width 0)
				(type default)
			)
			(fill no)
			(layer "B.CrtYd")
		)
		(fp_rect
			(start 0.508 0.9398)
			(end -0.508 -0.9398)
			(stroke
				(width 0)
				(type default)
			)
			(fill no)
			(layer "B.Fab")
		)
		(pad "1" smd custom
			(at 0 -0.4445 180)
			(size 0.1397 0.1397)
			(layers "B.Cu" "B.Mask" "B.Paste")
			(net "P3V3_STBY")
			(options
				(clearance outline)
				(anchor circle)
			)
			(primitives
				(gr_poly
					(pts
						(arc
							(start -0.1778 0.2794)
							(mid -0.249642 0.249642)
							(end -0.2794 0.1778)
						)
						(arc
							(start -0.2794 -0.1778)
							(mid -0.249642 -0.249642)
							(end -0.1778 -0.2794)
						)
						(arc
							(start 0.1778 -0.2794)
							(mid 0.249642 -0.249642)
							(end 0.2794 -0.1778)
						)
						(arc
							(start 0.2794 0.1778)
							(mid 0.249642 0.249642)
							(end 0.1778 0.2794)
						)
					)
					(width 0)
					(fill yes)
				)
			)
		)
		(pad "2" smd custom
			(at 0 0.4445 180)
			(size 0.1397 0.1397)
			(layers "B.Cu" "B.Mask" "B.Paste")
			(net "NCSI_TXD0")
			(options
				(clearance outline)
				(anchor circle)
			)
			(primitives
				(gr_poly
					(pts
						(arc
							(start -0.1778 0.2794)
							(mid -0.249642 0.249642)
							(end -0.2794 0.1778)
						)
						(arc
							(start -0.2794 -0.1778)
							(mid -0.249642 -0.249642)
							(end -0.1778 -0.2794)
						)
						(arc
							(start 0.1778 -0.2794)
							(mid 0.249642 -0.249642)
							(end 0.2794 -0.1778)
						)
						(arc
							(start 0.2794 0.1778)
							(mid 0.249642 0.249642)
							(end 0.1778 0.2794)
						)
					)
					(width 0)
					(fill yes)
				)
			)
		)
	)
	(footprint ""
		(layer "B.Cu")
		(at 24.4602 -179.2478 -90)
		(property "Reference" "C179"
			(at 0 0 90)
			(layer "B.SilkS")
			(hide yes)
			(effects
				(font
					(size 1.27 1.27)
				)
				(justify mirror)
			)
		)
		(property "Value" "SC4D7U25V5KX-1-GP"
			(at 0.0762 -6.1214 270)
			(unlocked yes)
			(layer "B.Fab")
			(hide yes)
			(effects
				(font
					(size 1.016 1.016)
					(thickness 0.1524)
				)
				(justify mirror)
			)
		)
		(property "Device Type" "C805H58"
			(at 0.0762 -8.1534 270)
			(unlocked yes)
			(layer "B.Fab")
			(hide yes)
			(effects
				(font
					(size 1.016 1.016)
					(thickness 0.1524)
				)
				(justify mirror)
			)
		)
		(duplicate_pad_numbers_are_jumpers no)
		(fp_line
			(start -0.635 0)
			(end 0.635 0)
			(stroke
				(width 0.508)
				(type default)
			)
			(layer "B.SilkS")
		)
		(fp_rect
			(start 0.9652 1.778)
			(end -0.9652 -1.778)
			(stroke
				(width 0)
				(type default)
			)
			(fill no)
			(layer "B.CrtYd")
		)
		(fp_poly
			(pts
				(xy 0.9652 -1.778) (xy -0.9652 -1.778) (xy -0.9652 1.778) (xy 0.9652 1.778)
			)
			(stroke
				(width 0)
				(type default)
			)
			(fill no)
			(layer "B.Fab")
		)
		(pad "1" smd rect
			(at 0 -0.9652 90)
			(size 1.397 1.143)
			(layers "B.Cu" "B.Mask" "B.Paste")
			(net "P12V_STBY_VDD_PU2")
		)
		(pad "2" smd rect
			(at 0 0.9652 90)
			(size 1.397 1.143)
			(layers "B.Cu" "B.Mask" "B.Paste")
			(net "GND")
		)
	)
	(footprint ""
		(layer "B.Cu")
		(at 95.25 -6.223 90)
		(property "Reference" "C525"
			(at 0 0 90)
			(layer "B.SilkS")
			(hide yes)
			(effects
				(font
					(size 1.27 1.27)
				)
				(justify mirror)
			)
		)
		(property "Value" "SC1000P2KV6KX-GP-U"
			(at -0.0508 -3.5052 90)
			(unlocked yes)
			(layer "B.Fab")
			(hide yes)
			(effects
				(font
					(size 1.016 1.016)
					(thickness 0.1524)
				)
				(justify mirror)
			)
		)
		(property "Device Type" "C1206H58"
			(at -0.0508 -5.0292 90)
			(unlocked yes)
			(layer "B.Fab")
			(hide yes)
			(effects
				(font
					(size 1.016 1.016)
					(thickness 0.1524)
				)
				(justify mirror)
			)
		)
		(duplicate_pad_numbers_are_jumpers no)
		(fp_line
			(start 1.016 -2.2352)
			(end 1.016 -0.8382)
			(stroke
				(width 0.1524)
				(type default)
			)
			(layer "B.SilkS")
		)
		(fp_line
			(start -1.016 -2.2352)
			(end 1.016 -2.2352)
			(stroke
				(width 0.1524)
				(type default)
			)
			(layer "B.SilkS")
		)
		(fp_line
			(start -1.016 -2.2352)
			(end -1.016 -0.8382)
			(stroke
				(width 0.1524)
				(type default)
			)
			(layer "B.SilkS")
		)
		(fp_line
			(start -1.016 0.8382)
			(end -1.016 2.2352)
			(stroke
				(width 0.1524)
				(type default)
			)
			(layer "B.SilkS")
		)
		(fp_line
			(start 1.016 2.2352)
			(end 1.016 0.8128)
			(stroke
				(width 0.1524)
				(type default)
			)
			(layer "B.SilkS")
		)
		(fp_line
			(start -1.016 2.2352)
			(end 1.016 2.2352)
			(stroke
				(width 0.1524)
				(type default)
			)
			(layer "B.SilkS")
		)
		(fp_rect
			(start 1.0922 2.3114)
			(end -1.0922 -2.3114)
			(stroke
				(width 0)
				(type default)
			)
			(fill no)
			(layer "B.CrtYd")
		)
		(fp_poly
			(pts
				(xy 1.0922 -2.3114) (xy -1.0922 -2.3114) (xy -1.0922 2.3114) (xy 1.0922 2.3114)
			)
			(stroke
				(width 0)
				(type default)
			)
			(fill no)
			(layer "B.Fab")
		)
		(pad "1" smd rect
			(at 0 -1.397 270)
			(size 1.651 1.27)
			(layers "B.Cu" "B.Mask" "B.Paste")
			(net "USB_CONN_GND")
		)
		(pad "2" smd rect
			(at 0 1.397 270)
			(size 1.651 1.27)
			(layers "B.Cu" "B.Mask" "B.Paste")
			(net "GND")
		)
	)
	(footprint ""
		(layer "B.Cu")
		(at 56.3118 -138.557 -90)
		(property "Reference" "TP70"
			(at 0 0 90)
			(layer "B.SilkS")
			(hide yes)
			(effects
				(font
					(size 1.27 1.27)
				)
				(justify mirror)
			)
		)
		(property "Value" "TPAD28-2-GP"
			(at 0.0127 -1.6637 270)
			(unlocked yes)
			(layer "B.Fab")
			(hide yes)
			(effects
				(font
					(size 1.016 1.016)
					(thickness 0.1524)
				)
				(justify mirror)
			)
		)
		(property "Device Type" "TPAD28"
			(at 0.0127 -3.1877 270)
			(unlocked yes)
			(layer "B.Fab")
			(hide yes)
			(effects
				(font
					(size 1.016 1.016)
					(thickness 0.1524)
				)
				(justify mirror)
			)
		)
		(duplicate_pad_numbers_are_jumpers no)
		(fp_poly
			(pts
				(arc
					(start 0 -0.3556)
					(mid 0 0.3556)
					(end 0 -0.3556)
				)
			)
			(stroke
				(width 0)
				(type default)
			)
			(fill no)
			(layer "B.CrtYd")
		)
		(fp_poly
			(pts
				(arc
					(start 0 -0.6096)
					(mid 0 0.6096)
					(end 0 -0.6096)
				)
			)
			(stroke
				(width 0)
				(type default)
			)
			(fill no)
			(layer "B.Fab")
		)
		(pad "1" smd circle
			(at 0 0 90)
			(size 0.7112 0.7112)
			(layers "B.Cu" "B.Mask" "B.Paste")
			(net "TP_BMC_GPIOI0")
		)
	)
	(footprint ""
		(layer "B.Cu")
		(at 20.376896 -141.833092 -90)
		(property "Reference" "R205"
			(at 0 0 90)
			(layer "B.SilkS")
			(hide yes)
			(effects
				(font
					(size 1.27 1.27)
				)
				(justify mirror)
			)
		)
		(property "Value" "60D4R2F-GP"
			(at -0.064008 -3.993896 270)
			(unlocked yes)
			(layer "B.Fab")
			(hide yes)
			(effects
				(font
					(size 1.016 1.016)
					(thickness 0.1524)
				)
				(justify mirror)
			)
		)
		(property "Device Type" "R402H16"
			(at -0.064008 -5.517896 270)
			(unlocked yes)
			(layer "B.Fab")
			(hide yes)
			(effects
				(font
					(size 1.016 1.016)
					(thickness 0.1524)
				)
				(justify mirror)
			)
		)
		(duplicate_pad_numbers_are_jumpers no)
		(fp_line
			(start -0.508 -0.9398)
			(end 0.508 -0.9398)
			(stroke
				(width 0.1524)
				(type default)
			)
			(layer "B.SilkS")
		)
		(fp_line
			(start 0.508 -0.9398)
			(end 0.508 0.9398)
			(stroke
				(width 0.1524)
				(type default)
			)
			(layer "B.SilkS")
		)
		(fp_rect
			(start 0.508 0.9398)
			(end -0.508 -0.9398)
			(stroke
				(width 0)
				(type default)
			)
			(fill no)
			(layer "B.CrtYd")
		)
		(fp_rect
			(start 0.508 0.9398)
			(end -0.508 -0.9398)
			(stroke
				(width 0)
				(type default)
			)
			(fill no)
			(layer "B.Fab")
		)
		(pad "1" smd custom
			(at 0 -0.4445 90)
			(size 0.1397 0.1397)
			(layers "B.Cu" "B.Mask" "B.Paste")
			(net "MEMCK_P")
			(options
				(clearance outline)
				(anchor circle)
			)
			(primitives
				(gr_poly
					(pts
						(arc
							(start -0.1778 0.2794)
							(mid -0.249642 0.249642)
							(end -0.2794 0.1778)
						)
						(arc
							(start -0.2794 -0.1778)
							(mid -0.249642 -0.249642)
							(end -0.1778 -0.2794)
						)
						(arc
							(start 0.1778 -0.2794)
							(mid 0.249642 -0.249642)
							(end 0.2794 -0.1778)
						)
						(arc
							(start 0.2794 0.1778)
							(mid 0.249642 0.249642)
							(end 0.1778 0.2794)
						)
					)
					(width 0)
					(fill yes)
				)
			)
		)
		(pad "2" smd custom
			(at 0 0.4445 90)
			(size 0.1397 0.1397)
			(layers "B.Cu" "B.Mask" "B.Paste")
			(net "MEMCK_TER")
			(options
				(clearance outline)
				(anchor circle)
			)
			(primitives
				(gr_poly
					(pts
						(arc
							(start -0.1778 0.2794)
							(mid -0.249642 0.249642)
							(end -0.2794 0.1778)
						)
						(arc
							(start -0.2794 -0.1778)
							(mid -0.249642 -0.249642)
							(end -0.1778 -0.2794)
						)
						(arc
							(start 0.1778 -0.2794)
							(mid 0.249642 -0.249642)
							(end 0.2794 -0.1778)
						)
						(arc
							(start 0.2794 0.1778)
							(mid 0.249642 0.249642)
							(end 0.1778 0.2794)
						)
					)
					(width 0)
					(fill yes)
				)
			)
		)
	)
	(footprint ""
		(layer "B.Cu")
		(at 176.5554 -115.57 -90)
		(property "Reference" "R834"
			(at 0 0 90)
			(layer "B.SilkS")
			(hide yes)
			(effects
				(font
					(size 1.27 1.27)
				)
				(justify mirror)
			)
		)
		(property "Value" "200KR2F-L-GP"
			(at -0.064008 -3.993896 270)
			(unlocked yes)
			(layer "B.Fab")
			(hide yes)
			(effects
				(font
					(size 1.016 1.016)
					(thickness 0.1524)
				)
				(justify mirror)
			)
		)
		(property "Device Type" "R402H16"
			(at -0.064008 -5.517896 270)
			(unlocked yes)
			(layer "B.Fab")
			(hide yes)
			(effects
				(font
					(size 1.016 1.016)
					(thickness 0.1524)
				)
				(justify mirror)
			)
		)
		(duplicate_pad_numbers_are_jumpers no)
		(fp_line
			(start -0.508 -0.9398)
			(end 0.508 -0.9398)
			(stroke
				(width 0.1524)
				(type default)
			)
			(layer "B.SilkS")
		)
		(fp_line
			(start 0.508 -0.9398)
			(end 0.508 0.9398)
			(stroke
				(width 0.1524)
				(type default)
			)
			(layer "B.SilkS")
		)
		(fp_rect
			(start 0.508 0.9398)
			(end -0.508 -0.9398)
			(stroke
				(width 0)
				(type default)
			)
			(fill no)
			(layer "B.CrtYd")
		)
		(fp_rect
			(start 0.508 0.9398)
			(end -0.508 -0.9398)
			(stroke
				(width 0)
				(type default)
			)
			(fill no)
			(layer "B.Fab")
		)
		(pad "1" smd custom
			(at 0 -0.4445 90)
			(size 0.1397 0.1397)
			(layers "B.Cu" "B.Mask" "B.Paste")
			(net "U83_VREF2")
			(options
				(clearance outline)
				(anchor circle)
			)
			(primitives
				(gr_poly
					(pts
						(arc
							(start -0.1778 0.2794)
							(mid -0.249642 0.249642)
							(end -0.2794 0.1778)
						)
						(arc
							(start -0.2794 -0.1778)
							(mid -0.249642 -0.249642)
							(end -0.1778 -0.2794)
						)
						(arc
							(start 0.1778 -0.2794)
							(mid 0.249642 -0.249642)
							(end 0.2794 -0.1778)
						)
						(arc
							(start 0.2794 0.1778)
							(mid 0.249642 0.249642)
							(end 0.1778 0.2794)
						)
					)
					(width 0)
					(fill yes)
				)
			)
		)
		(pad "2" smd custom
			(at 0 0.4445 90)
			(size 0.1397 0.1397)
			(layers "B.Cu" "B.Mask" "B.Paste")
			(net "P3V3_STBY")
			(options
				(clearance outline)
				(anchor circle)
			)
			(primitives
				(gr_poly
					(pts
						(arc
							(start -0.1778 0.2794)
							(mid -0.249642 0.249642)
							(end -0.2794 0.1778)
						)
						(arc
							(start -0.2794 -0.1778)
							(mid -0.249642 -0.249642)
							(end -0.1778 -0.2794)
						)
						(arc
							(start 0.1778 -0.2794)
							(mid 0.249642 -0.249642)
							(end 0.2794 -0.1778)
						)
						(arc
							(start 0.2794 0.1778)
							(mid 0.249642 0.249642)
							(end 0.1778 0.2794)
						)
					)
					(width 0)
					(fill yes)
				)
			)
		)
	)
	(footprint ""
		(layer "B.Cu")
		(at 227.094288 -101.96195 180)
		(property "Reference" "C638"
			(at 0 0 0)
			(layer "B.SilkS")
			(hide yes)
			(effects
				(font
					(size 1.27 1.27)
				)
				(justify mirror)
			)
		)
		(property "Value" "SC10U16V5KX-7-GP-U"
			(at 0.0762 -6.1214 180)
			(unlocked yes)
			(layer "B.Fab")
			(hide yes)
			(effects
				(font
					(size 1.016 1.016)
					(thickness 0.1524)
				)
				(justify mirror)
			)
		)
		(property "Device Type" "C805H58"
			(at 0.0762 -8.1534 180)
			(unlocked yes)
			(layer "B.Fab")
			(hide yes)
			(effects
				(font
					(size 1.016 1.016)
					(thickness 0.1524)
				)
				(justify mirror)
			)
		)
		(duplicate_pad_numbers_are_jumpers no)
		(fp_line
			(start -0.635 0)
			(end 0.635 0)
			(stroke
				(width 0.508)
				(type default)
			)
			(layer "B.SilkS")
		)
		(fp_rect
			(start 0.9652 1.778)
			(end -0.9652 -1.778)
			(stroke
				(width 0)
				(type default)
			)
			(fill no)
			(layer "B.CrtYd")
		)
		(fp_poly
			(pts
				(xy 0.9652 -1.778) (xy -0.9652 -1.778) (xy -0.9652 1.778) (xy 0.9652 1.778)
			)
			(stroke
				(width 0)
				(type default)
			)
			(fill no)
			(layer "B.Fab")
		)
		(pad "1" smd rect
			(at 0 -0.9652)
			(size 1.397 1.143)
			(layers "B.Cu" "B.Mask" "B.Paste")
			(net "P12V_STBY_VIN_U81")
		)
		(pad "2" smd rect
			(at 0 0.9652)
			(size 1.397 1.143)
			(layers "B.Cu" "B.Mask" "B.Paste")
			(net "GND")
		)
	)
	(footprint ""
		(layer "B.Cu")
		(at 41.653714 -153.965148)
		(property "Reference" "TP62"
			(at 0 0 0)
			(layer "B.SilkS")
			(hide yes)
			(effects
				(font
					(size 1.27 1.27)
				)
				(justify mirror)
			)
		)
		(property "Value" "TPAD28-2-GP"
			(at 0.0127 -1.6637 0)
			(unlocked yes)
			(layer "B.Fab")
			(hide yes)
			(effects
				(font
					(size 1.016 1.016)
					(thickness 0.1524)
				)
				(justify mirror)
			)
		)
		(property "Device Type" "TPAD28"
			(at 0.0127 -3.1877 0)
			(unlocked yes)
			(layer "B.Fab")
			(hide yes)
			(effects
				(font
					(size 1.016 1.016)
					(thickness 0.1524)
				)
				(justify mirror)
			)
		)
		(duplicate_pad_numbers_are_jumpers no)
		(fp_poly
			(pts
				(arc
					(start 0.3556 0)
					(mid -0.3556 0)
					(end 0.3556 0)
				)
			)
			(stroke
				(width 0)
				(type default)
			)
			(fill no)
			(layer "B.CrtYd")
		)
		(fp_poly
			(pts
				(arc
					(start 0.6096 0)
					(mid -0.6096 0)
					(end 0.6096 0)
				)
			)
			(stroke
				(width 0)
				(type default)
			)
			(fill no)
			(layer "B.Fab")
		)
		(pad "1" smd circle
			(at 0 0 180)
			(size 0.7112 0.7112)
			(layers "B.Cu" "B.Mask" "B.Paste")
			(net "TP_BMC_GPION2")
		)
	)
	(footprint ""
		(layer "B.Cu")
		(at 65.420494 -139.270232 -90)
		(property "Reference" "R601"
			(at 0 0 90)
			(layer "B.SilkS")
			(hide yes)
			(effects
				(font
					(size 1.27 1.27)
				)
				(justify mirror)
			)
		)
		(property "Value" "4K7R2F-GP"
			(at -0.064008 -3.993896 270)
			(unlocked yes)
			(layer "B.Fab")
			(hide yes)
			(effects
				(font
					(size 1.016 1.016)
					(thickness 0.1524)
				)
				(justify mirror)
			)
		)
		(property "Device Type" "R402H16"
			(at -0.064008 -5.517896 270)
			(unlocked yes)
			(layer "B.Fab")
			(hide yes)
			(effects
				(font
					(size 1.016 1.016)
					(thickness 0.1524)
				)
				(justify mirror)
			)
		)
		(duplicate_pad_numbers_are_jumpers no)
		(fp_line
			(start -0.508 -0.9398)
			(end 0.508 -0.9398)
			(stroke
				(width 0.1524)
				(type default)
			)
			(layer "B.SilkS")
		)
		(fp_line
			(start 0.508 -0.9398)
			(end 0.508 0.9398)
			(stroke
				(width 0.1524)
				(type default)
			)
			(layer "B.SilkS")
		)
		(fp_rect
			(start 0.508 0.9398)
			(end -0.508 -0.9398)
			(stroke
				(width 0)
				(type default)
			)
			(fill no)
			(layer "B.CrtYd")
		)
		(fp_rect
			(start 0.508 0.9398)
			(end -0.508 -0.9398)
			(stroke
				(width 0)
				(type default)
			)
			(fill no)
			(layer "B.Fab")
		)
		(pad "1" smd custom
			(at 0 -0.4445 90)
			(size 0.1397 0.1397)
			(layers "B.Cu" "B.Mask" "B.Paste")
			(net "P3V3_STBY")
			(options
				(clearance outline)
				(anchor circle)
			)
			(primitives
				(gr_poly
					(pts
						(arc
							(start -0.1778 0.2794)
							(mid -0.249642 0.249642)
							(end -0.2794 0.1778)
						)
						(arc
							(start -0.2794 -0.1778)
							(mid -0.249642 -0.249642)
							(end -0.1778 -0.2794)
						)
						(arc
							(start 0.1778 -0.2794)
							(mid 0.249642 -0.249642)
							(end 0.2794 -0.1778)
						)
						(arc
							(start 0.2794 0.1778)
							(mid 0.249642 0.249642)
							(end 0.1778 0.2794)
						)
					)
					(width 0)
					(fill yes)
				)
			)
		)
		(pad "2" smd custom
			(at 0 0.4445 90)
			(size 0.1397 0.1397)
			(layers "B.Cu" "B.Mask" "B.Paste")
			(net "I2C_COMP_ALERT_N")
			(options
				(clearance outline)
				(anchor circle)
			)
			(primitives
				(gr_poly
					(pts
						(arc
							(start -0.1778 0.2794)
							(mid -0.249642 0.249642)
							(end -0.2794 0.1778)
						)
						(arc
							(start -0.2794 -0.1778)
							(mid -0.249642 -0.249642)
							(end -0.1778 -0.2794)
						)
						(arc
							(start 0.1778 -0.2794)
							(mid 0.249642 -0.249642)
							(end 0.2794 -0.1778)
						)
						(arc
							(start 0.2794 0.1778)
							(mid 0.249642 0.249642)
							(end 0.1778 0.2794)
						)
					)
					(width 0)
					(fill yes)
				)
			)
		)
	)
	(footprint ""
		(layer "B.Cu")
		(at 50.75682 -148.19376 -90)
		(property "Reference" "C101"
			(at 0 0 90)
			(layer "B.SilkS")
			(hide yes)
			(effects
				(font
					(size 1.27 1.27)
				)
				(justify mirror)
			)
		)
		(property "Value" "SC1U16V3KX-5GP"
			(at 0 -2.8194 270)
			(unlocked yes)
			(layer "B.Fab")
			(hide yes)
			(effects
				(font
					(size 1.016 1.016)
					(thickness 0.1524)
				)
				(justify mirror)
			)
		)
		(property "Device Type" "C603H36"
			(at 0 -4.3434 270)
			(unlocked yes)
			(layer "B.Fab")
			(hide yes)
			(effects
				(font
					(size 1.016 1.016)
					(thickness 0.1524)
				)
				(justify mirror)
			)
		)
		(duplicate_pad_numbers_are_jumpers no)
		(fp_line
			(start -0.508 0)
			(end 0.508 0)
			(stroke
				(width 0.2032)
				(type default)
			)
			(layer "B.SilkS")
		)
		(fp_rect
			(start 0.5842 1.3335)
			(end -0.5842 -1.3335)
			(stroke
				(width 0)
				(type default)
			)
			(fill no)
			(layer "B.CrtYd")
		)
		(fp_rect
			(start 0.5842 1.3335)
			(end -0.5842 -1.3335)
			(stroke
				(width 0)
				(type default)
			)
			(fill no)
			(layer "B.Fab")
		)
		(pad "1" smd custom
			(at 0 -0.762 90)
			(size 0.2159 0.2159)
			(layers "B.Cu" "B.Mask" "B.Paste")
			(net "P3V3_STBY")
			(options
				(clearance outline)
				(anchor circle)
			)
			(primitives
				(gr_poly
					(pts
						(arc
							(start -0.3302 0.4318)
							(mid -0.402042 0.402042)
							(end -0.4318 0.3302)
						)
						(arc
							(start -0.4318 -0.3302)
							(mid -0.402042 -0.402042)
							(end -0.3302 -0.4318)
						)
						(arc
							(start 0.3302 -0.4318)
							(mid 0.402042 -0.402042)
							(end 0.4318 -0.3302)
						)
						(arc
							(start 0.4318 0.3302)
							(mid 0.402042 0.402042)
							(end 0.3302 0.4318)
						)
					)
					(width 0)
					(fill yes)
				)
			)
		)
		(pad "2" smd custom
			(at 0 0.762 90)
			(size 0.2159 0.2159)
			(layers "B.Cu" "B.Mask" "B.Paste")
			(net "GND")
			(options
				(clearance outline)
				(anchor circle)
			)
			(primitives
				(gr_poly
					(pts
						(arc
							(start -0.3302 0.4318)
							(mid -0.402042 0.402042)
							(end -0.4318 0.3302)
						)
						(arc
							(start -0.4318 -0.3302)
							(mid -0.402042 -0.402042)
							(end -0.3302 -0.4318)
						)
						(arc
							(start 0.3302 -0.4318)
							(mid 0.402042 -0.402042)
							(end 0.4318 -0.3302)
						)
						(arc
							(start 0.4318 0.3302)
							(mid 0.402042 0.402042)
							(end 0.3302 0.4318)
						)
					)
					(width 0)
					(fill yes)
				)
			)
		)
	)
	(footprint ""
		(layer "B.Cu")
		(at 60.4774 -148.5138 180)
		(property "Reference" "R384"
			(at 0 0 0)
			(layer "B.SilkS")
			(hide yes)
			(effects
				(font
					(size 1.27 1.27)
				)
				(justify mirror)
			)
		)
		(property "Value" "4K7R2F-GP"
			(at -0.064008 -3.993896 180)
			(unlocked yes)
			(layer "B.Fab")
			(hide yes)
			(effects
				(font
					(size 1.016 1.016)
					(thickness 0.1524)
				)
				(justify mirror)
			)
		)
		(property "Device Type" "R402H16"
			(at -0.064008 -5.517896 180)
			(unlocked yes)
			(layer "B.Fab")
			(hide yes)
			(effects
				(font
					(size 1.016 1.016)
					(thickness 0.1524)
				)
				(justify mirror)
			)
		)
		(duplicate_pad_numbers_are_jumpers no)
		(fp_line
			(start 0.508 -0.9398)
			(end 0.508 0.9398)
			(stroke
				(width 0.1524)
				(type default)
			)
			(layer "B.SilkS")
		)
		(fp_line
			(start -0.508 -0.9398)
			(end 0.508 -0.9398)
			(stroke
				(width 0.1524)
				(type default)
			)
			(layer "B.SilkS")
		)
		(fp_rect
			(start 0.508 0.9398)
			(end -0.508 -0.9398)
			(stroke
				(width 0)
				(type default)
			)
			(fill no)
			(layer "B.CrtYd")
		)
		(fp_rect
			(start 0.508 0.9398)
			(end -0.508 -0.9398)
			(stroke
				(width 0)
				(type default)
			)
			(fill no)
			(layer "B.Fab")
		)
		(pad "1" smd custom
			(at 0 -0.4445)
			(size 0.1397 0.1397)
			(layers "B.Cu" "B.Mask" "B.Paste")
			(net "P3V3_STBY")
			(options
				(clearance outline)
				(anchor circle)
			)
			(primitives
				(gr_poly
					(pts
						(arc
							(start -0.1778 0.2794)
							(mid -0.249642 0.249642)
							(end -0.2794 0.1778)
						)
						(arc
							(start -0.2794 -0.1778)
							(mid -0.249642 -0.249642)
							(end -0.1778 -0.2794)
						)
						(arc
							(start 0.1778 -0.2794)
							(mid 0.249642 -0.249642)
							(end 0.2794 -0.1778)
						)
						(arc
							(start 0.2794 0.1778)
							(mid 0.249642 0.249642)
							(end 0.1778 0.2794)
						)
					)
					(width 0)
					(fill yes)
				)
			)
		)
		(pad "2" smd custom
			(at 0 0.4445)
			(size 0.1397 0.1397)
			(layers "B.Cu" "B.Mask" "B.Paste")
			(net "MAC1_TXD3")
			(options
				(clearance outline)
				(anchor circle)
			)
			(primitives
				(gr_poly
					(pts
						(arc
							(start -0.1778 0.2794)
							(mid -0.249642 0.249642)
							(end -0.2794 0.1778)
						)
						(arc
							(start -0.2794 -0.1778)
							(mid -0.249642 -0.249642)
							(end -0.1778 -0.2794)
						)
						(arc
							(start 0.1778 -0.2794)
							(mid 0.249642 -0.249642)
							(end 0.2794 -0.1778)
						)
						(arc
							(start 0.2794 0.1778)
							(mid 0.249642 0.249642)
							(end 0.1778 0.2794)
						)
					)
					(width 0)
					(fill yes)
				)
			)
		)
	)
	(footprint ""
		(layer "B.Cu")
		(at 90.805 -143.5608 180)
		(property "Reference" "R722"
			(at 0 0 0)
			(layer "B.SilkS")
			(hide yes)
			(effects
				(font
					(size 1.27 1.27)
				)
				(justify mirror)
			)
		)
		(property "Value" "10KR2J-3-GP"
			(at -0.064008 -3.993896 180)
			(unlocked yes)
			(layer "B.Fab")
			(hide yes)
			(effects
				(font
					(size 1.016 1.016)
					(thickness 0.1524)
				)
				(justify mirror)
			)
		)
		(property "Device Type" "R402H16"
			(at -0.064008 -5.517896 180)
			(unlocked yes)
			(layer "B.Fab")
			(hide yes)
			(effects
				(font
					(size 1.016 1.016)
					(thickness 0.1524)
				)
				(justify mirror)
			)
		)
		(duplicate_pad_numbers_are_jumpers no)
		(fp_line
			(start 0.508 -0.9398)
			(end 0.508 0.9398)
			(stroke
				(width 0.1524)
				(type default)
			)
			(layer "B.SilkS")
		)
		(fp_line
			(start -0.508 -0.9398)
			(end 0.508 -0.9398)
			(stroke
				(width 0.1524)
				(type default)
			)
			(layer "B.SilkS")
		)
		(fp_rect
			(start 0.508 0.9398)
			(end -0.508 -0.9398)
			(stroke
				(width 0)
				(type default)
			)
			(fill no)
			(layer "B.CrtYd")
		)
		(fp_rect
			(start 0.508 0.9398)
			(end -0.508 -0.9398)
			(stroke
				(width 0)
				(type default)
			)
			(fill no)
			(layer "B.Fab")
		)
		(pad "1" smd custom
			(at 0 -0.4445)
			(size 0.1397 0.1397)
			(layers "B.Cu" "B.Mask" "B.Paste")
			(net "DB_PRSNT_BMC_N")
			(options
				(clearance outline)
				(anchor circle)
			)
			(primitives
				(gr_poly
					(pts
						(arc
							(start -0.1778 0.2794)
							(mid -0.249642 0.249642)
							(end -0.2794 0.1778)
						)
						(arc
							(start -0.2794 -0.1778)
							(mid -0.249642 -0.249642)
							(end -0.1778 -0.2794)
						)
						(arc
							(start 0.1778 -0.2794)
							(mid 0.249642 -0.249642)
							(end 0.2794 -0.1778)
						)
						(arc
							(start 0.2794 0.1778)
							(mid 0.249642 0.249642)
							(end 0.1778 0.2794)
						)
					)
					(width 0)
					(fill yes)
				)
			)
		)
		(pad "2" smd custom
			(at 0 0.4445)
			(size 0.1397 0.1397)
			(layers "B.Cu" "B.Mask" "B.Paste")
			(net "P3V3_STBY")
			(options
				(clearance outline)
				(anchor circle)
			)
			(primitives
				(gr_poly
					(pts
						(arc
							(start -0.1778 0.2794)
							(mid -0.249642 0.249642)
							(end -0.2794 0.1778)
						)
						(arc
							(start -0.2794 -0.1778)
							(mid -0.249642 -0.249642)
							(end -0.1778 -0.2794)
						)
						(arc
							(start 0.1778 -0.2794)
							(mid 0.249642 -0.249642)
							(end 0.2794 -0.1778)
						)
						(arc
							(start 0.2794 0.1778)
							(mid 0.249642 0.249642)
							(end 0.1778 0.2794)
						)
					)
					(width 0)
					(fill yes)
				)
			)
		)
	)
	(footprint ""
		(layer "B.Cu")
		(at 177.303176 -121.968006 90)
		(property "Reference" "R815"
			(at 0 0 90)
			(layer "B.SilkS")
			(hide yes)
			(effects
				(font
					(size 1.27 1.27)
				)
				(justify mirror)
			)
		)
		(property "Value" "1KR2F-3-GP"
			(at -0.064008 -3.993896 90)
			(unlocked yes)
			(layer "B.Fab")
			(hide yes)
			(effects
				(font
					(size 1.016 1.016)
					(thickness 0.1524)
				)
				(justify mirror)
			)
		)
		(property "Device Type" "R402H16"
			(at -0.064008 -5.517896 90)
			(unlocked yes)
			(layer "B.Fab")
			(hide yes)
			(effects
				(font
					(size 1.016 1.016)
					(thickness 0.1524)
				)
				(justify mirror)
			)
		)
		(duplicate_pad_numbers_are_jumpers no)
		(fp_line
			(start 0.508 -0.9398)
			(end 0.508 0.9398)
			(stroke
				(width 0.1524)
				(type default)
			)
			(layer "B.SilkS")
		)
		(fp_line
			(start -0.508 -0.9398)
			(end 0.508 -0.9398)
			(stroke
				(width 0.1524)
				(type default)
			)
			(layer "B.SilkS")
		)
		(fp_rect
			(start 0.508 0.9398)
			(end -0.508 -0.9398)
			(stroke
				(width 0)
				(type default)
			)
			(fill no)
			(layer "B.CrtYd")
		)
		(fp_rect
			(start 0.508 0.9398)
			(end -0.508 -0.9398)
			(stroke
				(width 0)
				(type default)
			)
			(fill no)
			(layer "B.Fab")
		)
		(pad "1" smd custom
			(at 0 -0.4445 270)
			(size 0.1397 0.1397)
			(layers "B.Cu" "B.Mask" "B.Paste")
			(net "P1V8_STBY")
			(options
				(clearance outline)
				(anchor circle)
			)
			(primitives
				(gr_poly
					(pts
						(arc
							(start -0.1778 0.2794)
							(mid -0.249642 0.249642)
							(end -0.2794 0.1778)
						)
						(arc
							(start -0.2794 -0.1778)
							(mid -0.249642 -0.249642)
							(end -0.1778 -0.2794)
						)
						(arc
							(start 0.1778 -0.2794)
							(mid 0.249642 -0.249642)
							(end 0.2794 -0.1778)
						)
						(arc
							(start 0.2794 0.1778)
							(mid 0.249642 0.249642)
							(end 0.1778 0.2794)
						)
					)
					(width 0)
					(fill yes)
				)
			)
		)
		(pad "2" smd custom
			(at 0 0.4445 270)
			(size 0.1397 0.1397)
			(layers "B.Cu" "B.Mask" "B.Paste")
			(net "I2C_M2_2_1V8_SCL")
			(options
				(clearance outline)
				(anchor circle)
			)
			(primitives
				(gr_poly
					(pts
						(arc
							(start -0.1778 0.2794)
							(mid -0.249642 0.249642)
							(end -0.2794 0.1778)
						)
						(arc
							(start -0.2794 -0.1778)
							(mid -0.249642 -0.249642)
							(end -0.1778 -0.2794)
						)
						(arc
							(start 0.1778 -0.2794)
							(mid 0.249642 -0.249642)
							(end 0.2794 -0.1778)
						)
						(arc
							(start 0.2794 0.1778)
							(mid 0.249642 0.249642)
							(end 0.1778 0.2794)
						)
					)
					(width 0)
					(fill yes)
				)
			)
		)
	)
	(footprint ""
		(layer "B.Cu")
		(at 78.193646 -169.4688 180)
		(property "Reference" "R302"
			(at 0 0 0)
			(layer "B.SilkS")
			(hide yes)
			(effects
				(font
					(size 1.27 1.27)
				)
				(justify mirror)
			)
		)
		(property "Value" "0R2J-2-GP"
			(at -0.064008 -3.993896 180)
			(unlocked yes)
			(layer "B.Fab")
			(hide yes)
			(effects
				(font
					(size 1.016 1.016)
					(thickness 0.1524)
				)
				(justify mirror)
			)
		)
		(property "Device Type" "R402H16"
			(at -0.064008 -5.517896 180)
			(unlocked yes)
			(layer "B.Fab")
			(hide yes)
			(effects
				(font
					(size 1.016 1.016)
					(thickness 0.1524)
				)
				(justify mirror)
			)
		)
		(duplicate_pad_numbers_are_jumpers no)
		(fp_line
			(start 0.508 -0.9398)
			(end 0.508 0.9398)
			(stroke
				(width 0.1524)
				(type default)
			)
			(layer "B.SilkS")
		)
		(fp_line
			(start -0.508 -0.9398)
			(end 0.508 -0.9398)
			(stroke
				(width 0.1524)
				(type default)
			)
			(layer "B.SilkS")
		)
		(fp_rect
			(start 0.508 0.9398)
			(end -0.508 -0.9398)
			(stroke
				(width 0)
				(type default)
			)
			(fill no)
			(layer "B.CrtYd")
		)
		(fp_rect
			(start 0.508 0.9398)
			(end -0.508 -0.9398)
			(stroke
				(width 0)
				(type default)
			)
			(fill no)
			(layer "B.Fab")
		)
		(pad "1" smd custom
			(at 0 -0.4445)
			(size 0.1397 0.1397)
			(layers "B.Cu" "B.Mask" "B.Paste")
			(net "UART_EXP_BMC_TX")
			(options
				(clearance outline)
				(anchor circle)
			)
			(primitives
				(gr_poly
					(pts
						(arc
							(start -0.1778 0.2794)
							(mid -0.249642 0.249642)
							(end -0.2794 0.1778)
						)
						(arc
							(start -0.2794 -0.1778)
							(mid -0.249642 -0.249642)
							(end -0.1778 -0.2794)
						)
						(arc
							(start 0.1778 -0.2794)
							(mid 0.249642 -0.249642)
							(end 0.2794 -0.1778)
						)
						(arc
							(start 0.2794 0.1778)
							(mid 0.249642 0.249642)
							(end 0.1778 0.2794)
						)
					)
					(width 0)
					(fill yes)
				)
			)
		)
		(pad "2" smd custom
			(at 0 0.4445)
			(size 0.1397 0.1397)
			(layers "B.Cu" "B.Mask" "B.Paste")
			(net "UART_EXP_BMC_TX_R")
			(options
				(clearance outline)
				(anchor circle)
			)
			(primitives
				(gr_poly
					(pts
						(arc
							(start -0.1778 0.2794)
							(mid -0.249642 0.249642)
							(end -0.2794 0.1778)
						)
						(arc
							(start -0.2794 -0.1778)
							(mid -0.249642 -0.249642)
							(end -0.1778 -0.2794)
						)
						(arc
							(start 0.1778 -0.2794)
							(mid 0.249642 -0.249642)
							(end 0.2794 -0.1778)
						)
						(arc
							(start 0.2794 0.1778)
							(mid 0.249642 0.249642)
							(end 0.1778 0.2794)
						)
					)
					(width 0)
					(fill yes)
				)
			)
		)
	)
	(footprint ""
		(layer "B.Cu")
		(at 23.58898 -143.81861 180)
		(property "Reference" "C67"
			(at 0 0 0)
			(layer "B.SilkS")
			(hide yes)
			(effects
				(font
					(size 1.27 1.27)
				)
				(justify mirror)
			)
		)
		(property "Value" "SCD1U16V2KX-3GP"
			(at -1.1811 -2.7051 180)
			(unlocked yes)
			(layer "B.Fab")
			(hide yes)
			(effects
				(font
					(size 1.016 1.016)
					(thickness 0.1524)
				)
				(justify mirror)
			)
		)
		(property "Device Type" "C402H22"
			(at -1.1811 -4.2291 180)
			(unlocked yes)
			(layer "B.Fab")
			(hide yes)
			(effects
				(font
					(size 1.016 1.016)
					(thickness 0.1524)
				)
				(justify mirror)
			)
		)
		(duplicate_pad_numbers_are_jumpers no)
		(fp_rect
			(start 0.4318 0.9525)
			(end -0.4318 -0.9525)
			(stroke
				(width 0)
				(type default)
			)
			(fill no)
			(layer "B.CrtYd")
		)
		(fp_rect
			(start 0.4318 0.9525)
			(end -0.4318 -0.9525)
			(stroke
				(width 0)
				(type default)
			)
			(fill no)
			(layer "B.Fab")
		)
		(pad "1" smd custom
			(at 0 -0.4445)
			(size 0.1524 0.1524)
			(layers "B.Cu" "B.Mask" "B.Paste")
			(net "GND")
			(options
				(clearance outline)
				(anchor circle)
			)
			(primitives
				(gr_poly
					(pts
						(arc
							(start 0.3048 0.2032)
							(mid 0.275042 0.275042)
							(end 0.2032 0.3048)
						)
						(arc
							(start -0.2032 0.3048)
							(mid -0.275042 0.275042)
							(end -0.3048 0.2032)
						)
						(arc
							(start -0.3048 -0.2032)
							(mid -0.275042 -0.275042)
							(end -0.2032 -0.3048)
						)
						(arc
							(start 0.2032 -0.3048)
							(mid 0.275042 -0.275042)
							(end 0.3048 -0.2032)
						)
					)
					(width 0)
					(fill yes)
				)
			)
		)
		(pad "2" smd custom
			(at 0 0.4445)
			(size 0.1524 0.1524)
			(layers "B.Cu" "B.Mask" "B.Paste")
			(net "P1V2_STBY")
			(options
				(clearance outline)
				(anchor circle)
			)
			(primitives
				(gr_poly
					(pts
						(arc
							(start 0.3048 0.2032)
							(mid 0.275042 0.275042)
							(end 0.2032 0.3048)
						)
						(arc
							(start -0.2032 0.3048)
							(mid -0.275042 0.275042)
							(end -0.3048 0.2032)
						)
						(arc
							(start -0.3048 -0.2032)
							(mid -0.275042 -0.275042)
							(end -0.2032 -0.3048)
						)
						(arc
							(start 0.2032 -0.3048)
							(mid 0.275042 -0.275042)
							(end 0.3048 -0.2032)
						)
					)
					(width 0)
					(fill yes)
				)
			)
		)
	)
	(footprint ""
		(layer "B.Cu")
		(at 30.549342 -126.760986 180)
		(property "Reference" "R716"
			(at 0 0 0)
			(layer "B.SilkS")
			(hide yes)
			(effects
				(font
					(size 1.27 1.27)
				)
				(justify mirror)
			)
		)
		(property "Value" "10KR2F-2-GP"
			(at -0.064008 -3.993896 180)
			(unlocked yes)
			(layer "B.Fab")
			(hide yes)
			(effects
				(font
					(size 1.016 1.016)
					(thickness 0.1524)
				)
				(justify mirror)
			)
		)
		(property "Device Type" "R402H16"
			(at -0.064008 -5.517896 180)
			(unlocked yes)
			(layer "B.Fab")
			(hide yes)
			(effects
				(font
					(size 1.016 1.016)
					(thickness 0.1524)
				)
				(justify mirror)
			)
		)
		(duplicate_pad_numbers_are_jumpers no)
		(fp_line
			(start 0.508 -0.9398)
			(end 0.508 0.9398)
			(stroke
				(width 0.1524)
				(type default)
			)
			(layer "B.SilkS")
		)
		(fp_line
			(start -0.508 -0.9398)
			(end 0.508 -0.9398)
			(stroke
				(width 0.1524)
				(type default)
			)
			(layer "B.SilkS")
		)
		(fp_rect
			(start 0.508 0.9398)
			(end -0.508 -0.9398)
			(stroke
				(width 0)
				(type default)
			)
			(fill no)
			(layer "B.CrtYd")
		)
		(fp_rect
			(start 0.508 0.9398)
			(end -0.508 -0.9398)
			(stroke
				(width 0)
				(type default)
			)
			(fill no)
			(layer "B.Fab")
		)
		(pad "1" smd custom
			(at 0 -0.4445)
			(size 0.1397 0.1397)
			(layers "B.Cu" "B.Mask" "B.Paste")
			(net "SYS_RESET_N_OUT")
			(options
				(clearance outline)
				(anchor circle)
			)
			(primitives
				(gr_poly
					(pts
						(arc
							(start -0.1778 0.2794)
							(mid -0.249642 0.249642)
							(end -0.2794 0.1778)
						)
						(arc
							(start -0.2794 -0.1778)
							(mid -0.249642 -0.249642)
							(end -0.1778 -0.2794)
						)
						(arc
							(start 0.1778 -0.2794)
							(mid 0.249642 -0.249642)
							(end 0.2794 -0.1778)
						)
						(arc
							(start 0.2794 0.1778)
							(mid 0.249642 0.249642)
							(end 0.1778 0.2794)
						)
					)
					(width 0)
					(fill yes)
				)
			)
		)
		(pad "2" smd custom
			(at 0 0.4445)
			(size 0.1397 0.1397)
			(layers "B.Cu" "B.Mask" "B.Paste")
			(net "GND")
			(options
				(clearance outline)
				(anchor circle)
			)
			(primitives
				(gr_poly
					(pts
						(arc
							(start -0.1778 0.2794)
							(mid -0.249642 0.249642)
							(end -0.2794 0.1778)
						)
						(arc
							(start -0.2794 -0.1778)
							(mid -0.249642 -0.249642)
							(end -0.1778 -0.2794)
						)
						(arc
							(start 0.1778 -0.2794)
							(mid 0.249642 -0.249642)
							(end 0.2794 -0.1778)
						)
						(arc
							(start 0.2794 0.1778)
							(mid 0.249642 0.249642)
							(end 0.1778 0.2794)
						)
					)
					(width 0)
					(fill yes)
				)
			)
		)
	)
	(footprint ""
		(layer "B.Cu")
		(at 175.22825 -119.541544 180)
		(property "Reference" "C633"
			(at 0 0 0)
			(layer "B.SilkS")
			(hide yes)
			(effects
				(font
					(size 1.27 1.27)
				)
				(justify mirror)
			)
		)
		(property "Value" "SCD1U16V2KX-3GP"
			(at -1.1811 -2.7051 180)
			(unlocked yes)
			(layer "B.Fab")
			(hide yes)
			(effects
				(font
					(size 1.016 1.016)
					(thickness 0.1524)
				)
				(justify mirror)
			)
		)
		(property "Device Type" "C402H22"
			(at -1.1811 -4.2291 180)
			(unlocked yes)
			(layer "B.Fab")
			(hide yes)
			(effects
				(font
					(size 1.016 1.016)
					(thickness 0.1524)
				)
				(justify mirror)
			)
		)
		(duplicate_pad_numbers_are_jumpers no)
		(fp_rect
			(start 0.4318 0.9525)
			(end -0.4318 -0.9525)
			(stroke
				(width 0)
				(type default)
			)
			(fill no)
			(layer "B.CrtYd")
		)
		(fp_rect
			(start 0.4318 0.9525)
			(end -0.4318 -0.9525)
			(stroke
				(width 0)
				(type default)
			)
			(fill no)
			(layer "B.Fab")
		)
		(pad "1" smd custom
			(at 0 -0.4445)
			(size 0.1524 0.1524)
			(layers "B.Cu" "B.Mask" "B.Paste")
			(net "P1V8_STBY")
			(options
				(clearance outline)
				(anchor circle)
			)
			(primitives
				(gr_poly
					(pts
						(arc
							(start 0.3048 0.2032)
							(mid 0.275042 0.275042)
							(end 0.2032 0.3048)
						)
						(arc
							(start -0.2032 0.3048)
							(mid -0.275042 0.275042)
							(end -0.3048 0.2032)
						)
						(arc
							(start -0.3048 -0.2032)
							(mid -0.275042 -0.275042)
							(end -0.2032 -0.3048)
						)
						(arc
							(start 0.2032 -0.3048)
							(mid 0.275042 -0.275042)
							(end 0.3048 -0.2032)
						)
					)
					(width 0)
					(fill yes)
				)
			)
		)
		(pad "2" smd custom
			(at 0 0.4445)
			(size 0.1524 0.1524)
			(layers "B.Cu" "B.Mask" "B.Paste")
			(net "GND")
			(options
				(clearance outline)
				(anchor circle)
			)
			(primitives
				(gr_poly
					(pts
						(arc
							(start 0.3048 0.2032)
							(mid 0.275042 0.275042)
							(end 0.2032 0.3048)
						)
						(arc
							(start -0.2032 0.3048)
							(mid -0.275042 0.275042)
							(end -0.3048 0.2032)
						)
						(arc
							(start -0.3048 -0.2032)
							(mid -0.275042 -0.275042)
							(end -0.2032 -0.3048)
						)
						(arc
							(start 0.2032 -0.3048)
							(mid 0.275042 -0.275042)
							(end 0.3048 -0.2032)
						)
					)
					(width 0)
					(fill yes)
				)
			)
		)
	)
	(footprint ""
		(layer "B.Cu")
		(at 43.63212 -125.991874)
		(property "Reference" "TP84"
			(at 0 0 0)
			(layer "B.SilkS")
			(hide yes)
			(effects
				(font
					(size 1.27 1.27)
				)
				(justify mirror)
			)
		)
		(property "Value" "TPAD28-2-GP"
			(at 0.0127 -1.6637 0)
			(unlocked yes)
			(layer "B.Fab")
			(hide yes)
			(effects
				(font
					(size 1.016 1.016)
					(thickness 0.1524)
				)
				(justify mirror)
			)
		)
		(property "Device Type" "TPAD28"
			(at 0.0127 -3.1877 0)
			(unlocked yes)
			(layer "B.Fab")
			(hide yes)
			(effects
				(font
					(size 1.016 1.016)
					(thickness 0.1524)
				)
				(justify mirror)
			)
		)
		(duplicate_pad_numbers_are_jumpers no)
		(fp_poly
			(pts
				(arc
					(start 0.3556 0)
					(mid -0.3556 0)
					(end 0.3556 0)
				)
			)
			(stroke
				(width 0)
				(type default)
			)
			(fill no)
			(layer "B.CrtYd")
		)
		(fp_poly
			(pts
				(arc
					(start 0.6096 0)
					(mid -0.6096 0)
					(end 0.6096 0)
				)
			)
			(stroke
				(width 0)
				(type default)
			)
			(fill no)
			(layer "B.Fab")
		)
		(pad "1" smd circle
			(at 0 0 180)
			(size 0.7112 0.7112)
			(layers "B.Cu" "B.Mask" "B.Paste")
			(net "FM_BMC_RESET_N")
		)
	)
	(footprint ""
		(layer "B.Cu")
		(at 193.13525 -133.831584 180)
		(property "Reference" "C612"
			(at 0 0 0)
			(layer "B.SilkS")
			(hide yes)
			(effects
				(font
					(size 1.27 1.27)
				)
				(justify mirror)
			)
		)
		(property "Value" "SCD1U16V2KX-3GP"
			(at -1.1811 -2.7051 180)
			(unlocked yes)
			(layer "B.Fab")
			(hide yes)
			(effects
				(font
					(size 1.016 1.016)
					(thickness 0.1524)
				)
				(justify mirror)
			)
		)
		(property "Device Type" "C402H22"
			(at -1.1811 -4.2291 180)
			(unlocked yes)
			(layer "B.Fab")
			(hide yes)
			(effects
				(font
					(size 1.016 1.016)
					(thickness 0.1524)
				)
				(justify mirror)
			)
		)
		(duplicate_pad_numbers_are_jumpers no)
		(fp_rect
			(start 0.4318 0.9525)
			(end -0.4318 -0.9525)
			(stroke
				(width 0)
				(type default)
			)
			(fill no)
			(layer "B.CrtYd")
		)
		(fp_rect
			(start 0.4318 0.9525)
			(end -0.4318 -0.9525)
			(stroke
				(width 0)
				(type default)
			)
			(fill no)
			(layer "B.Fab")
		)
		(pad "1" smd custom
			(at 0 -0.4445)
			(size 0.1524 0.1524)
			(layers "B.Cu" "B.Mask" "B.Paste")
			(net "P3V3_M2")
			(options
				(clearance outline)
				(anchor circle)
			)
			(primitives
				(gr_poly
					(pts
						(arc
							(start 0.3048 0.2032)
							(mid 0.275042 0.275042)
							(end 0.2032 0.3048)
						)
						(arc
							(start -0.2032 0.3048)
							(mid -0.275042 0.275042)
							(end -0.3048 0.2032)
						)
						(arc
							(start -0.3048 -0.2032)
							(mid -0.275042 -0.275042)
							(end -0.2032 -0.3048)
						)
						(arc
							(start 0.2032 -0.3048)
							(mid 0.275042 -0.275042)
							(end 0.3048 -0.2032)
						)
					)
					(width 0)
					(fill yes)
				)
			)
		)
		(pad "2" smd custom
			(at 0 0.4445)
			(size 0.1524 0.1524)
			(layers "B.Cu" "B.Mask" "B.Paste")
			(net "GND")
			(options
				(clearance outline)
				(anchor circle)
			)
			(primitives
				(gr_poly
					(pts
						(arc
							(start 0.3048 0.2032)
							(mid 0.275042 0.275042)
							(end 0.2032 0.3048)
						)
						(arc
							(start -0.2032 0.3048)
							(mid -0.275042 0.275042)
							(end -0.3048 0.2032)
						)
						(arc
							(start -0.3048 -0.2032)
							(mid -0.275042 -0.275042)
							(end -0.2032 -0.3048)
						)
						(arc
							(start 0.2032 -0.3048)
							(mid 0.275042 -0.275042)
							(end 0.3048 -0.2032)
						)
					)
					(width 0)
					(fill yes)
				)
			)
		)
	)
	(footprint ""
		(layer "B.Cu")
		(at 42.418 -131.7752 180)
		(property "Reference" "R284"
			(at 0 0 0)
			(layer "B.SilkS")
			(hide yes)
			(effects
				(font
					(size 1.27 1.27)
				)
				(justify mirror)
			)
		)
		(property "Value" "33R2F-3-GP"
			(at -0.064008 -3.993896 180)
			(unlocked yes)
			(layer "B.Fab")
			(hide yes)
			(effects
				(font
					(size 1.016 1.016)
					(thickness 0.1524)
				)
				(justify mirror)
			)
		)
		(property "Device Type" "R402H16"
			(at -0.064008 -5.517896 180)
			(unlocked yes)
			(layer "B.Fab")
			(hide yes)
			(effects
				(font
					(size 1.016 1.016)
					(thickness 0.1524)
				)
				(justify mirror)
			)
		)
		(duplicate_pad_numbers_are_jumpers no)
		(fp_line
			(start 0.508 -0.9398)
			(end 0.508 0.9398)
			(stroke
				(width 0.1524)
				(type default)
			)
			(layer "B.SilkS")
		)
		(fp_line
			(start -0.508 -0.9398)
			(end 0.508 -0.9398)
			(stroke
				(width 0.1524)
				(type default)
			)
			(layer "B.SilkS")
		)
		(fp_rect
			(start 0.508 0.9398)
			(end -0.508 -0.9398)
			(stroke
				(width 0)
				(type default)
			)
			(fill no)
			(layer "B.CrtYd")
		)
		(fp_rect
			(start 0.508 0.9398)
			(end -0.508 -0.9398)
			(stroke
				(width 0)
				(type default)
			)
			(fill no)
			(layer "B.Fab")
		)
		(pad "1" smd custom
			(at 0 -0.4445)
			(size 0.1397 0.1397)
			(layers "B.Cu" "B.Mask" "B.Paste")
			(net "BMC_SPI_MOSI_R")
			(options
				(clearance outline)
				(anchor circle)
			)
			(primitives
				(gr_poly
					(pts
						(arc
							(start -0.1778 0.2794)
							(mid -0.249642 0.249642)
							(end -0.2794 0.1778)
						)
						(arc
							(start -0.2794 -0.1778)
							(mid -0.249642 -0.249642)
							(end -0.1778 -0.2794)
						)
						(arc
							(start 0.1778 -0.2794)
							(mid 0.249642 -0.249642)
							(end 0.2794 -0.1778)
						)
						(arc
							(start 0.2794 0.1778)
							(mid 0.249642 0.249642)
							(end 0.1778 0.2794)
						)
					)
					(width 0)
					(fill yes)
				)
			)
		)
		(pad "2" smd custom
			(at 0 0.4445)
			(size 0.1397 0.1397)
			(layers "B.Cu" "B.Mask" "B.Paste")
			(net "BMC_SPI_MOSI")
			(options
				(clearance outline)
				(anchor circle)
			)
			(primitives
				(gr_poly
					(pts
						(arc
							(start -0.1778 0.2794)
							(mid -0.249642 0.249642)
							(end -0.2794 0.1778)
						)
						(arc
							(start -0.2794 -0.1778)
							(mid -0.249642 -0.249642)
							(end -0.1778 -0.2794)
						)
						(arc
							(start 0.1778 -0.2794)
							(mid 0.249642 -0.249642)
							(end 0.2794 -0.1778)
						)
						(arc
							(start 0.2794 0.1778)
							(mid 0.249642 0.249642)
							(end 0.1778 0.2794)
						)
					)
					(width 0)
					(fill yes)
				)
			)
		)
	)
	(footprint ""
		(layer "B.Cu")
		(at 52.1462 -163.1442 90)
		(property "Reference" "R819"
			(at 0 0 90)
			(layer "B.SilkS")
			(hide yes)
			(effects
				(font
					(size 1.27 1.27)
				)
				(justify mirror)
			)
		)
		(property "Value" "1K4R2F-1-GP"
			(at -0.064008 -3.993896 90)
			(unlocked yes)
			(layer "B.Fab")
			(hide yes)
			(effects
				(font
					(size 1.016 1.016)
					(thickness 0.1524)
				)
				(justify mirror)
			)
		)
		(property "Device Type" "R402H16"
			(at -0.064008 -5.517896 90)
			(unlocked yes)
			(layer "B.Fab")
			(hide yes)
			(effects
				(font
					(size 1.016 1.016)
					(thickness 0.1524)
				)
				(justify mirror)
			)
		)
		(duplicate_pad_numbers_are_jumpers no)
		(fp_line
			(start 0.508 -0.9398)
			(end 0.508 0.9398)
			(stroke
				(width 0.1524)
				(type default)
			)
			(layer "B.SilkS")
		)
		(fp_line
			(start -0.508 -0.9398)
			(end 0.508 -0.9398)
			(stroke
				(width 0.1524)
				(type default)
			)
			(layer "B.SilkS")
		)
		(fp_rect
			(start 0.508 0.9398)
			(end -0.508 -0.9398)
			(stroke
				(width 0)
				(type default)
			)
			(fill no)
			(layer "B.CrtYd")
		)
		(fp_rect
			(start 0.508 0.9398)
			(end -0.508 -0.9398)
			(stroke
				(width 0)
				(type default)
			)
			(fill no)
			(layer "B.Fab")
		)
		(pad "1" smd custom
			(at 0 -0.4445 270)
			(size 0.1397 0.1397)
			(layers "B.Cu" "B.Mask" "B.Paste")
			(net "P3V3_M2")
			(options
				(clearance outline)
				(anchor circle)
			)
			(primitives
				(gr_poly
					(pts
						(arc
							(start -0.1778 0.2794)
							(mid -0.249642 0.249642)
							(end -0.2794 0.1778)
						)
						(arc
							(start -0.2794 -0.1778)
							(mid -0.249642 -0.249642)
							(end -0.1778 -0.2794)
						)
						(arc
							(start 0.1778 -0.2794)
							(mid 0.249642 -0.249642)
							(end 0.2794 -0.1778)
						)
						(arc
							(start 0.2794 0.1778)
							(mid 0.249642 0.249642)
							(end 0.1778 0.2794)
						)
					)
					(width 0)
					(fill yes)
				)
			)
		)
		(pad "2" smd custom
			(at 0 0.4445 270)
			(size 0.1397 0.1397)
			(layers "B.Cu" "B.Mask" "B.Paste")
			(net "ADC_P3V3_M2")
			(options
				(clearance outline)
				(anchor circle)
			)
			(primitives
				(gr_poly
					(pts
						(arc
							(start -0.1778 0.2794)
							(mid -0.249642 0.249642)
							(end -0.2794 0.1778)
						)
						(arc
							(start -0.2794 -0.1778)
							(mid -0.249642 -0.249642)
							(end -0.1778 -0.2794)
						)
						(arc
							(start 0.1778 -0.2794)
							(mid 0.249642 -0.249642)
							(end 0.2794 -0.1778)
						)
						(arc
							(start 0.2794 0.1778)
							(mid 0.249642 0.249642)
							(end 0.1778 0.2794)
						)
					)
					(width 0)
					(fill yes)
				)
			)
		)
	)
	(footprint ""
		(layer "B.Cu")
		(at 50.292 -132.08)
		(property "Reference" "C110"
			(at 0 0 0)
			(layer "B.SilkS")
			(hide yes)
			(effects
				(font
					(size 1.27 1.27)
				)
				(justify mirror)
			)
		)
		(property "Value" "SC1U16V3KX-5GP"
			(at 0 -2.8194 0)
			(unlocked yes)
			(layer "B.Fab")
			(hide yes)
			(effects
				(font
					(size 1.016 1.016)
					(thickness 0.1524)
				)
				(justify mirror)
			)
		)
		(property "Device Type" "C603H36"
			(at 0 -4.3434 0)
			(unlocked yes)
			(layer "B.Fab")
			(hide yes)
			(effects
				(font
					(size 1.016 1.016)
					(thickness 0.1524)
				)
				(justify mirror)
			)
		)
		(duplicate_pad_numbers_are_jumpers no)
		(fp_line
			(start -0.508 0)
			(end 0.508 0)
			(stroke
				(width 0.2032)
				(type default)
			)
			(layer "B.SilkS")
		)
		(fp_rect
			(start 0.5842 1.3335)
			(end -0.5842 -1.3335)
			(stroke
				(width 0)
				(type default)
			)
			(fill no)
			(layer "B.CrtYd")
		)
		(fp_rect
			(start 0.5842 1.3335)
			(end -0.5842 -1.3335)
			(stroke
				(width 0)
				(type default)
			)
			(fill no)
			(layer "B.Fab")
		)
		(pad "1" smd custom
			(at 0 -0.762 180)
			(size 0.2159 0.2159)
			(layers "B.Cu" "B.Mask" "B.Paste")
			(net "P1V15_STBY")
			(options
				(clearance outline)
				(anchor circle)
			)
			(primitives
				(gr_poly
					(pts
						(arc
							(start -0.3302 0.4318)
							(mid -0.402042 0.402042)
							(end -0.4318 0.3302)
						)
						(arc
							(start -0.4318 -0.3302)
							(mid -0.402042 -0.402042)
							(end -0.3302 -0.4318)
						)
						(arc
							(start 0.3302 -0.4318)
							(mid 0.402042 -0.402042)
							(end 0.4318 -0.3302)
						)
						(arc
							(start 0.4318 0.3302)
							(mid 0.402042 0.402042)
							(end 0.3302 0.4318)
						)
					)
					(width 0)
					(fill yes)
				)
			)
		)
		(pad "2" smd custom
			(at 0 0.762 180)
			(size 0.2159 0.2159)
			(layers "B.Cu" "B.Mask" "B.Paste")
			(net "GND")
			(options
				(clearance outline)
				(anchor circle)
			)
			(primitives
				(gr_poly
					(pts
						(arc
							(start -0.3302 0.4318)
							(mid -0.402042 0.402042)
							(end -0.4318 0.3302)
						)
						(arc
							(start -0.4318 -0.3302)
							(mid -0.402042 -0.402042)
							(end -0.3302 -0.4318)
						)
						(arc
							(start 0.3302 -0.4318)
							(mid 0.402042 -0.402042)
							(end 0.4318 -0.3302)
						)
						(arc
							(start 0.4318 0.3302)
							(mid 0.402042 0.402042)
							(end 0.3302 0.4318)
						)
					)
					(width 0)
					(fill yes)
				)
			)
		)
	)
	(footprint ""
		(layer "B.Cu")
		(at 92.71 -132.1054 -90)
		(property "Reference" "U100"
			(at 0 0 90)
			(layer "B.SilkS")
			(hide yes)
			(effects
				(font
					(size 1.27 1.27)
				)
				(justify mirror)
			)
		)
		(property "Value" "SNLVC1G126DCKR-GP"
			(at 2.3368 -8.6868 270)
			(unlocked yes)
			(layer "B.Fab")
			(hide yes)
			(effects
				(font
					(size 1.016 1.016)
					(thickness 0.1524)
				)
				(justify mirror)
			)
		)
		(property "Device Type" "SC70-5H44"
			(at 2.3114 -10.414 270)
			(unlocked yes)
			(layer "B.Fab")
			(hide yes)
			(effects
				(font
					(size 1.016 1.016)
					(thickness 0.1524)
				)
				(justify mirror)
			)
		)
		(duplicate_pad_numbers_are_jumpers no)
		(fp_line
			(start -1.27 1.7018)
			(end 1.27 1.7018)
			(stroke
				(width 0.1524)
				(type default)
			)
			(layer "B.SilkS")
		)
		(fp_line
			(start 1.27 1.7018)
			(end 1.27 -1.7018)
			(stroke
				(width 0.1524)
				(type default)
			)
			(layer "B.SilkS")
		)
		(fp_line
			(start -1.27 -1.7018)
			(end -1.27 1.7018)
			(stroke
				(width 0.1524)
				(type default)
			)
			(layer "B.SilkS")
		)
		(fp_line
			(start 1.27 -1.7018)
			(end -1.27 -1.7018)
			(stroke
				(width 0.1524)
				(type default)
			)
			(layer "B.SilkS")
		)
		(fp_line
			(start -1.3843 -1.8034)
			(end -1.3843 -1.1176)
			(stroke
				(width 0.3302)
				(type default)
			)
			(layer "B.SilkS")
		)
		(fp_line
			(start -0.6604 -1.8034)
			(end -1.3843 -1.8034)
			(stroke
				(width 0.3302)
				(type default)
			)
			(layer "B.SilkS")
		)
		(fp_rect
			(start 1.524 1.9558)
			(end -1.524 -1.9558)
			(stroke
				(width 0)
				(type default)
			)
			(fill no)
			(layer "B.CrtYd")
		)
		(fp_poly
			(pts
				(xy 1.524 -1.9558) (xy -1.524 -1.9558) (xy -1.524 1.9558) (xy 1.524 1.9558)
			)
			(stroke
				(width 0)
				(type default)
			)
			(fill no)
			(layer "B.Fab")
		)
		(pad "1" smd rect
			(at -0.65024 -0.8255 90)
			(size 0.4064 1.2192)
			(layers "B.Cu" "B.Mask" "B.Paste")
			(net "DEBUG_CARD_PRSNT")
		)
		(pad "2" smd rect
			(at 0 -0.8255 90)
			(size 0.4064 1.2192)
			(layers "B.Cu" "B.Mask" "B.Paste")
			(net "DEBUG_UART_IOM_TX")
		)
		(pad "3" smd rect
			(at 0.65024 -0.8255 90)
			(size 0.4064 1.2192)
			(layers "B.Cu" "B.Mask" "B.Paste")
			(net "GND")
		)
		(pad "4" smd rect
			(at 0.65024 0.8255 90)
			(size 0.4064 1.2192)
			(layers "B.Cu" "B.Mask" "B.Paste")
			(net "UART_IOM_TX")
		)
		(pad "5" smd rect
			(at -0.65024 0.8255 90)
			(size 0.4064 1.2192)
			(layers "B.Cu" "B.Mask" "B.Paste")
			(net "P3V3_STBY")
		)
	)
	(footprint ""
		(layer "B.Cu")
		(at 83.67649 -56.358536)
		(property "Reference" "C512"
			(at 0 0 0)
			(layer "B.SilkS")
			(hide yes)
			(effects
				(font
					(size 1.27 1.27)
				)
				(justify mirror)
			)
		)
		(property "Value" "SC10U16V5KX-7-GP-U"
			(at 0.076454 -6.1214 0)
			(unlocked yes)
			(layer "B.Fab")
			(hide yes)
			(effects
				(font
					(size 1.016 1.016)
					(thickness 0.1524)
				)
				(justify mirror)
			)
		)
		(property "Device Type" "C805H58"
			(at 0.0762 -8.1534 0)
			(unlocked yes)
			(layer "B.Fab")
			(hide yes)
			(effects
				(font
					(size 1.016 1.016)
					(thickness 0.1524)
				)
				(justify mirror)
			)
		)
		(duplicate_pad_numbers_are_jumpers no)
		(fp_line
			(start -0.635 0)
			(end 0.635 0)
			(stroke
				(width 0.508)
				(type default)
			)
			(layer "B.SilkS")
		)
		(fp_rect
			(start 0.9652 1.778)
			(end -0.9652 -1.778)
			(stroke
				(width 0)
				(type default)
			)
			(fill no)
			(layer "B.CrtYd")
		)
		(fp_poly
			(pts
				(xy 0.9652 -1.778) (xy -0.9652 -1.778) (xy -0.9652 1.778) (xy 0.9652 1.778)
			)
			(stroke
				(width 0)
				(type default)
			)
			(fill no)
			(layer "B.Fab")
		)
		(pad "1" smd rect
			(at 0 -0.9652 180)
			(size 1.397 1.143)
			(layers "B.Cu" "B.Mask" "B.Paste")
			(net "P3V3_STBY")
		)
		(pad "2" smd rect
			(at 0 0.9652 180)
			(size 1.397 1.143)
			(layers "B.Cu" "B.Mask" "B.Paste")
			(net "GND")
		)
	)
	(footprint ""
		(layer "B.Cu")
		(at 80.965802 -57.02046 180)
		(property "Reference" "C187"
			(at 0 0 0)
			(layer "B.SilkS")
			(hide yes)
			(effects
				(font
					(size 1.27 1.27)
				)
				(justify mirror)
			)
		)
		(property "Value" "SC10U6D3V5KX-4GP"
			(at 0.0762 -6.1214 180)
			(unlocked yes)
			(layer "B.Fab")
			(hide yes)
			(effects
				(font
					(size 1.016 1.016)
					(thickness 0.1524)
				)
				(justify mirror)
			)
		)
		(property "Device Type" "C805H58"
			(at 0.0762 -8.1534 180)
			(unlocked yes)
			(layer "B.Fab")
			(hide yes)
			(effects
				(font
					(size 1.016 1.016)
					(thickness 0.1524)
				)
				(justify mirror)
			)
		)
		(duplicate_pad_numbers_are_jumpers no)
		(fp_line
			(start -0.635 0)
			(end 0.635 0)
			(stroke
				(width 0.508)
				(type default)
			)
			(layer "B.SilkS")
		)
		(fp_rect
			(start 0.9652 1.778)
			(end -0.9652 -1.778)
			(stroke
				(width 0)
				(type default)
			)
			(fill no)
			(layer "B.CrtYd")
		)
		(fp_poly
			(pts
				(xy 0.9652 -1.778) (xy -0.9652 -1.778) (xy -0.9652 1.778) (xy 0.9652 1.778)
			)
			(stroke
				(width 0)
				(type default)
			)
			(fill no)
			(layer "B.Fab")
		)
		(pad "1" smd rect
			(at 0 -0.9652)
			(size 1.397 1.143)
			(layers "B.Cu" "B.Mask" "B.Paste")
			(net "P3V3")
		)
		(pad "2" smd rect
			(at 0 0.9652)
			(size 1.397 1.143)
			(layers "B.Cu" "B.Mask" "B.Paste")
			(net "GND")
		)
	)
	(footprint ""
		(layer "B.Cu")
		(at 87.401908 -150.612602 180)
		(property "Reference" "R97"
			(at 0 0 0)
			(layer "B.SilkS")
			(hide yes)
			(effects
				(font
					(size 1.27 1.27)
				)
				(justify mirror)
			)
		)
		(property "Value" "0R2J-2-GP"
			(at -0.064008 -3.993896 180)
			(unlocked yes)
			(layer "B.Fab")
			(hide yes)
			(effects
				(font
					(size 1.016 1.016)
					(thickness 0.1524)
				)
				(justify mirror)
			)
		)
		(property "Device Type" "R402H16"
			(at -0.064008 -5.517896 180)
			(unlocked yes)
			(layer "B.Fab")
			(hide yes)
			(effects
				(font
					(size 1.016 1.016)
					(thickness 0.1524)
				)
				(justify mirror)
			)
		)
		(duplicate_pad_numbers_are_jumpers no)
		(fp_line
			(start 0.508 -0.9398)
			(end 0.508 0.9398)
			(stroke
				(width 0.1524)
				(type default)
			)
			(layer "B.SilkS")
		)
		(fp_line
			(start -0.508 -0.9398)
			(end 0.508 -0.9398)
			(stroke
				(width 0.1524)
				(type default)
			)
			(layer "B.SilkS")
		)
		(fp_rect
			(start 0.508 0.9398)
			(end -0.508 -0.9398)
			(stroke
				(width 0)
				(type default)
			)
			(fill no)
			(layer "B.CrtYd")
		)
		(fp_rect
			(start 0.508 0.9398)
			(end -0.508 -0.9398)
			(stroke
				(width 0)
				(type default)
			)
			(fill no)
			(layer "B.Fab")
		)
		(pad "1" smd custom
			(at 0 -0.4445)
			(size 0.1397 0.1397)
			(layers "B.Cu" "B.Mask" "B.Paste")
			(net "I2C_BMC_COMP_SDA_OUT")
			(options
				(clearance outline)
				(anchor circle)
			)
			(primitives
				(gr_poly
					(pts
						(arc
							(start -0.1778 0.2794)
							(mid -0.249642 0.249642)
							(end -0.2794 0.1778)
						)
						(arc
							(start -0.2794 -0.1778)
							(mid -0.249642 -0.249642)
							(end -0.1778 -0.2794)
						)
						(arc
							(start 0.1778 -0.2794)
							(mid 0.249642 -0.249642)
							(end 0.2794 -0.1778)
						)
						(arc
							(start 0.2794 0.1778)
							(mid 0.249642 0.249642)
							(end 0.1778 0.2794)
						)
					)
					(width 0)
					(fill yes)
				)
			)
		)
		(pad "2" smd custom
			(at 0 0.4445)
			(size 0.1397 0.1397)
			(layers "B.Cu" "B.Mask" "B.Paste")
			(net "I2C_BMC_COMP_SDA_R")
			(options
				(clearance outline)
				(anchor circle)
			)
			(primitives
				(gr_poly
					(pts
						(arc
							(start -0.1778 0.2794)
							(mid -0.249642 0.249642)
							(end -0.2794 0.1778)
						)
						(arc
							(start -0.2794 -0.1778)
							(mid -0.249642 -0.249642)
							(end -0.1778 -0.2794)
						)
						(arc
							(start 0.1778 -0.2794)
							(mid 0.249642 -0.249642)
							(end 0.2794 -0.1778)
						)
						(arc
							(start 0.2794 0.1778)
							(mid 0.249642 0.249642)
							(end 0.1778 0.2794)
						)
					)
					(width 0)
					(fill yes)
				)
			)
		)
	)
	(footprint ""
		(layer "B.Cu")
		(at 26.079196 -136.099296 90)
		(property "Reference" "C64"
			(at 0 0 90)
			(layer "B.SilkS")
			(hide yes)
			(effects
				(font
					(size 1.27 1.27)
				)
				(justify mirror)
			)
		)
		(property "Value" "SC1U16V3KX-5GP"
			(at 0 -2.8194 90)
			(unlocked yes)
			(layer "B.Fab")
			(hide yes)
			(effects
				(font
					(size 1.016 1.016)
					(thickness 0.1524)
				)
				(justify mirror)
			)
		)
		(property "Device Type" "C603H36"
			(at 0 -4.3434 90)
			(unlocked yes)
			(layer "B.Fab")
			(hide yes)
			(effects
				(font
					(size 1.016 1.016)
					(thickness 0.1524)
				)
				(justify mirror)
			)
		)
		(duplicate_pad_numbers_are_jumpers no)
		(fp_line
			(start -0.508 0)
			(end 0.508 0)
			(stroke
				(width 0.2032)
				(type default)
			)
			(layer "B.SilkS")
		)
		(fp_rect
			(start 0.5842 1.3335)
			(end -0.5842 -1.3335)
			(stroke
				(width 0)
				(type default)
			)
			(fill no)
			(layer "B.CrtYd")
		)
		(fp_rect
			(start 0.5842 1.3335)
			(end -0.5842 -1.3335)
			(stroke
				(width 0)
				(type default)
			)
			(fill no)
			(layer "B.Fab")
		)
		(pad "1" smd custom
			(at 0 -0.762 270)
			(size 0.2159 0.2159)
			(layers "B.Cu" "B.Mask" "B.Paste")
			(net "P2V5_STBY")
			(options
				(clearance outline)
				(anchor circle)
			)
			(primitives
				(gr_poly
					(pts
						(arc
							(start -0.3302 0.4318)
							(mid -0.402042 0.402042)
							(end -0.4318 0.3302)
						)
						(arc
							(start -0.4318 -0.3302)
							(mid -0.402042 -0.402042)
							(end -0.3302 -0.4318)
						)
						(arc
							(start 0.3302 -0.4318)
							(mid 0.402042 -0.402042)
							(end 0.4318 -0.3302)
						)
						(arc
							(start 0.4318 0.3302)
							(mid 0.402042 0.402042)
							(end 0.3302 0.4318)
						)
					)
					(width 0)
					(fill yes)
				)
			)
		)
		(pad "2" smd custom
			(at 0 0.762 270)
			(size 0.2159 0.2159)
			(layers "B.Cu" "B.Mask" "B.Paste")
			(net "GND")
			(options
				(clearance outline)
				(anchor circle)
			)
			(primitives
				(gr_poly
					(pts
						(arc
							(start -0.3302 0.4318)
							(mid -0.402042 0.402042)
							(end -0.4318 0.3302)
						)
						(arc
							(start -0.4318 -0.3302)
							(mid -0.402042 -0.402042)
							(end -0.3302 -0.4318)
						)
						(arc
							(start 0.3302 -0.4318)
							(mid 0.402042 -0.402042)
							(end 0.4318 -0.3302)
						)
						(arc
							(start 0.4318 0.3302)
							(mid 0.402042 0.402042)
							(end 0.3302 0.4318)
						)
					)
					(width 0)
					(fill yes)
				)
			)
		)
	)
	(footprint ""
		(layer "B.Cu")
		(at 52.0192 -124.1552)
		(property "Reference" "R403"
			(at 0 0 0)
			(layer "B.SilkS")
			(hide yes)
			(effects
				(font
					(size 1.27 1.27)
				)
				(justify mirror)
			)
		)
		(property "Value" "0R2J-2-GP"
			(at -0.064008 -3.993896 0)
			(unlocked yes)
			(layer "B.Fab")
			(hide yes)
			(effects
				(font
					(size 1.016 1.016)
					(thickness 0.1524)
				)
				(justify mirror)
			)
		)
		(property "Device Type" "R402H16"
			(at -0.064008 -5.517896 0)
			(unlocked yes)
			(layer "B.Fab")
			(hide yes)
			(effects
				(font
					(size 1.016 1.016)
					(thickness 0.1524)
				)
				(justify mirror)
			)
		)
		(duplicate_pad_numbers_are_jumpers no)
		(fp_line
			(start -0.508 -0.9398)
			(end 0.508 -0.9398)
			(stroke
				(width 0.1524)
				(type default)
			)
			(layer "B.SilkS")
		)
		(fp_line
			(start 0.508 -0.9398)
			(end 0.508 0.9398)
			(stroke
				(width 0.1524)
				(type default)
			)
			(layer "B.SilkS")
		)
		(fp_rect
			(start 0.508 0.9398)
			(end -0.508 -0.9398)
			(stroke
				(width 0)
				(type default)
			)
			(fill no)
			(layer "B.CrtYd")
		)
		(fp_rect
			(start 0.508 0.9398)
			(end -0.508 -0.9398)
			(stroke
				(width 0)
				(type default)
			)
			(fill no)
			(layer "B.Fab")
		)
		(pad "1" smd custom
			(at 0 -0.4445 180)
			(size 0.1397 0.1397)
			(layers "B.Cu" "B.Mask" "B.Paste")
			(net "M2_1_ALERT#_R")
			(options
				(clearance outline)
				(anchor circle)
			)
			(primitives
				(gr_poly
					(pts
						(arc
							(start -0.1778 0.2794)
							(mid -0.249642 0.249642)
							(end -0.2794 0.1778)
						)
						(arc
							(start -0.2794 -0.1778)
							(mid -0.249642 -0.249642)
							(end -0.1778 -0.2794)
						)
						(arc
							(start 0.1778 -0.2794)
							(mid 0.249642 -0.249642)
							(end 0.2794 -0.1778)
						)
						(arc
							(start 0.2794 0.1778)
							(mid 0.249642 0.249642)
							(end 0.1778 0.2794)
						)
					)
					(width 0)
					(fill yes)
				)
			)
		)
		(pad "2" smd custom
			(at 0 0.4445 180)
			(size 0.1397 0.1397)
			(layers "B.Cu" "B.Mask" "B.Paste")
			(net "M2_1_ALERT#")
			(options
				(clearance outline)
				(anchor circle)
			)
			(primitives
				(gr_poly
					(pts
						(arc
							(start -0.1778 0.2794)
							(mid -0.249642 0.249642)
							(end -0.2794 0.1778)
						)
						(arc
							(start -0.2794 -0.1778)
							(mid -0.249642 -0.249642)
							(end -0.1778 -0.2794)
						)
						(arc
							(start 0.1778 -0.2794)
							(mid 0.249642 -0.249642)
							(end 0.2794 -0.1778)
						)
						(arc
							(start 0.2794 0.1778)
							(mid 0.249642 0.249642)
							(end 0.1778 0.2794)
						)
					)
					(width 0)
					(fill yes)
				)
			)
		)
	)
	(footprint ""
		(layer "B.Cu")
		(at 79.248 -168.91 180)
		(property "Reference" "R452"
			(at 0 0 0)
			(layer "B.SilkS")
			(hide yes)
			(effects
				(font
					(size 1.27 1.27)
				)
				(justify mirror)
			)
		)
		(property "Value" "0R2J-2-GP"
			(at -0.064008 -3.993896 180)
			(unlocked yes)
			(layer "B.Fab")
			(hide yes)
			(effects
				(font
					(size 1.016 1.016)
					(thickness 0.1524)
				)
				(justify mirror)
			)
		)
		(property "Device Type" "R402H16"
			(at -0.064008 -5.517896 180)
			(unlocked yes)
			(layer "B.Fab")
			(hide yes)
			(effects
				(font
					(size 1.016 1.016)
					(thickness 0.1524)
				)
				(justify mirror)
			)
		)
		(duplicate_pad_numbers_are_jumpers no)
		(fp_line
			(start 0.508 -0.9398)
			(end 0.508 0.9398)
			(stroke
				(width 0.1524)
				(type default)
			)
			(layer "B.SilkS")
		)
		(fp_line
			(start -0.508 -0.9398)
			(end 0.508 -0.9398)
			(stroke
				(width 0.1524)
				(type default)
			)
			(layer "B.SilkS")
		)
		(fp_rect
			(start 0.508 0.9398)
			(end -0.508 -0.9398)
			(stroke
				(width 0)
				(type default)
			)
			(fill no)
			(layer "B.CrtYd")
		)
		(fp_rect
			(start 0.508 0.9398)
			(end -0.508 -0.9398)
			(stroke
				(width 0)
				(type default)
			)
			(fill no)
			(layer "B.Fab")
		)
		(pad "1" smd custom
			(at 0 -0.4445)
			(size 0.1397 0.1397)
			(layers "B.Cu" "B.Mask" "B.Paste")
			(net "UART_SDB_TX_R")
			(options
				(clearance outline)
				(anchor circle)
			)
			(primitives
				(gr_poly
					(pts
						(arc
							(start -0.1778 0.2794)
							(mid -0.249642 0.249642)
							(end -0.2794 0.1778)
						)
						(arc
							(start -0.2794 -0.1778)
							(mid -0.249642 -0.249642)
							(end -0.1778 -0.2794)
						)
						(arc
							(start 0.1778 -0.2794)
							(mid 0.249642 -0.249642)
							(end 0.2794 -0.1778)
						)
						(arc
							(start 0.2794 0.1778)
							(mid 0.249642 0.249642)
							(end 0.1778 0.2794)
						)
					)
					(width 0)
					(fill yes)
				)
			)
		)
		(pad "2" smd custom
			(at 0 0.4445)
			(size 0.1397 0.1397)
			(layers "B.Cu" "B.Mask" "B.Paste")
			(net "UART_SDB_TX")
			(options
				(clearance outline)
				(anchor circle)
			)
			(primitives
				(gr_poly
					(pts
						(arc
							(start -0.1778 0.2794)
							(mid -0.249642 0.249642)
							(end -0.2794 0.1778)
						)
						(arc
							(start -0.2794 -0.1778)
							(mid -0.249642 -0.249642)
							(end -0.1778 -0.2794)
						)
						(arc
							(start 0.1778 -0.2794)
							(mid 0.249642 -0.249642)
							(end 0.2794 -0.1778)
						)
						(arc
							(start 0.2794 0.1778)
							(mid 0.249642 0.249642)
							(end 0.1778 0.2794)
						)
					)
					(width 0)
					(fill yes)
				)
			)
		)
	)
	(footprint ""
		(layer "B.Cu")
		(at 50.419 -124.333 90)
		(property "Reference" "R406"
			(at 0 0 90)
			(layer "B.SilkS")
			(hide yes)
			(effects
				(font
					(size 1.27 1.27)
				)
				(justify mirror)
			)
		)
		(property "Value" "0R2J-2-GP"
			(at -0.064008 -3.993896 90)
			(unlocked yes)
			(layer "B.Fab")
			(hide yes)
			(effects
				(font
					(size 1.016 1.016)
					(thickness 0.1524)
				)
				(justify mirror)
			)
		)
		(property "Device Type" "R402H16"
			(at -0.064008 -5.517896 90)
			(unlocked yes)
			(layer "B.Fab")
			(hide yes)
			(effects
				(font
					(size 1.016 1.016)
					(thickness 0.1524)
				)
				(justify mirror)
			)
		)
		(duplicate_pad_numbers_are_jumpers no)
		(fp_line
			(start 0.508 -0.9398)
			(end 0.508 0.9398)
			(stroke
				(width 0.1524)
				(type default)
			)
			(layer "B.SilkS")
		)
		(fp_line
			(start -0.508 -0.9398)
			(end 0.508 -0.9398)
			(stroke
				(width 0.1524)
				(type default)
			)
			(layer "B.SilkS")
		)
		(fp_rect
			(start 0.508 0.9398)
			(end -0.508 -0.9398)
			(stroke
				(width 0)
				(type default)
			)
			(fill no)
			(layer "B.CrtYd")
		)
		(fp_rect
			(start 0.508 0.9398)
			(end -0.508 -0.9398)
			(stroke
				(width 0)
				(type default)
			)
			(fill no)
			(layer "B.Fab")
		)
		(pad "1" smd custom
			(at 0 -0.4445 270)
			(size 0.1397 0.1397)
			(layers "B.Cu" "B.Mask" "B.Paste")
			(net "M2_2_ALERT#_R")
			(options
				(clearance outline)
				(anchor circle)
			)
			(primitives
				(gr_poly
					(pts
						(arc
							(start -0.1778 0.2794)
							(mid -0.249642 0.249642)
							(end -0.2794 0.1778)
						)
						(arc
							(start -0.2794 -0.1778)
							(mid -0.249642 -0.249642)
							(end -0.1778 -0.2794)
						)
						(arc
							(start 0.1778 -0.2794)
							(mid 0.249642 -0.249642)
							(end 0.2794 -0.1778)
						)
						(arc
							(start 0.2794 0.1778)
							(mid 0.249642 0.249642)
							(end 0.1778 0.2794)
						)
					)
					(width 0)
					(fill yes)
				)
			)
		)
		(pad "2" smd custom
			(at 0 0.4445 270)
			(size 0.1397 0.1397)
			(layers "B.Cu" "B.Mask" "B.Paste")
			(net "M2_2_ALERT#")
			(options
				(clearance outline)
				(anchor circle)
			)
			(primitives
				(gr_poly
					(pts
						(arc
							(start -0.1778 0.2794)
							(mid -0.249642 0.249642)
							(end -0.2794 0.1778)
						)
						(arc
							(start -0.2794 -0.1778)
							(mid -0.249642 -0.249642)
							(end -0.1778 -0.2794)
						)
						(arc
							(start 0.1778 -0.2794)
							(mid 0.249642 -0.249642)
							(end 0.2794 -0.1778)
						)
						(arc
							(start 0.2794 0.1778)
							(mid 0.249642 0.249642)
							(end 0.1778 0.2794)
						)
					)
					(width 0)
					(fill yes)
				)
			)
		)
	)
	(footprint ""
		(layer "B.Cu")
		(at 44.141898 -149.135338 90)
		(property "Reference" "R143"
			(at 0 0 90)
			(layer "B.SilkS")
			(hide yes)
			(effects
				(font
					(size 1.27 1.27)
				)
				(justify mirror)
			)
		)
		(property "Value" "1KR2D-1-GP"
			(at -0.064008 -3.993896 90)
			(unlocked yes)
			(layer "B.Fab")
			(hide yes)
			(effects
				(font
					(size 1.016 1.016)
					(thickness 0.1524)
				)
				(justify mirror)
			)
		)
		(property "Device Type" "R402H16"
			(at -0.064008 -5.517896 90)
			(unlocked yes)
			(layer "B.Fab")
			(hide yes)
			(effects
				(font
					(size 1.016 1.016)
					(thickness 0.1524)
				)
				(justify mirror)
			)
		)
		(duplicate_pad_numbers_are_jumpers no)
		(fp_line
			(start 0.508 -0.9398)
			(end 0.508 0.9398)
			(stroke
				(width 0.1524)
				(type default)
			)
			(layer "B.SilkS")
		)
		(fp_line
			(start -0.508 -0.9398)
			(end 0.508 -0.9398)
			(stroke
				(width 0.1524)
				(type default)
			)
			(layer "B.SilkS")
		)
		(fp_rect
			(start 0.508 0.9398)
			(end -0.508 -0.9398)
			(stroke
				(width 0)
				(type default)
			)
			(fill no)
			(layer "B.CrtYd")
		)
		(fp_rect
			(start 0.508 0.9398)
			(end -0.508 -0.9398)
			(stroke
				(width 0)
				(type default)
			)
			(fill no)
			(layer "B.Fab")
		)
		(pad "1" smd custom
			(at 0 -0.4445 270)
			(size 0.1397 0.1397)
			(layers "B.Cu" "B.Mask" "B.Paste")
			(net "DDR_VREF")
			(options
				(clearance outline)
				(anchor circle)
			)
			(primitives
				(gr_poly
					(pts
						(arc
							(start -0.1778 0.2794)
							(mid -0.249642 0.249642)
							(end -0.2794 0.1778)
						)
						(arc
							(start -0.2794 -0.1778)
							(mid -0.249642 -0.249642)
							(end -0.1778 -0.2794)
						)
						(arc
							(start 0.1778 -0.2794)
							(mid 0.249642 -0.249642)
							(end 0.2794 -0.1778)
						)
						(arc
							(start 0.2794 0.1778)
							(mid 0.249642 0.249642)
							(end 0.1778 0.2794)
						)
					)
					(width 0)
					(fill yes)
				)
			)
		)
		(pad "2" smd custom
			(at 0 0.4445 270)
			(size 0.1397 0.1397)
			(layers "B.Cu" "B.Mask" "B.Paste")
			(net "GND")
			(options
				(clearance outline)
				(anchor circle)
			)
			(primitives
				(gr_poly
					(pts
						(arc
							(start -0.1778 0.2794)
							(mid -0.249642 0.249642)
							(end -0.2794 0.1778)
						)
						(arc
							(start -0.2794 -0.1778)
							(mid -0.249642 -0.249642)
							(end -0.1778 -0.2794)
						)
						(arc
							(start 0.1778 -0.2794)
							(mid 0.249642 -0.249642)
							(end 0.2794 -0.1778)
						)
						(arc
							(start 0.2794 0.1778)
							(mid 0.249642 0.249642)
							(end 0.1778 0.2794)
						)
					)
					(width 0)
					(fill yes)
				)
			)
		)
	)
	(footprint ""
		(layer "B.Cu")
		(at 216.386918 -97.327974 90)
		(property "Reference" "G10"
			(at 0 0 90)
			(layer "B.SilkS")
			(hide yes)
			(effects
				(font
					(size 1.27 1.27)
				)
				(justify mirror)
			)
		)
		(property "Value" "COPPER-CLOSE-GP-U"
			(at -0.0762 -2.8702 90)
			(unlocked yes)
			(layer "B.Fab")
			(hide yes)
			(effects
				(font
					(size 1.016 1.016)
					(thickness 0.1524)
				)
				(justify mirror)
			)
		)
		(property "Device Type" "CON2C-U"
			(at -0.0762 -4.3942 90)
			(unlocked yes)
			(layer "B.Fab")
			(hide yes)
			(effects
				(font
					(size 1.016 1.016)
					(thickness 0.1524)
				)
				(justify mirror)
			)
		)
		(duplicate_pad_numbers_are_jumpers no)
		(fp_rect
			(start 0.9398 0.9652)
			(end -0.9398 -0.9652)
			(stroke
				(width 0)
				(type default)
			)
			(fill no)
			(layer "B.CrtYd")
		)
		(fp_rect
			(start 0.9398 0.9652)
			(end -0.9398 -0.9652)
			(stroke
				(width 0)
				(type default)
			)
			(fill no)
			(layer "B.Fab")
		)
		(pad "1" smd custom
			(at 0 -0.5334 270)
			(size 0.17145 0.17145)
			(layers "B.Cu" "B.Mask" "B.Paste")
			(net "AGND_P3V3_M2")
			(options
				(clearance outline)
				(anchor circle)
			)
			(primitives
				(gr_poly
					(pts
						(xy -0.127 -0.3429) (xy -0.127 -0.1651) (xy -0.635 0.3429) (xy 0.635 0.3429) (xy 0.127 -0.1651)
						(xy 0.127 -0.3429)
					)
					(width 0)
					(fill yes)
				)
			)
		)
		(pad "2" smd custom
			(at 0 0.5334 270)
			(size 0.17145 0.17145)
			(layers "B.Cu" "B.Mask" "B.Paste")
			(net "GND")
			(options
				(clearance outline)
				(anchor circle)
			)
			(primitives
				(gr_poly
					(pts
						(xy -0.635 -0.3429) (xy -0.127 0.1651) (xy -0.127 0.3429) (xy 0.127 0.3429) (xy 0.127 0.1651)
						(xy 0.635 -0.3429)
					)
					(width 0)
					(fill yes)
				)
			)
		)
	)
	(footprint ""
		(layer "B.Cu")
		(at 25.343104 -142.282164 -90)
		(property "Reference" "R222"
			(at 0 0 90)
			(layer "B.SilkS")
			(hide yes)
			(effects
				(font
					(size 1.27 1.27)
				)
				(justify mirror)
			)
		)
		(property "Value" "120R2F-GP"
			(at -0.064008 -3.993896 270)
			(unlocked yes)
			(layer "B.Fab")
			(hide yes)
			(effects
				(font
					(size 1.016 1.016)
					(thickness 0.1524)
				)
				(justify mirror)
			)
		)
		(property "Device Type" "R402H16"
			(at -0.064008 -5.517896 270)
			(unlocked yes)
			(layer "B.Fab")
			(hide yes)
			(effects
				(font
					(size 1.016 1.016)
					(thickness 0.1524)
				)
				(justify mirror)
			)
		)
		(duplicate_pad_numbers_are_jumpers no)
		(fp_line
			(start -0.508 -0.9398)
			(end 0.508 -0.9398)
			(stroke
				(width 0.1524)
				(type default)
			)
			(layer "B.SilkS")
		)
		(fp_line
			(start 0.508 -0.9398)
			(end 0.508 0.9398)
			(stroke
				(width 0.1524)
				(type default)
			)
			(layer "B.SilkS")
		)
		(fp_rect
			(start 0.508 0.9398)
			(end -0.508 -0.9398)
			(stroke
				(width 0)
				(type default)
			)
			(fill no)
			(layer "B.CrtYd")
		)
		(fp_rect
			(start 0.508 0.9398)
			(end -0.508 -0.9398)
			(stroke
				(width 0)
				(type default)
			)
			(fill no)
			(layer "B.Fab")
		)
		(pad "1" smd custom
			(at 0 -0.4445 90)
			(size 0.1397 0.1397)
			(layers "B.Cu" "B.Mask" "B.Paste")
			(net "GND")
			(options
				(clearance outline)
				(anchor circle)
			)
			(primitives
				(gr_poly
					(pts
						(arc
							(start -0.1778 0.2794)
							(mid -0.249642 0.249642)
							(end -0.2794 0.1778)
						)
						(arc
							(start -0.2794 -0.1778)
							(mid -0.249642 -0.249642)
							(end -0.1778 -0.2794)
						)
						(arc
							(start 0.1778 -0.2794)
							(mid 0.249642 -0.249642)
							(end 0.2794 -0.1778)
						)
						(arc
							(start 0.2794 0.1778)
							(mid 0.249642 0.249642)
							(end 0.1778 0.2794)
						)
					)
					(width 0)
					(fill yes)
				)
			)
		)
		(pad "2" smd custom
			(at 0 0.4445 90)
			(size 0.1397 0.1397)
			(layers "B.Cu" "B.Mask" "B.Paste")
			(net "MEMRASN")
			(options
				(clearance outline)
				(anchor circle)
			)
			(primitives
				(gr_poly
					(pts
						(arc
							(start -0.1778 0.2794)
							(mid -0.249642 0.249642)
							(end -0.2794 0.1778)
						)
						(arc
							(start -0.2794 -0.1778)
							(mid -0.249642 -0.249642)
							(end -0.1778 -0.2794)
						)
						(arc
							(start 0.1778 -0.2794)
							(mid 0.249642 -0.249642)
							(end 0.2794 -0.1778)
						)
						(arc
							(start 0.2794 0.1778)
							(mid 0.249642 0.249642)
							(end 0.1778 0.2794)
						)
					)
					(width 0)
					(fill yes)
				)
			)
		)
	)
	(footprint ""
		(layer "B.Cu")
		(at 46.9392 -123.077224)
		(property "Reference" "TP203"
			(at 0 0 0)
			(layer "B.SilkS")
			(hide yes)
			(effects
				(font
					(size 1.27 1.27)
				)
				(justify mirror)
			)
		)
		(property "Value" "TPAD28-2-GP"
			(at 0.0127 -1.6637 0)
			(unlocked yes)
			(layer "B.Fab")
			(hide yes)
			(effects
				(font
					(size 1.016 1.016)
					(thickness 0.1524)
				)
				(justify mirror)
			)
		)
		(property "Device Type" "TPAD28"
			(at 0.0127 -3.1877 0)
			(unlocked yes)
			(layer "B.Fab")
			(hide yes)
			(effects
				(font
					(size 1.016 1.016)
					(thickness 0.1524)
				)
				(justify mirror)
			)
		)
		(duplicate_pad_numbers_are_jumpers no)
		(fp_poly
			(pts
				(arc
					(start 0.3556 0)
					(mid -0.3556 0)
					(end 0.3556 0)
				)
			)
			(stroke
				(width 0)
				(type default)
			)
			(fill no)
			(layer "B.CrtYd")
		)
		(fp_poly
			(pts
				(arc
					(start 0.6096 0)
					(mid -0.6096 0)
					(end 0.6096 0)
				)
			)
			(stroke
				(width 0)
				(type default)
			)
			(fill no)
			(layer "B.Fab")
		)
		(pad "1" smd circle
			(at 0 0 180)
			(size 0.7112 0.7112)
			(layers "B.Cu" "B.Mask" "B.Paste")
			(net "BMC_SMB2_CLK_TP")
		)
	)
	(footprint ""
		(layer "B.Cu")
		(at 219.325444 -40.51046 90)
		(property "Reference" "C158"
			(at 0 0 90)
			(layer "B.SilkS")
			(hide yes)
			(effects
				(font
					(size 1.27 1.27)
				)
				(justify mirror)
			)
		)
		(property "Value" "SCD1U50V3KX-GP"
			(at 0 -2.8194 90)
			(unlocked yes)
			(layer "B.Fab")
			(hide yes)
			(effects
				(font
					(size 1.016 1.016)
					(thickness 0.1524)
				)
				(justify mirror)
			)
		)
		(property "Device Type" "C603H36"
			(at 0 -4.3434 90)
			(unlocked yes)
			(layer "B.Fab")
			(hide yes)
			(effects
				(font
					(size 1.016 1.016)
					(thickness 0.1524)
				)
				(justify mirror)
			)
		)
		(duplicate_pad_numbers_are_jumpers no)
		(fp_line
			(start -0.508 0)
			(end 0.508 0)
			(stroke
				(width 0.2032)
				(type default)
			)
			(layer "B.SilkS")
		)
		(fp_rect
			(start 0.5842 1.3335)
			(end -0.5842 -1.3335)
			(stroke
				(width 0)
				(type default)
			)
			(fill no)
			(layer "B.CrtYd")
		)
		(fp_rect
			(start 0.5842 1.3335)
			(end -0.5842 -1.3335)
			(stroke
				(width 0)
				(type default)
			)
			(fill no)
			(layer "B.Fab")
		)
		(pad "1" smd custom
			(at 0 -0.762 270)
			(size 0.2159 0.2159)
			(layers "B.Cu" "B.Mask" "B.Paste")
			(net "P5V_VBST_RC")
			(options
				(clearance outline)
				(anchor circle)
			)
			(primitives
				(gr_poly
					(pts
						(arc
							(start -0.3302 0.4318)
							(mid -0.402042 0.402042)
							(end -0.4318 0.3302)
						)
						(arc
							(start -0.4318 -0.3302)
							(mid -0.402042 -0.402042)
							(end -0.3302 -0.4318)
						)
						(arc
							(start 0.3302 -0.4318)
							(mid 0.402042 -0.402042)
							(end 0.4318 -0.3302)
						)
						(arc
							(start 0.4318 0.3302)
							(mid 0.402042 0.402042)
							(end 0.3302 0.4318)
						)
					)
					(width 0)
					(fill yes)
				)
			)
		)
		(pad "2" smd custom
			(at 0 0.762 270)
			(size 0.2159 0.2159)
			(layers "B.Cu" "B.Mask" "B.Paste")
			(net "P5V_LL")
			(options
				(clearance outline)
				(anchor circle)
			)
			(primitives
				(gr_poly
					(pts
						(arc
							(start -0.3302 0.4318)
							(mid -0.402042 0.402042)
							(end -0.4318 0.3302)
						)
						(arc
							(start -0.4318 -0.3302)
							(mid -0.402042 -0.402042)
							(end -0.3302 -0.4318)
						)
						(arc
							(start 0.3302 -0.4318)
							(mid 0.402042 -0.402042)
							(end 0.4318 -0.3302)
						)
						(arc
							(start 0.4318 0.3302)
							(mid 0.402042 0.402042)
							(end 0.3302 0.4318)
						)
					)
					(width 0)
					(fill yes)
				)
			)
		)
	)
	(footprint ""
		(layer "B.Cu")
		(at 96.25711 -155.095702 45)
		(property "Reference" "TP6"
			(at 0 0 45)
			(layer "B.SilkS")
			(hide yes)
			(effects
				(font
					(size 1.27 1.27)
				)
				(justify mirror)
			)
		)
		(property "Value" "TPAD28-2-GP"
			(at 0.012752 -1.663607 45)
			(unlocked yes)
			(layer "B.Fab")
			(hide yes)
			(effects
				(font
					(size 1.016 1.016)
					(thickness 0.1524)
				)
				(justify mirror)
			)
		)
		(property "Device Type" "TPAD28"
			(at 0.012752 -3.187736 45)
			(unlocked yes)
			(layer "B.Fab")
			(hide yes)
			(effects
				(font
					(size 1.016 1.016)
					(thickness 0.1524)
				)
				(justify mirror)
			)
		)
		(duplicate_pad_numbers_are_jumpers no)
		(fp_poly
			(pts
				(arc
					(start 0.251447 0.251447)
					(mid -0.251447 -0.251447)
					(end 0.251447 0.251447)
				)
			)
			(stroke
				(width 0)
				(type default)
			)
			(fill no)
			(layer "B.CrtYd")
		)
		(fp_poly
			(pts
				(arc
					(start 0.431052 0.431052)
					(mid -0.431052 -0.431052)
					(end 0.431052 0.431052)
				)
			)
			(stroke
				(width 0)
				(type default)
			)
			(fill no)
			(layer "B.Fab")
		)
		(pad "1" smd circle
			(at 0 0 225)
			(size 0.7112 0.7112)
			(layers "B.Cu" "B.Mask" "B.Paste")
			(net "TP_USB_SDA")
		)
	)
	(footprint ""
		(layer "B.Cu")
		(at 29.075888 -126.31547 90)
		(property "Reference" "R783"
			(at 0 0 90)
			(layer "B.SilkS")
			(hide yes)
			(effects
				(font
					(size 1.27 1.27)
				)
				(justify mirror)
			)
		)
		(property "Value" "10KR2F-2-GP"
			(at -0.064008 -3.993896 90)
			(unlocked yes)
			(layer "B.Fab")
			(hide yes)
			(effects
				(font
					(size 1.016 1.016)
					(thickness 0.1524)
				)
				(justify mirror)
			)
		)
		(property "Device Type" "R402H16"
			(at -0.064008 -5.517896 90)
			(unlocked yes)
			(layer "B.Fab")
			(hide yes)
			(effects
				(font
					(size 1.016 1.016)
					(thickness 0.1524)
				)
				(justify mirror)
			)
		)
		(duplicate_pad_numbers_are_jumpers no)
		(fp_line
			(start 0.508 -0.9398)
			(end 0.508 0.9398)
			(stroke
				(width 0.1524)
				(type default)
			)
			(layer "B.SilkS")
		)
		(fp_line
			(start -0.508 -0.9398)
			(end 0.508 -0.9398)
			(stroke
				(width 0.1524)
				(type default)
			)
			(layer "B.SilkS")
		)
		(fp_rect
			(start 0.508 0.9398)
			(end -0.508 -0.9398)
			(stroke
				(width 0)
				(type default)
			)
			(fill no)
			(layer "B.CrtYd")
		)
		(fp_rect
			(start 0.508 0.9398)
			(end -0.508 -0.9398)
			(stroke
				(width 0)
				(type default)
			)
			(fill no)
			(layer "B.Fab")
		)
		(pad "1" smd custom
			(at 0 -0.4445 270)
			(size 0.1397 0.1397)
			(layers "B.Cu" "B.Mask" "B.Paste")
			(net "P3V3_STBY")
			(options
				(clearance outline)
				(anchor circle)
			)
			(primitives
				(gr_poly
					(pts
						(arc
							(start -0.1778 0.2794)
							(mid -0.249642 0.249642)
							(end -0.2794 0.1778)
						)
						(arc
							(start -0.2794 -0.1778)
							(mid -0.249642 -0.249642)
							(end -0.1778 -0.2794)
						)
						(arc
							(start 0.1778 -0.2794)
							(mid 0.249642 -0.249642)
							(end 0.2794 -0.1778)
						)
						(arc
							(start 0.2794 0.1778)
							(mid 0.249642 0.249642)
							(end 0.1778 0.2794)
						)
					)
					(width 0)
					(fill yes)
				)
			)
		)
		(pad "2" smd custom
			(at 0 0.4445 270)
			(size 0.1397 0.1397)
			(layers "B.Cu" "B.Mask" "B.Paste")
			(net "SYS_RESET_N_OUT")
			(options
				(clearance outline)
				(anchor circle)
			)
			(primitives
				(gr_poly
					(pts
						(arc
							(start -0.1778 0.2794)
							(mid -0.249642 0.249642)
							(end -0.2794 0.1778)
						)
						(arc
							(start -0.2794 -0.1778)
							(mid -0.249642 -0.249642)
							(end -0.1778 -0.2794)
						)
						(arc
							(start 0.1778 -0.2794)
							(mid 0.249642 -0.249642)
							(end 0.2794 -0.1778)
						)
						(arc
							(start 0.2794 0.1778)
							(mid 0.249642 0.249642)
							(end 0.1778 0.2794)
						)
					)
					(width 0)
					(fill yes)
				)
			)
		)
	)
	(footprint ""
		(layer "B.Cu")
		(at 10.1854 -142.4686 90)
		(property "Reference" "R211"
			(at 0 0 90)
			(layer "B.SilkS")
			(hide yes)
			(effects
				(font
					(size 1.27 1.27)
				)
				(justify mirror)
			)
		)
		(property "Value" "120R2F-GP"
			(at -0.064008 -3.993896 90)
			(unlocked yes)
			(layer "B.Fab")
			(hide yes)
			(effects
				(font
					(size 1.016 1.016)
					(thickness 0.1524)
				)
				(justify mirror)
			)
		)
		(property "Device Type" "R402H16"
			(at -0.064008 -5.517896 90)
			(unlocked yes)
			(layer "B.Fab")
			(hide yes)
			(effects
				(font
					(size 1.016 1.016)
					(thickness 0.1524)
				)
				(justify mirror)
			)
		)
		(duplicate_pad_numbers_are_jumpers no)
		(fp_line
			(start 0.508 -0.9398)
			(end 0.508 0.9398)
			(stroke
				(width 0.1524)
				(type default)
			)
			(layer "B.SilkS")
		)
		(fp_line
			(start -0.508 -0.9398)
			(end 0.508 -0.9398)
			(stroke
				(width 0.1524)
				(type default)
			)
			(layer "B.SilkS")
		)
		(fp_rect
			(start 0.508 0.9398)
			(end -0.508 -0.9398)
			(stroke
				(width 0)
				(type default)
			)
			(fill no)
			(layer "B.CrtYd")
		)
		(fp_rect
			(start 0.508 0.9398)
			(end -0.508 -0.9398)
			(stroke
				(width 0)
				(type default)
			)
			(fill no)
			(layer "B.Fab")
		)
		(pad "1" smd custom
			(at 0 -0.4445 270)
			(size 0.1397 0.1397)
			(layers "B.Cu" "B.Mask" "B.Paste")
			(net "GND")
			(options
				(clearance outline)
				(anchor circle)
			)
			(primitives
				(gr_poly
					(pts
						(arc
							(start -0.1778 0.2794)
							(mid -0.249642 0.249642)
							(end -0.2794 0.1778)
						)
						(arc
							(start -0.2794 -0.1778)
							(mid -0.249642 -0.249642)
							(end -0.1778 -0.2794)
						)
						(arc
							(start 0.1778 -0.2794)
							(mid 0.249642 -0.249642)
							(end 0.2794 -0.1778)
						)
						(arc
							(start 0.2794 0.1778)
							(mid 0.249642 0.249642)
							(end 0.1778 0.2794)
						)
					)
					(width 0)
					(fill yes)
				)
			)
		)
		(pad "2" smd custom
			(at 0 0.4445 270)
			(size 0.1397 0.1397)
			(layers "B.Cu" "B.Mask" "B.Paste")
			(net "MEMODT")
			(options
				(clearance outline)
				(anchor circle)
			)
			(primitives
				(gr_poly
					(pts
						(arc
							(start -0.1778 0.2794)
							(mid -0.249642 0.249642)
							(end -0.2794 0.1778)
						)
						(arc
							(start -0.2794 -0.1778)
							(mid -0.249642 -0.249642)
							(end -0.1778 -0.2794)
						)
						(arc
							(start 0.1778 -0.2794)
							(mid 0.249642 -0.249642)
							(end 0.2794 -0.1778)
						)
						(arc
							(start 0.2794 0.1778)
							(mid 0.249642 0.249642)
							(end 0.1778 0.2794)
						)
					)
					(width 0)
					(fill yes)
				)
			)
		)
	)
	(footprint ""
		(layer "B.Cu")
		(at 82.5754 -59.7916 -90)
		(property "Reference" "C29"
			(at 0 0 90)
			(layer "B.SilkS")
			(hide yes)
			(effects
				(font
					(size 1.27 1.27)
				)
				(justify mirror)
			)
		)
		(property "Value" "SC2D2U25V5KX-2-GP"
			(at 0.0762 -6.1214 270)
			(unlocked yes)
			(layer "B.Fab")
			(hide yes)
			(effects
				(font
					(size 1.016 1.016)
					(thickness 0.1524)
				)
				(justify mirror)
			)
		)
		(property "Device Type" "C805H54"
			(at 0.0762 -8.1534 270)
			(unlocked yes)
			(layer "B.Fab")
			(hide yes)
			(effects
				(font
					(size 1.016 1.016)
					(thickness 0.1524)
				)
				(justify mirror)
			)
		)
		(duplicate_pad_numbers_are_jumpers no)
		(fp_line
			(start -0.635 0)
			(end 0.635 0)
			(stroke
				(width 0.508)
				(type default)
			)
			(layer "B.SilkS")
		)
		(fp_rect
			(start 0.9652 1.778)
			(end -0.9652 -1.778)
			(stroke
				(width 0)
				(type default)
			)
			(fill no)
			(layer "B.CrtYd")
		)
		(fp_poly
			(pts
				(xy 0.9652 -1.778) (xy -0.9652 -1.778) (xy -0.9652 1.778) (xy 0.9652 1.778)
			)
			(stroke
				(width 0)
				(type default)
			)
			(fill no)
			(layer "B.Fab")
		)
		(pad "1" smd rect
			(at 0 -0.9652 90)
			(size 1.397 1.143)
			(layers "B.Cu" "B.Mask" "B.Paste")
			(net "P3V3_STBY")
		)
		(pad "2" smd rect
			(at 0 0.9652 90)
			(size 1.397 1.143)
			(layers "B.Cu" "B.Mask" "B.Paste")
			(net "GND")
		)
	)
	(footprint ""
		(layer "B.Cu")
		(at 121.245122 -9.504426 180)
		(property "Reference" "CA1"
			(at 0 0 0)
			(layer "B.SilkS")
			(hide yes)
			(effects
				(font
					(size 1.27 1.27)
				)
				(justify mirror)
			)
		)
		(property "Value" "SC2D2U25V5KX-2-GP"
			(at 0.0762 -6.1214 180)
			(unlocked yes)
			(layer "B.Fab")
			(hide yes)
			(effects
				(font
					(size 1.016 1.016)
					(thickness 0.1524)
				)
				(justify mirror)
			)
		)
		(property "Device Type" "C805H54"
			(at 0.0762 -8.1534 180)
			(unlocked yes)
			(layer "B.Fab")
			(hide yes)
			(effects
				(font
					(size 1.016 1.016)
					(thickness 0.1524)
				)
				(justify mirror)
			)
		)
		(duplicate_pad_numbers_are_jumpers no)
		(fp_line
			(start -0.635 0)
			(end 0.635 0)
			(stroke
				(width 0.508)
				(type default)
			)
			(layer "B.SilkS")
		)
		(fp_rect
			(start 0.9652 1.778)
			(end -0.9652 -1.778)
			(stroke
				(width 0)
				(type default)
			)
			(fill no)
			(layer "B.CrtYd")
		)
		(fp_poly
			(pts
				(xy 0.9652 -1.778) (xy -0.9652 -1.778) (xy -0.9652 1.778) (xy 0.9652 1.778)
			)
			(stroke
				(width 0)
				(type default)
			)
			(fill no)
			(layer "B.Fab")
		)
		(pad "1" smd rect
			(at 0 -0.9652)
			(size 1.397 1.143)
			(layers "B.Cu" "B.Mask" "B.Paste")
			(net "P12V_IOM_PGOOD")
		)
		(pad "2" smd rect
			(at 0 0.9652)
			(size 1.397 1.143)
			(layers "B.Cu" "B.Mask" "B.Paste")
			(net "GND")
		)
	)
	(footprint ""
		(layer "B.Cu")
		(at 48.913034 -142.03934 -90)
		(property "Reference" "C100"
			(at 0 0 90)
			(layer "B.SilkS")
			(hide yes)
			(effects
				(font
					(size 1.27 1.27)
				)
				(justify mirror)
			)
		)
		(property "Value" "SC1U16V3KX-5GP"
			(at 0 -2.8194 270)
			(unlocked yes)
			(layer "B.Fab")
			(hide yes)
			(effects
				(font
					(size 1.016 1.016)
					(thickness 0.1524)
				)
				(justify mirror)
			)
		)
		(property "Device Type" "C603H36"
			(at 0 -4.3434 270)
			(unlocked yes)
			(layer "B.Fab")
			(hide yes)
			(effects
				(font
					(size 1.016 1.016)
					(thickness 0.1524)
				)
				(justify mirror)
			)
		)
		(duplicate_pad_numbers_are_jumpers no)
		(fp_line
			(start -0.508 0)
			(end 0.508 0)
			(stroke
				(width 0.2032)
				(type default)
			)
			(layer "B.SilkS")
		)
		(fp_rect
			(start 0.5842 1.3335)
			(end -0.5842 -1.3335)
			(stroke
				(width 0)
				(type default)
			)
			(fill no)
			(layer "B.CrtYd")
		)
		(fp_rect
			(start 0.5842 1.3335)
			(end -0.5842 -1.3335)
			(stroke
				(width 0)
				(type default)
			)
			(fill no)
			(layer "B.Fab")
		)
		(pad "1" smd custom
			(at 0 -0.762 90)
			(size 0.2159 0.2159)
			(layers "B.Cu" "B.Mask" "B.Paste")
			(net "P3V3_STBY")
			(options
				(clearance outline)
				(anchor circle)
			)
			(primitives
				(gr_poly
					(pts
						(arc
							(start -0.3302 0.4318)
							(mid -0.402042 0.402042)
							(end -0.4318 0.3302)
						)
						(arc
							(start -0.4318 -0.3302)
							(mid -0.402042 -0.402042)
							(end -0.3302 -0.4318)
						)
						(arc
							(start 0.3302 -0.4318)
							(mid 0.402042 -0.402042)
							(end 0.4318 -0.3302)
						)
						(arc
							(start 0.4318 0.3302)
							(mid 0.402042 0.402042)
							(end 0.3302 0.4318)
						)
					)
					(width 0)
					(fill yes)
				)
			)
		)
		(pad "2" smd custom
			(at 0 0.762 90)
			(size 0.2159 0.2159)
			(layers "B.Cu" "B.Mask" "B.Paste")
			(net "GND")
			(options
				(clearance outline)
				(anchor circle)
			)
			(primitives
				(gr_poly
					(pts
						(arc
							(start -0.3302 0.4318)
							(mid -0.402042 0.402042)
							(end -0.4318 0.3302)
						)
						(arc
							(start -0.4318 -0.3302)
							(mid -0.402042 -0.402042)
							(end -0.3302 -0.4318)
						)
						(arc
							(start 0.3302 -0.4318)
							(mid 0.402042 -0.402042)
							(end 0.4318 -0.3302)
						)
						(arc
							(start 0.4318 0.3302)
							(mid 0.402042 0.402042)
							(end 0.3302 0.4318)
						)
					)
					(width 0)
					(fill yes)
				)
			)
		)
	)
	(footprint ""
		(layer "B.Cu")
		(at 20.591272 -129.074164 180)
		(property "Reference" "R252"
			(at 0 0 0)
			(layer "B.SilkS")
			(hide yes)
			(effects
				(font
					(size 1.27 1.27)
				)
				(justify mirror)
			)
		)
		(property "Value" "120R2F-GP"
			(at -0.064008 -3.993896 180)
			(unlocked yes)
			(layer "B.Fab")
			(hide yes)
			(effects
				(font
					(size 1.016 1.016)
					(thickness 0.1524)
				)
				(justify mirror)
			)
		)
		(property "Device Type" "R402H16"
			(at -0.064008 -5.517896 180)
			(unlocked yes)
			(layer "B.Fab")
			(hide yes)
			(effects
				(font
					(size 1.016 1.016)
					(thickness 0.1524)
				)
				(justify mirror)
			)
		)
		(duplicate_pad_numbers_are_jumpers no)
		(fp_line
			(start 0.508 -0.9398)
			(end 0.508 0.9398)
			(stroke
				(width 0.1524)
				(type default)
			)
			(layer "B.SilkS")
		)
		(fp_line
			(start -0.508 -0.9398)
			(end 0.508 -0.9398)
			(stroke
				(width 0.1524)
				(type default)
			)
			(layer "B.SilkS")
		)
		(fp_rect
			(start 0.508 0.9398)
			(end -0.508 -0.9398)
			(stroke
				(width 0)
				(type default)
			)
			(fill no)
			(layer "B.CrtYd")
		)
		(fp_rect
			(start 0.508 0.9398)
			(end -0.508 -0.9398)
			(stroke
				(width 0)
				(type default)
			)
			(fill no)
			(layer "B.Fab")
		)
		(pad "1" smd custom
			(at 0 -0.4445)
			(size 0.1397 0.1397)
			(layers "B.Cu" "B.Mask" "B.Paste")
			(net "GND")
			(options
				(clearance outline)
				(anchor circle)
			)
			(primitives
				(gr_poly
					(pts
						(arc
							(start -0.1778 0.2794)
							(mid -0.249642 0.249642)
							(end -0.2794 0.1778)
						)
						(arc
							(start -0.2794 -0.1778)
							(mid -0.249642 -0.249642)
							(end -0.1778 -0.2794)
						)
						(arc
							(start 0.1778 -0.2794)
							(mid 0.249642 -0.249642)
							(end 0.2794 -0.1778)
						)
						(arc
							(start 0.2794 0.1778)
							(mid 0.249642 0.249642)
							(end 0.1778 0.2794)
						)
					)
					(width 0)
					(fill yes)
				)
			)
		)
		(pad "2" smd custom
			(at 0 0.4445)
			(size 0.1397 0.1397)
			(layers "B.Cu" "B.Mask" "B.Paste")
			(net "MEMA_9")
			(options
				(clearance outline)
				(anchor circle)
			)
			(primitives
				(gr_poly
					(pts
						(arc
							(start -0.1778 0.2794)
							(mid -0.249642 0.249642)
							(end -0.2794 0.1778)
						)
						(arc
							(start -0.2794 -0.1778)
							(mid -0.249642 -0.249642)
							(end -0.1778 -0.2794)
						)
						(arc
							(start 0.1778 -0.2794)
							(mid 0.249642 -0.249642)
							(end 0.2794 -0.1778)
						)
						(arc
							(start 0.2794 0.1778)
							(mid 0.249642 0.249642)
							(end 0.1778 0.2794)
						)
					)
					(width 0)
					(fill yes)
				)
			)
		)
	)
	(footprint ""
		(layer "B.Cu")
		(at 131.97586 -19.7358 90)
		(property "Reference" "R743"
			(at 0 0 90)
			(layer "B.SilkS")
			(hide yes)
			(effects
				(font
					(size 1.27 1.27)
				)
				(justify mirror)
			)
		)
		(property "Value" "100KR2F-L1-GP"
			(at -0.064008 -3.993896 90)
			(unlocked yes)
			(layer "B.Fab")
			(hide yes)
			(effects
				(font
					(size 1.016 1.016)
					(thickness 0.1524)
				)
				(justify mirror)
			)
		)
		(property "Device Type" "R402H16"
			(at -0.064008 -5.517896 90)
			(unlocked yes)
			(layer "B.Fab")
			(hide yes)
			(effects
				(font
					(size 1.016 1.016)
					(thickness 0.1524)
				)
				(justify mirror)
			)
		)
		(duplicate_pad_numbers_are_jumpers no)
		(fp_line
			(start 0.508 -0.9398)
			(end 0.508 0.9398)
			(stroke
				(width 0.1524)
				(type default)
			)
			(layer "B.SilkS")
		)
		(fp_line
			(start -0.508 -0.9398)
			(end 0.508 -0.9398)
			(stroke
				(width 0.1524)
				(type default)
			)
			(layer "B.SilkS")
		)
		(fp_rect
			(start 0.508 0.9398)
			(end -0.508 -0.9398)
			(stroke
				(width 0)
				(type default)
			)
			(fill no)
			(layer "B.CrtYd")
		)
		(fp_rect
			(start 0.508 0.9398)
			(end -0.508 -0.9398)
			(stroke
				(width 0)
				(type default)
			)
			(fill no)
			(layer "B.Fab")
		)
		(pad "1" smd custom
			(at 0 -0.4445 270)
			(size 0.1397 0.1397)
			(layers "B.Cu" "B.Mask" "B.Paste")
			(net "P12V_IOM")
			(options
				(clearance outline)
				(anchor circle)
			)
			(primitives
				(gr_poly
					(pts
						(arc
							(start -0.1778 0.2794)
							(mid -0.249642 0.249642)
							(end -0.2794 0.1778)
						)
						(arc
							(start -0.2794 -0.1778)
							(mid -0.249642 -0.249642)
							(end -0.1778 -0.2794)
						)
						(arc
							(start 0.1778 -0.2794)
							(mid 0.249642 -0.249642)
							(end 0.2794 -0.1778)
						)
						(arc
							(start 0.2794 0.1778)
							(mid 0.249642 0.249642)
							(end 0.1778 0.2794)
						)
					)
					(width 0)
					(fill yes)
				)
			)
		)
		(pad "2" smd custom
			(at 0 0.4445 270)
			(size 0.1397 0.1397)
			(layers "B.Cu" "B.Mask" "B.Paste")
			(net "IOM_ADM1278_EN")
			(options
				(clearance outline)
				(anchor circle)
			)
			(primitives
				(gr_poly
					(pts
						(arc
							(start -0.1778 0.2794)
							(mid -0.249642 0.249642)
							(end -0.2794 0.1778)
						)
						(arc
							(start -0.2794 -0.1778)
							(mid -0.249642 -0.249642)
							(end -0.1778 -0.2794)
						)
						(arc
							(start 0.1778 -0.2794)
							(mid 0.249642 -0.249642)
							(end 0.2794 -0.1778)
						)
						(arc
							(start 0.2794 0.1778)
							(mid 0.249642 0.249642)
							(end 0.1778 0.2794)
						)
					)
					(width 0)
					(fill yes)
				)
			)
		)
	)
	(footprint ""
		(layer "B.Cu")
		(at 63.8048 -145.0594 90)
		(property "Reference" "R202"
			(at 0 0 90)
			(layer "B.SilkS")
			(hide yes)
			(effects
				(font
					(size 1.27 1.27)
				)
				(justify mirror)
			)
		)
		(property "Value" "2K2R2F-GP"
			(at -0.064008 -3.993896 90)
			(unlocked yes)
			(layer "B.Fab")
			(hide yes)
			(effects
				(font
					(size 1.016 1.016)
					(thickness 0.1524)
				)
				(justify mirror)
			)
		)
		(property "Device Type" "R402H16"
			(at -0.064008 -5.517896 90)
			(unlocked yes)
			(layer "B.Fab")
			(hide yes)
			(effects
				(font
					(size 1.016 1.016)
					(thickness 0.1524)
				)
				(justify mirror)
			)
		)
		(duplicate_pad_numbers_are_jumpers no)
		(fp_line
			(start 0.508 -0.9398)
			(end 0.508 0.9398)
			(stroke
				(width 0.1524)
				(type default)
			)
			(layer "B.SilkS")
		)
		(fp_line
			(start -0.508 -0.9398)
			(end 0.508 -0.9398)
			(stroke
				(width 0.1524)
				(type default)
			)
			(layer "B.SilkS")
		)
		(fp_rect
			(start 0.508 0.9398)
			(end -0.508 -0.9398)
			(stroke
				(width 0)
				(type default)
			)
			(fill no)
			(layer "B.CrtYd")
		)
		(fp_rect
			(start 0.508 0.9398)
			(end -0.508 -0.9398)
			(stroke
				(width 0)
				(type default)
			)
			(fill no)
			(layer "B.Fab")
		)
		(pad "1" smd custom
			(at 0 -0.4445 270)
			(size 0.1397 0.1397)
			(layers "B.Cu" "B.Mask" "B.Paste")
			(net "I2C_MEZZ_FRU_SENSOR_SDA")
			(options
				(clearance outline)
				(anchor circle)
			)
			(primitives
				(gr_poly
					(pts
						(arc
							(start -0.1778 0.2794)
							(mid -0.249642 0.249642)
							(end -0.2794 0.1778)
						)
						(arc
							(start -0.2794 -0.1778)
							(mid -0.249642 -0.249642)
							(end -0.1778 -0.2794)
						)
						(arc
							(start 0.1778 -0.2794)
							(mid 0.249642 -0.249642)
							(end 0.2794 -0.1778)
						)
						(arc
							(start 0.2794 0.1778)
							(mid 0.249642 0.249642)
							(end 0.1778 0.2794)
						)
					)
					(width 0)
					(fill yes)
				)
			)
		)
		(pad "2" smd custom
			(at 0 0.4445 270)
			(size 0.1397 0.1397)
			(layers "B.Cu" "B.Mask" "B.Paste")
			(net "P3V3_STBY")
			(options
				(clearance outline)
				(anchor circle)
			)
			(primitives
				(gr_poly
					(pts
						(arc
							(start -0.1778 0.2794)
							(mid -0.249642 0.249642)
							(end -0.2794 0.1778)
						)
						(arc
							(start -0.2794 -0.1778)
							(mid -0.249642 -0.249642)
							(end -0.1778 -0.2794)
						)
						(arc
							(start 0.1778 -0.2794)
							(mid 0.249642 -0.249642)
							(end 0.2794 -0.1778)
						)
						(arc
							(start 0.2794 0.1778)
							(mid 0.249642 0.249642)
							(end 0.1778 0.2794)
						)
					)
					(width 0)
					(fill yes)
				)
			)
		)
	)
	(footprint ""
		(layer "B.Cu")
		(at 190.46825 -133.831584 180)
		(property "Reference" "C610"
			(at 0 0 0)
			(layer "B.SilkS")
			(hide yes)
			(effects
				(font
					(size 1.27 1.27)
				)
				(justify mirror)
			)
		)
		(property "Value" "SC10U6D3V5KX-4GP"
			(at 0.0762 -6.1214 180)
			(unlocked yes)
			(layer "B.Fab")
			(hide yes)
			(effects
				(font
					(size 1.016 1.016)
					(thickness 0.1524)
				)
				(justify mirror)
			)
		)
		(property "Device Type" "C805H58"
			(at 0.0762 -8.1534 180)
			(unlocked yes)
			(layer "B.Fab")
			(hide yes)
			(effects
				(font
					(size 1.016 1.016)
					(thickness 0.1524)
				)
				(justify mirror)
			)
		)
		(duplicate_pad_numbers_are_jumpers no)
		(fp_line
			(start -0.635 0)
			(end 0.635 0)
			(stroke
				(width 0.508)
				(type default)
			)
			(layer "B.SilkS")
		)
		(fp_rect
			(start 0.9652 1.778)
			(end -0.9652 -1.778)
			(stroke
				(width 0)
				(type default)
			)
			(fill no)
			(layer "B.CrtYd")
		)
		(fp_poly
			(pts
				(xy 0.9652 -1.778) (xy -0.9652 -1.778) (xy -0.9652 1.778) (xy 0.9652 1.778)
			)
			(stroke
				(width 0)
				(type default)
			)
			(fill no)
			(layer "B.Fab")
		)
		(pad "1" smd rect
			(at 0 -0.9652)
			(size 1.397 1.143)
			(layers "B.Cu" "B.Mask" "B.Paste")
			(net "P3V3_M2")
		)
		(pad "2" smd rect
			(at 0 0.9652)
			(size 1.397 1.143)
			(layers "B.Cu" "B.Mask" "B.Paste")
			(net "GND")
		)
	)
	(footprint ""
		(layer "B.Cu")
		(at 207.094836 -99.532948)
		(property "Reference" "C632"
			(at 0 0 0)
			(layer "B.SilkS")
			(hide yes)
			(effects
				(font
					(size 1.27 1.27)
				)
				(justify mirror)
			)
		)
		(property "Value" "SCD1U16V2KX-3GP"
			(at -1.1811 -2.7051 0)
			(unlocked yes)
			(layer "B.Fab")
			(hide yes)
			(effects
				(font
					(size 1.016 1.016)
					(thickness 0.1524)
				)
				(justify mirror)
			)
		)
		(property "Device Type" "C402H22"
			(at -1.181354 -4.2291 0)
			(unlocked yes)
			(layer "B.Fab")
			(hide yes)
			(effects
				(font
					(size 1.016 1.016)
					(thickness 0.1524)
				)
				(justify mirror)
			)
		)
		(duplicate_pad_numbers_are_jumpers no)
		(fp_rect
			(start 0.4318 0.9525)
			(end -0.4318 -0.9525)
			(stroke
				(width 0)
				(type default)
			)
			(fill no)
			(layer "B.CrtYd")
		)
		(fp_rect
			(start 0.4318 0.9525)
			(end -0.4318 -0.9525)
			(stroke
				(width 0)
				(type default)
			)
			(fill no)
			(layer "B.Fab")
		)
		(pad "1" smd custom
			(at 0 -0.4445 180)
			(size 0.1524 0.1524)
			(layers "B.Cu" "B.Mask" "B.Paste")
			(net "U82_VREF2")
			(options
				(clearance outline)
				(anchor circle)
			)
			(primitives
				(gr_poly
					(pts
						(arc
							(start 0.3048 0.2032)
							(mid 0.275042 0.275042)
							(end 0.2032 0.3048)
						)
						(arc
							(start -0.2032 0.3048)
							(mid -0.275042 0.275042)
							(end -0.3048 0.2032)
						)
						(arc
							(start -0.3048 -0.2032)
							(mid -0.275042 -0.275042)
							(end -0.2032 -0.3048)
						)
						(arc
							(start 0.2032 -0.3048)
							(mid 0.275042 -0.275042)
							(end 0.3048 -0.2032)
						)
					)
					(width 0)
					(fill yes)
				)
			)
		)
		(pad "2" smd custom
			(at 0 0.4445 180)
			(size 0.1524 0.1524)
			(layers "B.Cu" "B.Mask" "B.Paste")
			(net "GND")
			(options
				(clearance outline)
				(anchor circle)
			)
			(primitives
				(gr_poly
					(pts
						(arc
							(start 0.3048 0.2032)
							(mid 0.275042 0.275042)
							(end 0.2032 0.3048)
						)
						(arc
							(start -0.2032 0.3048)
							(mid -0.275042 0.275042)
							(end -0.3048 0.2032)
						)
						(arc
							(start -0.3048 -0.2032)
							(mid -0.275042 -0.275042)
							(end -0.2032 -0.3048)
						)
						(arc
							(start 0.2032 -0.3048)
							(mid 0.275042 -0.275042)
							(end 0.3048 -0.2032)
						)
					)
					(width 0)
					(fill yes)
				)
			)
		)
	)
	(footprint ""
		(layer "B.Cu")
		(at 31.9024 -128.1684 -90)
		(property "Reference" "C508"
			(at 0 0 90)
			(layer "B.SilkS")
			(hide yes)
			(effects
				(font
					(size 1.27 1.27)
				)
				(justify mirror)
			)
		)
		(property "Value" "SCD1U16V2KX-3GP"
			(at -1.1811 -2.7051 270)
			(unlocked yes)
			(layer "B.Fab")
			(hide yes)
			(effects
				(font
					(size 1.016 1.016)
					(thickness 0.1524)
				)
				(justify mirror)
			)
		)
		(property "Device Type" "C402H22"
			(at -1.1811 -4.2291 270)
			(unlocked yes)
			(layer "B.Fab")
			(hide yes)
			(effects
				(font
					(size 1.016 1.016)
					(thickness 0.1524)
				)
				(justify mirror)
			)
		)
		(duplicate_pad_numbers_are_jumpers no)
		(fp_rect
			(start 0.4318 0.9525)
			(end -0.4318 -0.9525)
			(stroke
				(width 0)
				(type default)
			)
			(fill no)
			(layer "B.CrtYd")
		)
		(fp_rect
			(start 0.4318 0.9525)
			(end -0.4318 -0.9525)
			(stroke
				(width 0)
				(type default)
			)
			(fill no)
			(layer "B.Fab")
		)
		(pad "1" smd custom
			(at 0 -0.4445 90)
			(size 0.1524 0.1524)
			(layers "B.Cu" "B.Mask" "B.Paste")
			(net "P3V3_STBY")
			(options
				(clearance outline)
				(anchor circle)
			)
			(primitives
				(gr_poly
					(pts
						(arc
							(start 0.3048 0.2032)
							(mid 0.275042 0.275042)
							(end 0.2032 0.3048)
						)
						(arc
							(start -0.2032 0.3048)
							(mid -0.275042 0.275042)
							(end -0.3048 0.2032)
						)
						(arc
							(start -0.3048 -0.2032)
							(mid -0.275042 -0.275042)
							(end -0.2032 -0.3048)
						)
						(arc
							(start 0.2032 -0.3048)
							(mid 0.275042 -0.275042)
							(end 0.3048 -0.2032)
						)
					)
					(width 0)
					(fill yes)
				)
			)
		)
		(pad "2" smd custom
			(at 0 0.4445 90)
			(size 0.1524 0.1524)
			(layers "B.Cu" "B.Mask" "B.Paste")
			(net "GND")
			(options
				(clearance outline)
				(anchor circle)
			)
			(primitives
				(gr_poly
					(pts
						(arc
							(start 0.3048 0.2032)
							(mid 0.275042 0.275042)
							(end 0.2032 0.3048)
						)
						(arc
							(start -0.2032 0.3048)
							(mid -0.275042 0.275042)
							(end -0.3048 0.2032)
						)
						(arc
							(start -0.3048 -0.2032)
							(mid -0.275042 -0.275042)
							(end -0.2032 -0.3048)
						)
						(arc
							(start 0.2032 -0.3048)
							(mid 0.275042 -0.275042)
							(end 0.3048 -0.2032)
						)
					)
					(width 0)
					(fill yes)
				)
			)
		)
	)
	(footprint ""
		(layer "B.Cu")
		(at 170.035728 -123.622308 -90)
		(property "Reference" "C618"
			(at 0 0 90)
			(layer "B.SilkS")
			(hide yes)
			(effects
				(font
					(size 1.27 1.27)
				)
				(justify mirror)
			)
		)
		(property "Value" "SCD1U16V2KX-3GP"
			(at -1.1811 -2.7051 270)
			(unlocked yes)
			(layer "B.Fab")
			(hide yes)
			(effects
				(font
					(size 1.016 1.016)
					(thickness 0.1524)
				)
				(justify mirror)
			)
		)
		(property "Device Type" "C402H22"
			(at -1.1811 -4.2291 270)
			(unlocked yes)
			(layer "B.Fab")
			(hide yes)
			(effects
				(font
					(size 1.016 1.016)
					(thickness 0.1524)
				)
				(justify mirror)
			)
		)
		(duplicate_pad_numbers_are_jumpers no)
		(fp_rect
			(start 0.4318 0.9525)
			(end -0.4318 -0.9525)
			(stroke
				(width 0)
				(type default)
			)
			(fill no)
			(layer "B.CrtYd")
		)
		(fp_rect
			(start 0.4318 0.9525)
			(end -0.4318 -0.9525)
			(stroke
				(width 0)
				(type default)
			)
			(fill no)
			(layer "B.Fab")
		)
		(pad "1" smd custom
			(at 0 -0.4445 90)
			(size 0.1524 0.1524)
			(layers "B.Cu" "B.Mask" "B.Paste")
			(net "P3V3_M2")
			(options
				(clearance outline)
				(anchor circle)
			)
			(primitives
				(gr_poly
					(pts
						(arc
							(start 0.3048 0.2032)
							(mid 0.275042 0.275042)
							(end 0.2032 0.3048)
						)
						(arc
							(start -0.2032 0.3048)
							(mid -0.275042 0.275042)
							(end -0.3048 0.2032)
						)
						(arc
							(start -0.3048 -0.2032)
							(mid -0.275042 -0.275042)
							(end -0.2032 -0.3048)
						)
						(arc
							(start 0.2032 -0.3048)
							(mid 0.275042 -0.275042)
							(end 0.3048 -0.2032)
						)
					)
					(width 0)
					(fill yes)
				)
			)
		)
		(pad "2" smd custom
			(at 0 0.4445 90)
			(size 0.1524 0.1524)
			(layers "B.Cu" "B.Mask" "B.Paste")
			(net "GND")
			(options
				(clearance outline)
				(anchor circle)
			)
			(primitives
				(gr_poly
					(pts
						(arc
							(start 0.3048 0.2032)
							(mid 0.275042 0.275042)
							(end 0.2032 0.3048)
						)
						(arc
							(start -0.2032 0.3048)
							(mid -0.275042 0.275042)
							(end -0.3048 0.2032)
						)
						(arc
							(start -0.3048 -0.2032)
							(mid -0.275042 -0.275042)
							(end -0.2032 -0.3048)
						)
						(arc
							(start 0.2032 -0.3048)
							(mid 0.275042 -0.275042)
							(end 0.3048 -0.2032)
						)
					)
					(width 0)
					(fill yes)
				)
			)
		)
	)
	(footprint ""
		(layer "B.Cu")
		(at 94.8436 -158.5722)
		(property "Reference" "R21"
			(at 0 0 0)
			(layer "B.SilkS")
			(hide yes)
			(effects
				(font
					(size 1.27 1.27)
				)
				(justify mirror)
			)
		)
		(property "Value" "4K7R2F-GP"
			(at -0.064008 -3.993896 0)
			(unlocked yes)
			(layer "B.Fab")
			(hide yes)
			(effects
				(font
					(size 1.016 1.016)
					(thickness 0.1524)
				)
				(justify mirror)
			)
		)
		(property "Device Type" "R402H16"
			(at -0.064008 -5.517896 0)
			(unlocked yes)
			(layer "B.Fab")
			(hide yes)
			(effects
				(font
					(size 1.016 1.016)
					(thickness 0.1524)
				)
				(justify mirror)
			)
		)
		(duplicate_pad_numbers_are_jumpers no)
		(fp_line
			(start -0.508 -0.9398)
			(end 0.508 -0.9398)
			(stroke
				(width 0.1524)
				(type default)
			)
			(layer "B.SilkS")
		)
		(fp_line
			(start 0.508 -0.9398)
			(end 0.508 0.9398)
			(stroke
				(width 0.1524)
				(type default)
			)
			(layer "B.SilkS")
		)
		(fp_rect
			(start 0.508 0.9398)
			(end -0.508 -0.9398)
			(stroke
				(width 0)
				(type default)
			)
			(fill no)
			(layer "B.CrtYd")
		)
		(fp_rect
			(start 0.508 0.9398)
			(end -0.508 -0.9398)
			(stroke
				(width 0)
				(type default)
			)
			(fill no)
			(layer "B.Fab")
		)
		(pad "1" smd custom
			(at 0 -0.4445 180)
			(size 0.1397 0.1397)
			(layers "B.Cu" "B.Mask" "B.Paste")
			(net "P3V3_STBY")
			(options
				(clearance outline)
				(anchor circle)
			)
			(primitives
				(gr_poly
					(pts
						(arc
							(start -0.1778 0.2794)
							(mid -0.249642 0.249642)
							(end -0.2794 0.1778)
						)
						(arc
							(start -0.2794 -0.1778)
							(mid -0.249642 -0.249642)
							(end -0.1778 -0.2794)
						)
						(arc
							(start 0.1778 -0.2794)
							(mid 0.249642 -0.249642)
							(end 0.2794 -0.1778)
						)
						(arc
							(start 0.2794 0.1778)
							(mid 0.249642 0.249642)
							(end 0.1778 0.2794)
						)
					)
					(width 0)
					(fill yes)
				)
			)
		)
		(pad "2" smd custom
			(at 0 0.4445 180)
			(size 0.1397 0.1397)
			(layers "B.Cu" "B.Mask" "B.Paste")
			(net "USB_RESET_N")
			(options
				(clearance outline)
				(anchor circle)
			)
			(primitives
				(gr_poly
					(pts
						(arc
							(start -0.1778 0.2794)
							(mid -0.249642 0.249642)
							(end -0.2794 0.1778)
						)
						(arc
							(start -0.2794 -0.1778)
							(mid -0.249642 -0.249642)
							(end -0.1778 -0.2794)
						)
						(arc
							(start 0.1778 -0.2794)
							(mid 0.249642 -0.249642)
							(end 0.2794 -0.1778)
						)
						(arc
							(start 0.2794 0.1778)
							(mid 0.249642 0.249642)
							(end 0.1778 0.2794)
						)
					)
					(width 0)
					(fill yes)
				)
			)
		)
	)
	(footprint ""
		(layer "B.Cu")
		(at 52.5526 -146.5834 -90)
		(property "Reference" "TP51"
			(at 0 0 90)
			(layer "B.SilkS")
			(hide yes)
			(effects
				(font
					(size 1.27 1.27)
				)
				(justify mirror)
			)
		)
		(property "Value" "TPAD28-2-GP"
			(at 0.0127 -1.6637 270)
			(unlocked yes)
			(layer "B.Fab")
			(hide yes)
			(effects
				(font
					(size 1.016 1.016)
					(thickness 0.1524)
				)
				(justify mirror)
			)
		)
		(property "Device Type" "TPAD28"
			(at 0.0127 -3.1877 270)
			(unlocked yes)
			(layer "B.Fab")
			(hide yes)
			(effects
				(font
					(size 1.016 1.016)
					(thickness 0.1524)
				)
				(justify mirror)
			)
		)
		(duplicate_pad_numbers_are_jumpers no)
		(fp_poly
			(pts
				(arc
					(start 0 -0.3556)
					(mid 0 0.3556)
					(end 0 -0.3556)
				)
			)
			(stroke
				(width 0)
				(type default)
			)
			(fill no)
			(layer "B.CrtYd")
		)
		(fp_poly
			(pts
				(arc
					(start 0 -0.6096)
					(mid 0 0.6096)
					(end 0 -0.6096)
				)
			)
			(stroke
				(width 0)
				(type default)
			)
			(fill no)
			(layer "B.Fab")
		)
		(pad "1" smd circle
			(at 0 0 90)
			(size 0.7112 0.7112)
			(layers "B.Cu" "B.Mask" "B.Paste")
			(net "RMII_BMC_MDC_R")
		)
	)
	(footprint ""
		(layer "B.Cu")
		(at 53.88991 -123.115832)
		(property "Reference" "R347"
			(at 0 0 0)
			(layer "B.SilkS")
			(hide yes)
			(effects
				(font
					(size 1.27 1.27)
				)
				(justify mirror)
			)
		)
		(property "Value" "4K7R2F-GP"
			(at -0.064008 -3.993896 0)
			(unlocked yes)
			(layer "B.Fab")
			(hide yes)
			(effects
				(font
					(size 1.016 1.016)
					(thickness 0.1524)
				)
				(justify mirror)
			)
		)
		(property "Device Type" "R402H16"
			(at -0.064008 -5.517896 0)
			(unlocked yes)
			(layer "B.Fab")
			(hide yes)
			(effects
				(font
					(size 1.016 1.016)
					(thickness 0.1524)
				)
				(justify mirror)
			)
		)
		(duplicate_pad_numbers_are_jumpers no)
		(fp_line
			(start -0.508 -0.9398)
			(end 0.508 -0.9398)
			(stroke
				(width 0.1524)
				(type default)
			)
			(layer "B.SilkS")
		)
		(fp_line
			(start 0.508 -0.9398)
			(end 0.508 0.9398)
			(stroke
				(width 0.1524)
				(type default)
			)
			(layer "B.SilkS")
		)
		(fp_rect
			(start 0.508 0.9398)
			(end -0.508 -0.9398)
			(stroke
				(width 0)
				(type default)
			)
			(fill no)
			(layer "B.CrtYd")
		)
		(fp_rect
			(start 0.508 0.9398)
			(end -0.508 -0.9398)
			(stroke
				(width 0)
				(type default)
			)
			(fill no)
			(layer "B.Fab")
		)
		(pad "1" smd custom
			(at 0 -0.4445 180)
			(size 0.1397 0.1397)
			(layers "B.Cu" "B.Mask" "B.Paste")
			(net "P3V3_STBY")
			(options
				(clearance outline)
				(anchor circle)
			)
			(primitives
				(gr_poly
					(pts
						(arc
							(start -0.1778 0.2794)
							(mid -0.249642 0.249642)
							(end -0.2794 0.1778)
						)
						(arc
							(start -0.2794 -0.1778)
							(mid -0.249642 -0.249642)
							(end -0.1778 -0.2794)
						)
						(arc
							(start 0.1778 -0.2794)
							(mid 0.249642 -0.249642)
							(end 0.2794 -0.1778)
						)
						(arc
							(start 0.2794 0.1778)
							(mid 0.249642 0.249642)
							(end 0.1778 0.2794)
						)
					)
					(width 0)
					(fill yes)
				)
			)
		)
		(pad "2" smd custom
			(at 0 0.4445 180)
			(size 0.1397 0.1397)
			(layers "B.Cu" "B.Mask" "B.Paste")
			(net "TEMP_3_A2")
			(options
				(clearance outline)
				(anchor circle)
			)
			(primitives
				(gr_poly
					(pts
						(arc
							(start -0.1778 0.2794)
							(mid -0.249642 0.249642)
							(end -0.2794 0.1778)
						)
						(arc
							(start -0.2794 -0.1778)
							(mid -0.249642 -0.249642)
							(end -0.1778 -0.2794)
						)
						(arc
							(start 0.1778 -0.2794)
							(mid 0.249642 -0.249642)
							(end 0.2794 -0.1778)
						)
						(arc
							(start 0.2794 0.1778)
							(mid 0.249642 0.249642)
							(end 0.1778 0.2794)
						)
					)
					(width 0)
					(fill yes)
				)
			)
		)
	)
	(footprint ""
		(layer "B.Cu")
		(at 35.2298 -121.8438 90)
		(property "Reference" "R780"
			(at 0 0 90)
			(layer "B.SilkS")
			(hide yes)
			(effects
				(font
					(size 1.27 1.27)
				)
				(justify mirror)
			)
		)
		(property "Value" "0R2J-2-GP"
			(at -0.064008 -3.993896 90)
			(unlocked yes)
			(layer "B.Fab")
			(hide yes)
			(effects
				(font
					(size 1.016 1.016)
					(thickness 0.1524)
				)
				(justify mirror)
			)
		)
		(property "Device Type" "R402H16"
			(at -0.064008 -5.517896 90)
			(unlocked yes)
			(layer "B.Fab")
			(hide yes)
			(effects
				(font
					(size 1.016 1.016)
					(thickness 0.1524)
				)
				(justify mirror)
			)
		)
		(duplicate_pad_numbers_are_jumpers no)
		(fp_line
			(start 0.508 -0.9398)
			(end 0.508 0.9398)
			(stroke
				(width 0.1524)
				(type default)
			)
			(layer "B.SilkS")
		)
		(fp_line
			(start -0.508 -0.9398)
			(end 0.508 -0.9398)
			(stroke
				(width 0.1524)
				(type default)
			)
			(layer "B.SilkS")
		)
		(fp_rect
			(start 0.508 0.9398)
			(end -0.508 -0.9398)
			(stroke
				(width 0)
				(type default)
			)
			(fill no)
			(layer "B.CrtYd")
		)
		(fp_rect
			(start 0.508 0.9398)
			(end -0.508 -0.9398)
			(stroke
				(width 0)
				(type default)
			)
			(fill no)
			(layer "B.Fab")
		)
		(pad "1" smd custom
			(at 0 -0.4445 270)
			(size 0.1397 0.1397)
			(layers "B.Cu" "B.Mask" "B.Paste")
			(net "FLA_CS_0_R")
			(options
				(clearance outline)
				(anchor circle)
			)
			(primitives
				(gr_poly
					(pts
						(arc
							(start -0.1778 0.2794)
							(mid -0.249642 0.249642)
							(end -0.2794 0.1778)
						)
						(arc
							(start -0.2794 -0.1778)
							(mid -0.249642 -0.249642)
							(end -0.1778 -0.2794)
						)
						(arc
							(start 0.1778 -0.2794)
							(mid 0.249642 -0.249642)
							(end 0.2794 -0.1778)
						)
						(arc
							(start 0.2794 0.1778)
							(mid 0.249642 0.249642)
							(end 0.1778 0.2794)
						)
					)
					(width 0)
					(fill yes)
				)
			)
		)
		(pad "2" smd custom
			(at 0 0.4445 270)
			(size 0.1397 0.1397)
			(layers "B.Cu" "B.Mask" "B.Paste")
			(net "BMC_CPU_EN")
			(options
				(clearance outline)
				(anchor circle)
			)
			(primitives
				(gr_poly
					(pts
						(arc
							(start -0.1778 0.2794)
							(mid -0.249642 0.249642)
							(end -0.2794 0.1778)
						)
						(arc
							(start -0.2794 -0.1778)
							(mid -0.249642 -0.249642)
							(end -0.1778 -0.2794)
						)
						(arc
							(start 0.1778 -0.2794)
							(mid 0.249642 -0.249642)
							(end 0.2794 -0.1778)
						)
						(arc
							(start 0.2794 0.1778)
							(mid 0.249642 0.249642)
							(end 0.1778 0.2794)
						)
					)
					(width 0)
					(fill yes)
				)
			)
		)
	)
	(footprint ""
		(layer "B.Cu")
		(at 63.3222 -136.1948 -90)
		(property "Reference" "R729"
			(at 0 0 90)
			(layer "B.SilkS")
			(hide yes)
			(effects
				(font
					(size 1.27 1.27)
				)
				(justify mirror)
			)
		)
		(property "Value" "10KR2F-2-GP"
			(at -0.064008 -3.993896 270)
			(unlocked yes)
			(layer "B.Fab")
			(hide yes)
			(effects
				(font
					(size 1.016 1.016)
					(thickness 0.1524)
				)
				(justify mirror)
			)
		)
		(property "Device Type" "R402H16"
			(at -0.064008 -5.517896 270)
			(unlocked yes)
			(layer "B.Fab")
			(hide yes)
			(effects
				(font
					(size 1.016 1.016)
					(thickness 0.1524)
				)
				(justify mirror)
			)
		)
		(duplicate_pad_numbers_are_jumpers no)
		(fp_line
			(start -0.508 -0.9398)
			(end 0.508 -0.9398)
			(stroke
				(width 0.1524)
				(type default)
			)
			(layer "B.SilkS")
		)
		(fp_line
			(start 0.508 -0.9398)
			(end 0.508 0.9398)
			(stroke
				(width 0.1524)
				(type default)
			)
			(layer "B.SilkS")
		)
		(fp_rect
			(start 0.508 0.9398)
			(end -0.508 -0.9398)
			(stroke
				(width 0)
				(type default)
			)
			(fill no)
			(layer "B.CrtYd")
		)
		(fp_rect
			(start 0.508 0.9398)
			(end -0.508 -0.9398)
			(stroke
				(width 0)
				(type default)
			)
			(fill no)
			(layer "B.Fab")
		)
		(pad "1" smd custom
			(at 0 -0.4445 90)
			(size 0.1397 0.1397)
			(layers "B.Cu" "B.Mask" "B.Paste")
			(net "TP_BMC_GPIOA0")
			(options
				(clearance outline)
				(anchor circle)
			)
			(primitives
				(gr_poly
					(pts
						(arc
							(start -0.1778 0.2794)
							(mid -0.249642 0.249642)
							(end -0.2794 0.1778)
						)
						(arc
							(start -0.2794 -0.1778)
							(mid -0.249642 -0.249642)
							(end -0.1778 -0.2794)
						)
						(arc
							(start 0.1778 -0.2794)
							(mid 0.249642 -0.249642)
							(end 0.2794 -0.1778)
						)
						(arc
							(start 0.2794 0.1778)
							(mid 0.249642 0.249642)
							(end 0.1778 0.2794)
						)
					)
					(width 0)
					(fill yes)
				)
			)
		)
		(pad "2" smd custom
			(at 0 0.4445 90)
			(size 0.1397 0.1397)
			(layers "B.Cu" "B.Mask" "B.Paste")
			(net "GND")
			(options
				(clearance outline)
				(anchor circle)
			)
			(primitives
				(gr_poly
					(pts
						(arc
							(start -0.1778 0.2794)
							(mid -0.249642 0.249642)
							(end -0.2794 0.1778)
						)
						(arc
							(start -0.2794 -0.1778)
							(mid -0.249642 -0.249642)
							(end -0.1778 -0.2794)
						)
						(arc
							(start 0.1778 -0.2794)
							(mid 0.249642 -0.249642)
							(end 0.2794 -0.1778)
						)
						(arc
							(start 0.2794 0.1778)
							(mid 0.249642 0.249642)
							(end 0.1778 0.2794)
						)
					)
					(width 0)
					(fill yes)
				)
			)
		)
	)
	(footprint ""
		(layer "B.Cu")
		(at 55.800752 -149.122384)
		(property "Reference" "TP80"
			(at 0 0 0)
			(layer "B.SilkS")
			(hide yes)
			(effects
				(font
					(size 1.27 1.27)
				)
				(justify mirror)
			)
		)
		(property "Value" "TPAD28-2-GP"
			(at 0.0127 -1.6637 0)
			(unlocked yes)
			(layer "B.Fab")
			(hide yes)
			(effects
				(font
					(size 1.016 1.016)
					(thickness 0.1524)
				)
				(justify mirror)
			)
		)
		(property "Device Type" "TPAD28"
			(at 0.0127 -3.1877 0)
			(unlocked yes)
			(layer "B.Fab")
			(hide yes)
			(effects
				(font
					(size 1.016 1.016)
					(thickness 0.1524)
				)
				(justify mirror)
			)
		)
		(duplicate_pad_numbers_are_jumpers no)
		(fp_poly
			(pts
				(arc
					(start 0.3556 0)
					(mid -0.3556 0)
					(end 0.3556 0)
				)
			)
			(stroke
				(width 0)
				(type default)
			)
			(fill no)
			(layer "B.CrtYd")
		)
		(fp_poly
			(pts
				(arc
					(start 0.6096 0)
					(mid -0.6096 0)
					(end 0.6096 0)
				)
			)
			(stroke
				(width 0)
				(type default)
			)
			(fill no)
			(layer "B.Fab")
		)
		(pad "1" smd circle
			(at 0 0 180)
			(size 0.7112 0.7112)
			(layers "B.Cu" "B.Mask" "B.Paste")
			(net "JTAG_BMC_TMS")
		)
	)
	(footprint ""
		(layer "B.Cu")
		(at 54.229 -162.1536 90)
		(property "Reference" "C117"
			(at 0 0 90)
			(layer "B.SilkS")
			(hide yes)
			(effects
				(font
					(size 1.27 1.27)
				)
				(justify mirror)
			)
		)
		(property "Value" "SCD1U25V2KX-2-GP"
			(at -1.1811 -2.7051 90)
			(unlocked yes)
			(layer "B.Fab")
			(hide yes)
			(effects
				(font
					(size 1.016 1.016)
					(thickness 0.1524)
				)
				(justify mirror)
			)
		)
		(property "Device Type" "C402H22"
			(at -1.1811 -4.2291 90)
			(unlocked yes)
			(layer "B.Fab")
			(hide yes)
			(effects
				(font
					(size 1.016 1.016)
					(thickness 0.1524)
				)
				(justify mirror)
			)
		)
		(duplicate_pad_numbers_are_jumpers no)
		(fp_rect
			(start 0.4318 0.9525)
			(end -0.4318 -0.9525)
			(stroke
				(width 0)
				(type default)
			)
			(fill no)
			(layer "B.CrtYd")
		)
		(fp_rect
			(start 0.4318 0.9525)
			(end -0.4318 -0.9525)
			(stroke
				(width 0)
				(type default)
			)
			(fill no)
			(layer "B.Fab")
		)
		(pad "1" smd custom
			(at 0 -0.4445 270)
			(size 0.1524 0.1524)
			(layers "B.Cu" "B.Mask" "B.Paste")
			(net "ADC_12V")
			(options
				(clearance outline)
				(anchor circle)
			)
			(primitives
				(gr_poly
					(pts
						(arc
							(start 0.3048 0.2032)
							(mid 0.275042 0.275042)
							(end 0.2032 0.3048)
						)
						(arc
							(start -0.2032 0.3048)
							(mid -0.275042 0.275042)
							(end -0.3048 0.2032)
						)
						(arc
							(start -0.3048 -0.2032)
							(mid -0.275042 -0.275042)
							(end -0.2032 -0.3048)
						)
						(arc
							(start 0.2032 -0.3048)
							(mid 0.275042 -0.275042)
							(end 0.3048 -0.2032)
						)
					)
					(width 0)
					(fill yes)
				)
			)
		)
		(pad "2" smd custom
			(at 0 0.4445 270)
			(size 0.1524 0.1524)
			(layers "B.Cu" "B.Mask" "B.Paste")
			(net "GND")
			(options
				(clearance outline)
				(anchor circle)
			)
			(primitives
				(gr_poly
					(pts
						(arc
							(start 0.3048 0.2032)
							(mid 0.275042 0.275042)
							(end 0.2032 0.3048)
						)
						(arc
							(start -0.2032 0.3048)
							(mid -0.275042 0.275042)
							(end -0.3048 0.2032)
						)
						(arc
							(start -0.3048 -0.2032)
							(mid -0.275042 -0.275042)
							(end -0.2032 -0.3048)
						)
						(arc
							(start 0.2032 -0.3048)
							(mid 0.275042 -0.275042)
							(end 0.3048 -0.2032)
						)
					)
					(width 0)
					(fill yes)
				)
			)
		)
	)
	(footprint ""
		(layer "B.Cu")
		(at 19.874738 -143.326866 180)
		(property "Reference" "C66"
			(at 0 0 0)
			(layer "B.SilkS")
			(hide yes)
			(effects
				(font
					(size 1.27 1.27)
				)
				(justify mirror)
			)
		)
		(property "Value" "SCD1U16V2KX-3GP"
			(at -1.1811 -2.7051 180)
			(unlocked yes)
			(layer "B.Fab")
			(hide yes)
			(effects
				(font
					(size 1.016 1.016)
					(thickness 0.1524)
				)
				(justify mirror)
			)
		)
		(property "Device Type" "C402H22"
			(at -1.1811 -4.2291 180)
			(unlocked yes)
			(layer "B.Fab")
			(hide yes)
			(effects
				(font
					(size 1.016 1.016)
					(thickness 0.1524)
				)
				(justify mirror)
			)
		)
		(duplicate_pad_numbers_are_jumpers no)
		(fp_rect
			(start 0.4318 0.9525)
			(end -0.4318 -0.9525)
			(stroke
				(width 0)
				(type default)
			)
			(fill no)
			(layer "B.CrtYd")
		)
		(fp_rect
			(start 0.4318 0.9525)
			(end -0.4318 -0.9525)
			(stroke
				(width 0)
				(type default)
			)
			(fill no)
			(layer "B.Fab")
		)
		(pad "1" smd custom
			(at 0 -0.4445)
			(size 0.1524 0.1524)
			(layers "B.Cu" "B.Mask" "B.Paste")
			(net "MEMCK_TER")
			(options
				(clearance outline)
				(anchor circle)
			)
			(primitives
				(gr_poly
					(pts
						(arc
							(start 0.3048 0.2032)
							(mid 0.275042 0.275042)
							(end 0.2032 0.3048)
						)
						(arc
							(start -0.2032 0.3048)
							(mid -0.275042 0.275042)
							(end -0.3048 0.2032)
						)
						(arc
							(start -0.3048 -0.2032)
							(mid -0.275042 -0.275042)
							(end -0.2032 -0.3048)
						)
						(arc
							(start 0.2032 -0.3048)
							(mid 0.275042 -0.275042)
							(end 0.3048 -0.2032)
						)
					)
					(width 0)
					(fill yes)
				)
			)
		)
		(pad "2" smd custom
			(at 0 0.4445)
			(size 0.1524 0.1524)
			(layers "B.Cu" "B.Mask" "B.Paste")
			(net "GND")
			(options
				(clearance outline)
				(anchor circle)
			)
			(primitives
				(gr_poly
					(pts
						(arc
							(start 0.3048 0.2032)
							(mid 0.275042 0.275042)
							(end 0.2032 0.3048)
						)
						(arc
							(start -0.2032 0.3048)
							(mid -0.275042 0.275042)
							(end -0.3048 0.2032)
						)
						(arc
							(start -0.3048 -0.2032)
							(mid -0.275042 -0.275042)
							(end -0.2032 -0.3048)
						)
						(arc
							(start 0.2032 -0.3048)
							(mid 0.275042 -0.275042)
							(end 0.3048 -0.2032)
						)
					)
					(width 0)
					(fill yes)
				)
			)
		)
	)
	(footprint ""
		(layer "B.Cu")
		(at 62.2554 -160.782 180)
		(property "Reference" "C87"
			(at 0 0 0)
			(layer "B.SilkS")
			(hide yes)
			(effects
				(font
					(size 1.27 1.27)
				)
				(justify mirror)
			)
		)
		(property "Value" "SC1U16V3KX-5GP"
			(at 0 -2.8194 180)
			(unlocked yes)
			(layer "B.Fab")
			(hide yes)
			(effects
				(font
					(size 1.016 1.016)
					(thickness 0.1524)
				)
				(justify mirror)
			)
		)
		(property "Device Type" "C603H36"
			(at 0 -4.3434 180)
			(unlocked yes)
			(layer "B.Fab")
			(hide yes)
			(effects
				(font
					(size 1.016 1.016)
					(thickness 0.1524)
				)
				(justify mirror)
			)
		)
		(duplicate_pad_numbers_are_jumpers no)
		(fp_line
			(start -0.508 0)
			(end 0.508 0)
			(stroke
				(width 0.2032)
				(type default)
			)
			(layer "B.SilkS")
		)
		(fp_rect
			(start 0.5842 1.3335)
			(end -0.5842 -1.3335)
			(stroke
				(width 0)
				(type default)
			)
			(fill no)
			(layer "B.CrtYd")
		)
		(fp_rect
			(start 0.5842 1.3335)
			(end -0.5842 -1.3335)
			(stroke
				(width 0)
				(type default)
			)
			(fill no)
			(layer "B.Fab")
		)
		(pad "1" smd custom
			(at 0 -0.762)
			(size 0.2159 0.2159)
			(layers "B.Cu" "B.Mask" "B.Paste")
			(net "ADCAV33")
			(options
				(clearance outline)
				(anchor circle)
			)
			(primitives
				(gr_poly
					(pts
						(arc
							(start -0.3302 0.4318)
							(mid -0.402042 0.402042)
							(end -0.4318 0.3302)
						)
						(arc
							(start -0.4318 -0.3302)
							(mid -0.402042 -0.402042)
							(end -0.3302 -0.4318)
						)
						(arc
							(start 0.3302 -0.4318)
							(mid 0.402042 -0.402042)
							(end 0.4318 -0.3302)
						)
						(arc
							(start 0.4318 0.3302)
							(mid 0.402042 0.402042)
							(end 0.3302 0.4318)
						)
					)
					(width 0)
					(fill yes)
				)
			)
		)
		(pad "2" smd custom
			(at 0 0.762)
			(size 0.2159 0.2159)
			(layers "B.Cu" "B.Mask" "B.Paste")
			(net "GND")
			(options
				(clearance outline)
				(anchor circle)
			)
			(primitives
				(gr_poly
					(pts
						(arc
							(start -0.3302 0.4318)
							(mid -0.402042 0.402042)
							(end -0.4318 0.3302)
						)
						(arc
							(start -0.4318 -0.3302)
							(mid -0.402042 -0.402042)
							(end -0.3302 -0.4318)
						)
						(arc
							(start 0.3302 -0.4318)
							(mid 0.402042 -0.402042)
							(end 0.4318 -0.3302)
						)
						(arc
							(start 0.4318 0.3302)
							(mid 0.402042 0.402042)
							(end 0.3302 0.4318)
						)
					)
					(width 0)
					(fill yes)
				)
			)
		)
	)
	(footprint ""
		(layer "B.Cu")
		(at 55.372 -132.08)
		(property "Reference" "C114"
			(at 0 0 0)
			(layer "B.SilkS")
			(hide yes)
			(effects
				(font
					(size 1.27 1.27)
				)
				(justify mirror)
			)
		)
		(property "Value" "SC1U16V3KX-5GP"
			(at 0 -2.8194 0)
			(unlocked yes)
			(layer "B.Fab")
			(hide yes)
			(effects
				(font
					(size 1.016 1.016)
					(thickness 0.1524)
				)
				(justify mirror)
			)
		)
		(property "Device Type" "C603H36"
			(at 0 -4.3434 0)
			(unlocked yes)
			(layer "B.Fab")
			(hide yes)
			(effects
				(font
					(size 1.016 1.016)
					(thickness 0.1524)
				)
				(justify mirror)
			)
		)
		(duplicate_pad_numbers_are_jumpers no)
		(fp_line
			(start -0.508 0)
			(end 0.508 0)
			(stroke
				(width 0.2032)
				(type default)
			)
			(layer "B.SilkS")
		)
		(fp_rect
			(start 0.5842 1.3335)
			(end -0.5842 -1.3335)
			(stroke
				(width 0)
				(type default)
			)
			(fill no)
			(layer "B.CrtYd")
		)
		(fp_rect
			(start 0.5842 1.3335)
			(end -0.5842 -1.3335)
			(stroke
				(width 0)
				(type default)
			)
			(fill no)
			(layer "B.Fab")
		)
		(pad "1" smd custom
			(at 0 -0.762 180)
			(size 0.2159 0.2159)
			(layers "B.Cu" "B.Mask" "B.Paste")
			(net "P1V15_STBY")
			(options
				(clearance outline)
				(anchor circle)
			)
			(primitives
				(gr_poly
					(pts
						(arc
							(start -0.3302 0.4318)
							(mid -0.402042 0.402042)
							(end -0.4318 0.3302)
						)
						(arc
							(start -0.4318 -0.3302)
							(mid -0.402042 -0.402042)
							(end -0.3302 -0.4318)
						)
						(arc
							(start 0.3302 -0.4318)
							(mid 0.402042 -0.402042)
							(end 0.4318 -0.3302)
						)
						(arc
							(start 0.4318 0.3302)
							(mid 0.402042 0.402042)
							(end 0.3302 0.4318)
						)
					)
					(width 0)
					(fill yes)
				)
			)
		)
		(pad "2" smd custom
			(at 0 0.762 180)
			(size 0.2159 0.2159)
			(layers "B.Cu" "B.Mask" "B.Paste")
			(net "GND")
			(options
				(clearance outline)
				(anchor circle)
			)
			(primitives
				(gr_poly
					(pts
						(arc
							(start -0.3302 0.4318)
							(mid -0.402042 0.402042)
							(end -0.4318 0.3302)
						)
						(arc
							(start -0.4318 -0.3302)
							(mid -0.402042 -0.402042)
							(end -0.3302 -0.4318)
						)
						(arc
							(start 0.3302 -0.4318)
							(mid 0.402042 -0.402042)
							(end 0.4318 -0.3302)
						)
						(arc
							(start 0.4318 0.3302)
							(mid 0.402042 0.402042)
							(end 0.3302 0.4318)
						)
					)
					(width 0)
					(fill yes)
				)
			)
		)
	)
	(footprint ""
		(layer "B.Cu")
		(at 54.229 -161.163 90)
		(property "Reference" "R404"
			(at 0 0 90)
			(layer "B.SilkS")
			(hide yes)
			(effects
				(font
					(size 1.27 1.27)
				)
				(justify mirror)
			)
		)
		(property "Value" "1KR2F-3-GP"
			(at -0.064008 -3.993896 90)
			(unlocked yes)
			(layer "B.Fab")
			(hide yes)
			(effects
				(font
					(size 1.016 1.016)
					(thickness 0.1524)
				)
				(justify mirror)
			)
		)
		(property "Device Type" "R402H16"
			(at -0.064008 -5.517896 90)
			(unlocked yes)
			(layer "B.Fab")
			(hide yes)
			(effects
				(font
					(size 1.016 1.016)
					(thickness 0.1524)
				)
				(justify mirror)
			)
		)
		(duplicate_pad_numbers_are_jumpers no)
		(fp_line
			(start 0.508 -0.9398)
			(end 0.508 0.9398)
			(stroke
				(width 0.1524)
				(type default)
			)
			(layer "B.SilkS")
		)
		(fp_line
			(start -0.508 -0.9398)
			(end 0.508 -0.9398)
			(stroke
				(width 0.1524)
				(type default)
			)
			(layer "B.SilkS")
		)
		(fp_rect
			(start 0.508 0.9398)
			(end -0.508 -0.9398)
			(stroke
				(width 0)
				(type default)
			)
			(fill no)
			(layer "B.CrtYd")
		)
		(fp_rect
			(start 0.508 0.9398)
			(end -0.508 -0.9398)
			(stroke
				(width 0)
				(type default)
			)
			(fill no)
			(layer "B.Fab")
		)
		(pad "1" smd custom
			(at 0 -0.4445 270)
			(size 0.1397 0.1397)
			(layers "B.Cu" "B.Mask" "B.Paste")
			(net "ADC_12V")
			(options
				(clearance outline)
				(anchor circle)
			)
			(primitives
				(gr_poly
					(pts
						(arc
							(start -0.1778 0.2794)
							(mid -0.249642 0.249642)
							(end -0.2794 0.1778)
						)
						(arc
							(start -0.2794 -0.1778)
							(mid -0.249642 -0.249642)
							(end -0.1778 -0.2794)
						)
						(arc
							(start 0.1778 -0.2794)
							(mid 0.249642 -0.249642)
							(end 0.2794 -0.1778)
						)
						(arc
							(start 0.2794 0.1778)
							(mid 0.249642 0.249642)
							(end 0.1778 0.2794)
						)
					)
					(width 0)
					(fill yes)
				)
			)
		)
		(pad "2" smd custom
			(at 0 0.4445 270)
			(size 0.1397 0.1397)
			(layers "B.Cu" "B.Mask" "B.Paste")
			(net "GND")
			(options
				(clearance outline)
				(anchor circle)
			)
			(primitives
				(gr_poly
					(pts
						(arc
							(start -0.1778 0.2794)
							(mid -0.249642 0.249642)
							(end -0.2794 0.1778)
						)
						(arc
							(start -0.2794 -0.1778)
							(mid -0.249642 -0.249642)
							(end -0.1778 -0.2794)
						)
						(arc
							(start 0.1778 -0.2794)
							(mid 0.249642 -0.249642)
							(end 0.2794 -0.1778)
						)
						(arc
							(start 0.2794 0.1778)
							(mid 0.249642 0.249642)
							(end 0.1778 0.2794)
						)
					)
					(width 0)
					(fill yes)
				)
			)
		)
	)
	(footprint ""
		(layer "B.Cu")
		(at 56.4134 -121.1326)
		(property "Reference" "R285"
			(at 0 0 0)
			(layer "B.SilkS")
			(hide yes)
			(effects
				(font
					(size 1.27 1.27)
				)
				(justify mirror)
			)
		)
		(property "Value" "4K7R2F-GP"
			(at -0.064008 -3.993896 0)
			(unlocked yes)
			(layer "B.Fab")
			(hide yes)
			(effects
				(font
					(size 1.016 1.016)
					(thickness 0.1524)
				)
				(justify mirror)
			)
		)
		(property "Device Type" "R402H16"
			(at -0.064008 -5.517896 0)
			(unlocked yes)
			(layer "B.Fab")
			(hide yes)
			(effects
				(font
					(size 1.016 1.016)
					(thickness 0.1524)
				)
				(justify mirror)
			)
		)
		(duplicate_pad_numbers_are_jumpers no)
		(fp_line
			(start -0.508 -0.9398)
			(end 0.508 -0.9398)
			(stroke
				(width 0.1524)
				(type default)
			)
			(layer "B.SilkS")
		)
		(fp_line
			(start 0.508 -0.9398)
			(end 0.508 0.9398)
			(stroke
				(width 0.1524)
				(type default)
			)
			(layer "B.SilkS")
		)
		(fp_rect
			(start 0.508 0.9398)
			(end -0.508 -0.9398)
			(stroke
				(width 0)
				(type default)
			)
			(fill no)
			(layer "B.CrtYd")
		)
		(fp_rect
			(start 0.508 0.9398)
			(end -0.508 -0.9398)
			(stroke
				(width 0)
				(type default)
			)
			(fill no)
			(layer "B.Fab")
		)
		(pad "1" smd custom
			(at 0 -0.4445 180)
			(size 0.1397 0.1397)
			(layers "B.Cu" "B.Mask" "B.Paste")
			(net "TEMP_3_A1")
			(options
				(clearance outline)
				(anchor circle)
			)
			(primitives
				(gr_poly
					(pts
						(arc
							(start -0.1778 0.2794)
							(mid -0.249642 0.249642)
							(end -0.2794 0.1778)
						)
						(arc
							(start -0.2794 -0.1778)
							(mid -0.249642 -0.249642)
							(end -0.1778 -0.2794)
						)
						(arc
							(start 0.1778 -0.2794)
							(mid 0.249642 -0.249642)
							(end 0.2794 -0.1778)
						)
						(arc
							(start 0.2794 0.1778)
							(mid 0.249642 0.249642)
							(end 0.1778 0.2794)
						)
					)
					(width 0)
					(fill yes)
				)
			)
		)
		(pad "2" smd custom
			(at 0 0.4445 180)
			(size 0.1397 0.1397)
			(layers "B.Cu" "B.Mask" "B.Paste")
			(net "GND")
			(options
				(clearance outline)
				(anchor circle)
			)
			(primitives
				(gr_poly
					(pts
						(arc
							(start -0.1778 0.2794)
							(mid -0.249642 0.249642)
							(end -0.2794 0.1778)
						)
						(arc
							(start -0.2794 -0.1778)
							(mid -0.249642 -0.249642)
							(end -0.1778 -0.2794)
						)
						(arc
							(start 0.1778 -0.2794)
							(mid 0.249642 -0.249642)
							(end 0.2794 -0.1778)
						)
						(arc
							(start 0.2794 0.1778)
							(mid 0.249642 0.249642)
							(end 0.1778 0.2794)
						)
					)
					(width 0)
					(fill yes)
				)
			)
		)
	)
	(footprint ""
		(layer "B.Cu")
		(at 53.690012 -135.661654)
		(property "Reference" "R355"
			(at 0 0 0)
			(layer "B.SilkS")
			(hide yes)
			(effects
				(font
					(size 1.27 1.27)
				)
				(justify mirror)
			)
		)
		(property "Value" "4K7R2F-GP"
			(at -0.064008 -3.993896 0)
			(unlocked yes)
			(layer "B.Fab")
			(hide yes)
			(effects
				(font
					(size 1.016 1.016)
					(thickness 0.1524)
				)
				(justify mirror)
			)
		)
		(property "Device Type" "R402H16"
			(at -0.064008 -5.517896 0)
			(unlocked yes)
			(layer "B.Fab")
			(hide yes)
			(effects
				(font
					(size 1.016 1.016)
					(thickness 0.1524)
				)
				(justify mirror)
			)
		)
		(duplicate_pad_numbers_are_jumpers no)
		(fp_line
			(start -0.508 -0.9398)
			(end 0.508 -0.9398)
			(stroke
				(width 0.1524)
				(type default)
			)
			(layer "B.SilkS")
		)
		(fp_line
			(start 0.508 -0.9398)
			(end 0.508 0.9398)
			(stroke
				(width 0.1524)
				(type default)
			)
			(layer "B.SilkS")
		)
		(fp_rect
			(start 0.508 0.9398)
			(end -0.508 -0.9398)
			(stroke
				(width 0)
				(type default)
			)
			(fill no)
			(layer "B.CrtYd")
		)
		(fp_rect
			(start 0.508 0.9398)
			(end -0.508 -0.9398)
			(stroke
				(width 0)
				(type default)
			)
			(fill no)
			(layer "B.Fab")
		)
		(pad "1" smd custom
			(at 0 -0.4445 180)
			(size 0.1397 0.1397)
			(layers "B.Cu" "B.Mask" "B.Paste")
			(net "SLOTID_1")
			(options
				(clearance outline)
				(anchor circle)
			)
			(primitives
				(gr_poly
					(pts
						(arc
							(start -0.1778 0.2794)
							(mid -0.249642 0.249642)
							(end -0.2794 0.1778)
						)
						(arc
							(start -0.2794 -0.1778)
							(mid -0.249642 -0.249642)
							(end -0.1778 -0.2794)
						)
						(arc
							(start 0.1778 -0.2794)
							(mid 0.249642 -0.249642)
							(end 0.2794 -0.1778)
						)
						(arc
							(start 0.2794 0.1778)
							(mid 0.249642 0.249642)
							(end 0.1778 0.2794)
						)
					)
					(width 0)
					(fill yes)
				)
			)
		)
		(pad "2" smd custom
			(at 0 0.4445 180)
			(size 0.1397 0.1397)
			(layers "B.Cu" "B.Mask" "B.Paste")
			(net "GND")
			(options
				(clearance outline)
				(anchor circle)
			)
			(primitives
				(gr_poly
					(pts
						(arc
							(start -0.1778 0.2794)
							(mid -0.249642 0.249642)
							(end -0.2794 0.1778)
						)
						(arc
							(start -0.2794 -0.1778)
							(mid -0.249642 -0.249642)
							(end -0.1778 -0.2794)
						)
						(arc
							(start 0.1778 -0.2794)
							(mid 0.249642 -0.249642)
							(end 0.2794 -0.1778)
						)
						(arc
							(start 0.2794 0.1778)
							(mid 0.249642 0.249642)
							(end 0.1778 0.2794)
						)
					)
					(width 0)
					(fill yes)
				)
			)
		)
	)
	(footprint ""
		(layer "B.Cu")
		(at 225.882454 -53.119274 90)
		(property "Reference" "C154"
			(at 0 0 90)
			(layer "B.SilkS")
			(hide yes)
			(effects
				(font
					(size 1.27 1.27)
				)
				(justify mirror)
			)
		)
		(property "Value" "SC10U16V5KX-7-GP-U"
			(at 0.0762 -6.1214 90)
			(unlocked yes)
			(layer "B.Fab")
			(hide yes)
			(effects
				(font
					(size 1.016 1.016)
					(thickness 0.1524)
				)
				(justify mirror)
			)
		)
		(property "Device Type" "C805H58"
			(at 0.0762 -8.1534 90)
			(unlocked yes)
			(layer "B.Fab")
			(hide yes)
			(effects
				(font
					(size 1.016 1.016)
					(thickness 0.1524)
				)
				(justify mirror)
			)
		)
		(duplicate_pad_numbers_are_jumpers no)
		(fp_line
			(start -0.635 0)
			(end 0.635 0)
			(stroke
				(width 0.508)
				(type default)
			)
			(layer "B.SilkS")
		)
		(fp_rect
			(start 0.9652 1.778)
			(end -0.9652 -1.778)
			(stroke
				(width 0)
				(type default)
			)
			(fill no)
			(layer "B.CrtYd")
		)
		(fp_poly
			(pts
				(xy 0.9652 -1.778) (xy -0.9652 -1.778) (xy -0.9652 1.778) (xy 0.9652 1.778)
			)
			(stroke
				(width 0)
				(type default)
			)
			(fill no)
			(layer "B.Fab")
		)
		(pad "1" smd rect
			(at 0 -0.9652 270)
			(size 1.397 1.143)
			(layers "B.Cu" "B.Mask" "B.Paste")
			(net "P12V_STBY_VIN_PU1")
		)
		(pad "2" smd rect
			(at 0 0.9652 270)
			(size 1.397 1.143)
			(layers "B.Cu" "B.Mask" "B.Paste")
			(net "GND")
		)
	)
	(footprint ""
		(layer "B.Cu")
		(at 60.8838 -140.1826 -90)
		(property "Reference" "R175"
			(at 0 0 90)
			(layer "B.SilkS")
			(hide yes)
			(effects
				(font
					(size 1.27 1.27)
				)
				(justify mirror)
			)
		)
		(property "Value" "0R2J-2-GP"
			(at -0.064008 -3.993896 270)
			(unlocked yes)
			(layer "B.Fab")
			(hide yes)
			(effects
				(font
					(size 1.016 1.016)
					(thickness 0.1524)
				)
				(justify mirror)
			)
		)
		(property "Device Type" "R402H16"
			(at -0.064008 -5.517896 270)
			(unlocked yes)
			(layer "B.Fab")
			(hide yes)
			(effects
				(font
					(size 1.016 1.016)
					(thickness 0.1524)
				)
				(justify mirror)
			)
		)
		(duplicate_pad_numbers_are_jumpers no)
		(fp_line
			(start -0.508 -0.9398)
			(end 0.508 -0.9398)
			(stroke
				(width 0.1524)
				(type default)
			)
			(layer "B.SilkS")
		)
		(fp_line
			(start 0.508 -0.9398)
			(end 0.508 0.9398)
			(stroke
				(width 0.1524)
				(type default)
			)
			(layer "B.SilkS")
		)
		(fp_rect
			(start 0.508 0.9398)
			(end -0.508 -0.9398)
			(stroke
				(width 0)
				(type default)
			)
			(fill no)
			(layer "B.CrtYd")
		)
		(fp_rect
			(start 0.508 0.9398)
			(end -0.508 -0.9398)
			(stroke
				(width 0)
				(type default)
			)
			(fill no)
			(layer "B.Fab")
		)
		(pad "1" smd custom
			(at 0 -0.4445 90)
			(size 0.1397 0.1397)
			(layers "B.Cu" "B.Mask" "B.Paste")
			(net "I2C_M2_2_SCL")
			(options
				(clearance outline)
				(anchor circle)
			)
			(primitives
				(gr_poly
					(pts
						(arc
							(start -0.1778 0.2794)
							(mid -0.249642 0.249642)
							(end -0.2794 0.1778)
						)
						(arc
							(start -0.2794 -0.1778)
							(mid -0.249642 -0.249642)
							(end -0.1778 -0.2794)
						)
						(arc
							(start 0.1778 -0.2794)
							(mid 0.249642 -0.249642)
							(end 0.2794 -0.1778)
						)
						(arc
							(start 0.2794 0.1778)
							(mid 0.249642 0.249642)
							(end 0.1778 0.2794)
						)
					)
					(width 0)
					(fill yes)
				)
			)
		)
		(pad "2" smd custom
			(at 0 0.4445 90)
			(size 0.1397 0.1397)
			(layers "B.Cu" "B.Mask" "B.Paste")
			(net "BMC_SMB9_CLK")
			(options
				(clearance outline)
				(anchor circle)
			)
			(primitives
				(gr_poly
					(pts
						(arc
							(start -0.1778 0.2794)
							(mid -0.249642 0.249642)
							(end -0.2794 0.1778)
						)
						(arc
							(start -0.2794 -0.1778)
							(mid -0.249642 -0.249642)
							(end -0.1778 -0.2794)
						)
						(arc
							(start 0.1778 -0.2794)
							(mid 0.249642 -0.249642)
							(end 0.2794 -0.1778)
						)
						(arc
							(start 0.2794 0.1778)
							(mid 0.249642 0.249642)
							(end 0.1778 0.2794)
						)
					)
					(width 0)
					(fill yes)
				)
			)
		)
	)
	(footprint ""
		(layer "B.Cu")
		(at 50.01006 -143.6624 180)
		(property "Reference" "R363"
			(at 0 0 0)
			(layer "B.SilkS")
			(hide yes)
			(effects
				(font
					(size 1.27 1.27)
				)
				(justify mirror)
			)
		)
		(property "Value" "4K7R2F-GP"
			(at -0.064008 -3.993896 180)
			(unlocked yes)
			(layer "B.Fab")
			(hide yes)
			(effects
				(font
					(size 1.016 1.016)
					(thickness 0.1524)
				)
				(justify mirror)
			)
		)
		(property "Device Type" "R402H16"
			(at -0.064008 -5.517896 180)
			(unlocked yes)
			(layer "B.Fab")
			(hide yes)
			(effects
				(font
					(size 1.016 1.016)
					(thickness 0.1524)
				)
				(justify mirror)
			)
		)
		(duplicate_pad_numbers_are_jumpers no)
		(fp_line
			(start 0.508 -0.9398)
			(end 0.508 0.9398)
			(stroke
				(width 0.1524)
				(type default)
			)
			(layer "B.SilkS")
		)
		(fp_line
			(start -0.508 -0.9398)
			(end 0.508 -0.9398)
			(stroke
				(width 0.1524)
				(type default)
			)
			(layer "B.SilkS")
		)
		(fp_rect
			(start 0.508 0.9398)
			(end -0.508 -0.9398)
			(stroke
				(width 0)
				(type default)
			)
			(fill no)
			(layer "B.CrtYd")
		)
		(fp_rect
			(start 0.508 0.9398)
			(end -0.508 -0.9398)
			(stroke
				(width 0)
				(type default)
			)
			(fill no)
			(layer "B.Fab")
		)
		(pad "1" smd custom
			(at 0 -0.4445)
			(size 0.1397 0.1397)
			(layers "B.Cu" "B.Mask" "B.Paste")
			(net "JTAG_BMC_TRST_N")
			(options
				(clearance outline)
				(anchor circle)
			)
			(primitives
				(gr_poly
					(pts
						(arc
							(start -0.1778 0.2794)
							(mid -0.249642 0.249642)
							(end -0.2794 0.1778)
						)
						(arc
							(start -0.2794 -0.1778)
							(mid -0.249642 -0.249642)
							(end -0.1778 -0.2794)
						)
						(arc
							(start 0.1778 -0.2794)
							(mid 0.249642 -0.249642)
							(end 0.2794 -0.1778)
						)
						(arc
							(start 0.2794 0.1778)
							(mid 0.249642 0.249642)
							(end 0.1778 0.2794)
						)
					)
					(width 0)
					(fill yes)
				)
			)
		)
		(pad "2" smd custom
			(at 0 0.4445)
			(size 0.1397 0.1397)
			(layers "B.Cu" "B.Mask" "B.Paste")
			(net "GND")
			(options
				(clearance outline)
				(anchor circle)
			)
			(primitives
				(gr_poly
					(pts
						(arc
							(start -0.1778 0.2794)
							(mid -0.249642 0.249642)
							(end -0.2794 0.1778)
						)
						(arc
							(start -0.2794 -0.1778)
							(mid -0.249642 -0.249642)
							(end -0.1778 -0.2794)
						)
						(arc
							(start 0.1778 -0.2794)
							(mid 0.249642 -0.249642)
							(end 0.2794 -0.1778)
						)
						(arc
							(start 0.2794 0.1778)
							(mid 0.249642 0.249642)
							(end 0.1778 0.2794)
						)
					)
					(width 0)
					(fill yes)
				)
			)
		)
	)
	(footprint ""
		(layer "B.Cu")
		(at 55.499 -124.206 180)
		(property "Reference" "R702"
			(at 0 0 0)
			(layer "B.SilkS")
			(hide yes)
			(effects
				(font
					(size 1.27 1.27)
				)
				(justify mirror)
			)
		)
		(property "Value" "4K7R2F-GP"
			(at -0.064008 -3.993896 180)
			(unlocked yes)
			(layer "B.Fab")
			(hide yes)
			(effects
				(font
					(size 1.016 1.016)
					(thickness 0.1524)
				)
				(justify mirror)
			)
		)
		(property "Device Type" "R402H16"
			(at -0.064008 -5.517896 180)
			(unlocked yes)
			(layer "B.Fab")
			(hide yes)
			(effects
				(font
					(size 1.016 1.016)
					(thickness 0.1524)
				)
				(justify mirror)
			)
		)
		(duplicate_pad_numbers_are_jumpers no)
		(fp_line
			(start 0.508 -0.9398)
			(end 0.508 0.9398)
			(stroke
				(width 0.1524)
				(type default)
			)
			(layer "B.SilkS")
		)
		(fp_line
			(start -0.508 -0.9398)
			(end 0.508 -0.9398)
			(stroke
				(width 0.1524)
				(type default)
			)
			(layer "B.SilkS")
		)
		(fp_rect
			(start 0.508 0.9398)
			(end -0.508 -0.9398)
			(stroke
				(width 0)
				(type default)
			)
			(fill no)
			(layer "B.CrtYd")
		)
		(fp_rect
			(start 0.508 0.9398)
			(end -0.508 -0.9398)
			(stroke
				(width 0)
				(type default)
			)
			(fill no)
			(layer "B.Fab")
		)
		(pad "1" smd custom
			(at 0 -0.4445)
			(size 0.1397 0.1397)
			(layers "B.Cu" "B.Mask" "B.Paste")
			(net "P3V3_STBY")
			(options
				(clearance outline)
				(anchor circle)
			)
			(primitives
				(gr_poly
					(pts
						(arc
							(start -0.1778 0.2794)
							(mid -0.249642 0.249642)
							(end -0.2794 0.1778)
						)
						(arc
							(start -0.2794 -0.1778)
							(mid -0.249642 -0.249642)
							(end -0.1778 -0.2794)
						)
						(arc
							(start 0.1778 -0.2794)
							(mid 0.249642 -0.249642)
							(end 0.2794 -0.1778)
						)
						(arc
							(start 0.2794 0.1778)
							(mid 0.249642 0.249642)
							(end 0.1778 0.2794)
						)
					)
					(width 0)
					(fill yes)
				)
			)
		)
		(pad "2" smd custom
			(at 0 0.4445)
			(size 0.1397 0.1397)
			(layers "B.Cu" "B.Mask" "B.Paste")
			(net "DEBUG_RST_BTN_N_R")
			(options
				(clearance outline)
				(anchor circle)
			)
			(primitives
				(gr_poly
					(pts
						(arc
							(start -0.1778 0.2794)
							(mid -0.249642 0.249642)
							(end -0.2794 0.1778)
						)
						(arc
							(start -0.2794 -0.1778)
							(mid -0.249642 -0.249642)
							(end -0.1778 -0.2794)
						)
						(arc
							(start 0.1778 -0.2794)
							(mid 0.249642 -0.249642)
							(end 0.2794 -0.1778)
						)
						(arc
							(start 0.2794 0.1778)
							(mid 0.249642 0.249642)
							(end 0.1778 0.2794)
						)
					)
					(width 0)
					(fill yes)
				)
			)
		)
	)
	(gr_line
		(start 18.034508 -144.16151)
		(end 18.434558 -143.76146)
		(stroke
			(width 0.06223)
			(type default)
		)
		(layer "F.Cu")
	)
	(gr_line
		(start 18.434558 -144.56156)
		(end 18.834608 -144.16151)
		(stroke
			(width 0.06223)
			(type default)
		)
		(layer "F.Cu")
	)
	(gr_line
		(start 21.63445 -148.561552)
		(end 22.0345 -148.961602)
		(stroke
			(width 0.06223)
			(type default)
		)
		(layer "F.Cu")
	)
	(gr_line
		(start 21.63445 -147.761452)
		(end 22.0345 -148.161502)
		(stroke
			(width 0.06223)
			(type default)
		)
		(layer "F.Cu")
	)
	(gr_arc
		(start 32.38246 -144.957546)
		(mid 32.297427 -144.752257)
		(end 32.092138 -144.667224)
		(stroke
			(width 0.06223)
			(type default)
		)
		(layer "F.Cu")
	)
	(gr_arc
		(start 33.174178 -144.687544)
		(mid 32.904907 -144.769663)
		(end 32.78886 -145.026126)
		(stroke
			(width 0.06223)
			(type default)
		)
		(layer "F.Cu")
	)
	(gr_line
		(start 36.798504 -150.076916)
		(end 36.96716 -149.908514)
		(stroke
			(width 0.06223)
			(type default)
		)
		(layer "F.Cu")
	)
	(gr_line
		(start 36.798504 -149.141942)
		(end 36.868608 -149.212046)
		(stroke
			(width 0.06223)
			(type default)
		)
		(layer "F.Cu")
	)
	(gr_arc
		(start 36.868608 -149.212046)
		(mid 37.051803 -149.334453)
		(end 37.267896 -149.3774)
		(stroke
			(width 0.06223)
			(type default)
		)
		(layer "F.Cu")
	)
	(gr_arc
		(start 37.267896 -149.7838)
		(mid 37.105114 -149.816228)
		(end 36.96716 -149.908514)
		(stroke
			(width 0.06223)
			(type default)
		)
		(layer "F.Cu")
	)
	(gr_arc
		(start 37.695886 -146.220688)
		(mid 37.865172 -146.380484)
		(end 38.090602 -146.43862)
		(stroke
			(width 0.06223)
			(type default)
		)
		(layer "F.Cu")
	)
	(gr_arc
		(start 38.065456 -146.84502)
		(mid 37.824083 -146.933011)
		(end 37.695886 -147.155662)
		(stroke
			(width 0.06223)
			(type default)
		)
		(layer "F.Cu")
	)
	(gr_arc
		(start 38.955472 -148.771356)
		(mid 39.115218 -148.739487)
		(end 39.25062 -148.648928)
		(stroke
			(width 0.06223)
			(type default)
		)
		(layer "F.Cu")
	)
	(gr_arc
		(start 38.9636 -144.81175)
		(mid 39.162326 -144.754376)
		(end 39.299896 -144.599914)
		(stroke
			(width 0.06223)
			(type default)
		)
		(layer "F.Cu")
	)
	(gr_arc
		(start 39.022274 -146.43862)
		(mid 39.205413 -146.370784)
		(end 39.299896 -146.19986)
		(stroke
			(width 0.06223)
			(type default)
		)
		(layer "F.Cu")
	)
	(gr_arc
		(start 39.054024 -146.846544)
		(mid 39.038294 -146.845402)
		(end 39.022528 -146.84502)
		(stroke
			(width 0.06223)
			(type default)
		)
		(layer "F.Cu")
	)
	(gr_arc
		(start 39.164006 -149.264116)
		(mid 39.06832 -149.200228)
		(end 38.955472 -149.177756)
		(stroke
			(width 0.06223)
			(type default)
		)
		(layer "F.Cu")
	)
	(gr_line
		(start 39.164006 -149.264116)
		(end 39.299896 -149.400006)
		(stroke
			(width 0.06223)
			(type default)
		)
		(layer "F.Cu")
	)
	(gr_line
		(start 39.25062 -148.648928)
		(end 39.299896 -148.599906)
		(stroke
			(width 0.06223)
			(type default)
		)
		(layer "F.Cu")
	)
	(gr_arc
		(start 39.299896 -146.99996)
		(mid 39.194955 -146.894406)
		(end 39.054024 -146.846544)
		(stroke
			(width 0.06223)
			(type default)
		)
		(layer "F.Cu")
	)
	(gr_arc
		(start 39.299896 -145.400014)
		(mid 39.154765 -145.266516)
		(end 38.9636 -145.21815)
		(stroke
			(width 0.06223)
			(type default)
		)
		(layer "F.Cu")
	)
	(gr_line
		(start 55.299864 -149.400006)
		(end 55.734458 -149.8346)
		(stroke
			(width 0.072898)
			(type default)
		)
		(layer "F.Cu")
	)
	(gr_line
		(start 55.734458 -149.8346)
		(end 55.909718 -149.8346)
		(stroke
			(width 0.072898)
			(type default)
		)
		(layer "F.Cu")
	)
	(gr_line
		(start 56.099964 -149.400006)
		(end 56.220868 -149.52091)
		(stroke
			(width 0.072898)
			(type default)
		)
		(layer "F.Cu")
	)
	(gr_line
		(start 56.099964 -148.599906)
		(end 56.278018 -148.421852)
		(stroke
			(width 0.072898)
			(type default)
		)
		(layer "F.Cu")
	)
	(gr_line
		(start 56.099964 -147.800314)
		(end 56.278018 -147.978368)
		(stroke
			(width 0.072898)
			(type default)
		)
		(layer "F.Cu")
	)
	(gr_line
		(start 56.099964 -147.80006)
		(end 56.099964 -147.800314)
		(stroke
			(width 0.072898)
			(type default)
		)
		(layer "F.Cu")
	)
	(gr_line
		(start 64.105536 -154.419046)
		(end 64.176402 -154.419046)
		(stroke
			(width 0.072898)
			(type default)
		)
		(layer "F.Cu")
	)
	(gr_line
		(start 64.416686 -154.219148)
		(end 64.487552 -154.219148)
		(stroke
			(width 0.072898)
			(type default)
		)
		(layer "F.Cu")
	)
	(gr_line
		(start 65.154048 -152.844246)
		(end 65.362328 -153.052526)
		(stroke
			(width 0.072898)
			(type default)
		)
		(layer "F.Cu")
	)
	(gr_line
		(start 65.154048 -152.400762)
		(end 65.365884 -152.188926)
		(stroke
			(width 0.072898)
			(type default)
		)
		(layer "F.Cu")
	)
	(gr_line
		(start 65.401698 -154.577542)
		(end 65.633092 -154.808936)
		(stroke
			(width 0.072898)
			(type default)
		)
		(layer "F.Cu")
	)
	(gr_line
		(start 65.401698 -154.133804)
		(end 65.633092 -153.90241)
		(stroke
			(width 0.072898)
			(type default)
		)
		(layer "F.Cu")
	)
	(gr_line
		(start 75.475084 -93.75013)
		(end 76.336398 -93.75013)
		(stroke
			(width 0.072898)
			(type default)
		)
		(layer "F.Cu")
	)
	(gr_line
		(start 75.475084 -92.95003)
		(end 76.34859 -92.95003)
		(stroke
			(width 0.072898)
			(type default)
		)
		(layer "F.Cu")
	)
	(gr_line
		(start 75.475084 -90.549984)
		(end 76.604622 -90.549984)
		(stroke
			(width 0.072898)
			(type default)
		)
		(layer "F.Cu")
	)
	(gr_line
		(start 75.475084 -89.750138)
		(end 76.575412 -89.750138)
		(stroke
			(width 0.072898)
			(type default)
		)
		(layer "F.Cu")
	)
	(gr_line
		(start 75.475084 -87.350092)
		(end 76.335636 -87.350092)
		(stroke
			(width 0.072898)
			(type default)
		)
		(layer "F.Cu")
	)
	(gr_line
		(start 75.475084 -86.549992)
		(end 76.349352 -86.549992)
		(stroke
			(width 0.072898)
			(type default)
		)
		(layer "F.Cu")
	)
	(gr_line
		(start 75.475084 -84.149946)
		(end 76.60386 -84.149946)
		(stroke
			(width 0.072898)
			(type default)
		)
		(layer "F.Cu")
	)
	(gr_line
		(start 75.475084 -83.3501)
		(end 76.576174 -83.3501)
		(stroke
			(width 0.072898)
			(type default)
		)
		(layer "F.Cu")
	)
	(gr_line
		(start 75.475084 -80.950054)
		(end 76.334874 -80.950054)
		(stroke
			(width 0.072898)
			(type default)
		)
		(layer "F.Cu")
	)
	(gr_line
		(start 75.475084 -80.149954)
		(end 76.350114 -80.149954)
		(stroke
			(width 0.072898)
			(type default)
		)
		(layer "F.Cu")
	)
	(gr_line
		(start 75.475084 -77.749908)
		(end 76.603098 -77.749908)
		(stroke
			(width 0.072898)
			(type default)
		)
		(layer "F.Cu")
	)
	(gr_line
		(start 75.475084 -76.950062)
		(end 76.576936 -76.950062)
		(stroke
			(width 0.072898)
			(type default)
		)
		(layer "F.Cu")
	)
	(gr_line
		(start 75.475084 -74.550016)
		(end 76.334112 -74.550016)
		(stroke
			(width 0.072898)
			(type default)
		)
		(layer "F.Cu")
	)
	(gr_line
		(start 75.475084 -73.749916)
		(end 76.350876 -73.749916)
		(stroke
			(width 0.072898)
			(type default)
		)
		(layer "F.Cu")
	)
	(gr_line
		(start 75.475084 -71.350124)
		(end 76.602082 -71.350124)
		(stroke
			(width 0.072898)
			(type default)
		)
		(layer "F.Cu")
	)
	(gr_line
		(start 75.475084 -70.550024)
		(end 76.577698 -70.550024)
		(stroke
			(width 0.072898)
			(type default)
		)
		(layer "F.Cu")
	)
	(gr_line
		(start 75.475084 -68.149978)
		(end 76.408788 -68.149978)
		(stroke
			(width 0.072898)
			(type default)
		)
		(layer "F.Cu")
	)
	(gr_line
		(start 75.475084 -67.350132)
		(end 76.419202 -67.350132)
		(stroke
			(width 0.072898)
			(type default)
		)
		(layer "F.Cu")
	)
	(gr_line
		(start 76.334112 -74.550016)
		(end 76.520802 -74.363326)
		(stroke
			(width 0.072898)
			(type default)
		)
		(layer "F.Cu")
	)
	(gr_line
		(start 76.334874 -80.950054)
		(end 76.520802 -80.764126)
		(stroke
			(width 0.072898)
			(type default)
		)
		(layer "F.Cu")
	)
	(gr_line
		(start 76.335636 -87.350092)
		(end 76.520802 -87.164926)
		(stroke
			(width 0.072898)
			(type default)
		)
		(layer "F.Cu")
	)
	(gr_line
		(start 76.336398 -93.75013)
		(end 76.520802 -93.565726)
		(stroke
			(width 0.072898)
			(type default)
		)
		(layer "F.Cu")
	)
	(gr_line
		(start 76.34859 -92.95003)
		(end 76.520802 -93.122242)
		(stroke
			(width 0.072898)
			(type default)
		)
		(layer "F.Cu")
	)
	(gr_line
		(start 76.349352 -86.549992)
		(end 76.520802 -86.721442)
		(stroke
			(width 0.072898)
			(type default)
		)
		(layer "F.Cu")
	)
	(gr_line
		(start 76.350114 -80.149954)
		(end 76.520802 -80.320642)
		(stroke
			(width 0.072898)
			(type default)
		)
		(layer "F.Cu")
	)
	(gr_line
		(start 76.350876 -73.749916)
		(end 76.520802 -73.919842)
		(stroke
			(width 0.072898)
			(type default)
		)
		(layer "F.Cu")
	)
	(gr_line
		(start 76.408788 -68.149978)
		(end 76.592176 -67.96659)
		(stroke
			(width 0.072898)
			(type default)
		)
		(layer "F.Cu")
	)
	(gr_line
		(start 76.419202 -67.350132)
		(end 76.592176 -67.523106)
		(stroke
			(width 0.072898)
			(type default)
		)
		(layer "F.Cu")
	)
	(gr_line
		(start 76.575412 -89.750138)
		(end 76.768198 -89.942924)
		(stroke
			(width 0.072898)
			(type default)
		)
		(layer "F.Cu")
	)
	(gr_line
		(start 76.576174 -83.3501)
		(end 76.768198 -83.542124)
		(stroke
			(width 0.072898)
			(type default)
		)
		(layer "F.Cu")
	)
	(gr_line
		(start 76.576936 -76.950062)
		(end 76.768198 -77.141324)
		(stroke
			(width 0.072898)
			(type default)
		)
		(layer "F.Cu")
	)
	(gr_line
		(start 76.577698 -70.550024)
		(end 76.768198 -70.740524)
		(stroke
			(width 0.072898)
			(type default)
		)
		(layer "F.Cu")
	)
	(gr_line
		(start 76.602082 -71.350124)
		(end 76.768198 -71.184008)
		(stroke
			(width 0.072898)
			(type default)
		)
		(layer "F.Cu")
	)
	(gr_line
		(start 76.603098 -77.749908)
		(end 76.768198 -77.584808)
		(stroke
			(width 0.072898)
			(type default)
		)
		(layer "F.Cu")
	)
	(gr_line
		(start 76.60386 -84.149946)
		(end 76.768198 -83.985608)
		(stroke
			(width 0.072898)
			(type default)
		)
		(layer "F.Cu")
	)
	(gr_line
		(start 76.604622 -90.549984)
		(end 76.768198 -90.386408)
		(stroke
			(width 0.072898)
			(type default)
		)
		(layer "F.Cu")
	)
	(gr_arc
		(start 76.82738 -93.20022)
		(mid 77.09752 -93.121884)
		(end 77.283818 -92.911168)
		(stroke
			(width 0.072898)
			(type default)
		)
		(layer "F.Cu")
	)
	(gr_arc
		(start 76.82738 -86.79942)
		(mid 77.09752 -86.721084)
		(end 77.283818 -86.510368)
		(stroke
			(width 0.072898)
			(type default)
		)
		(layer "F.Cu")
	)
	(gr_arc
		(start 76.82738 -80.39862)
		(mid 77.09752 -80.320284)
		(end 77.283818 -80.109568)
		(stroke
			(width 0.072898)
			(type default)
		)
		(layer "F.Cu")
	)
	(gr_arc
		(start 76.82738 -73.99782)
		(mid 77.09752 -73.919484)
		(end 77.283818 -73.708768)
		(stroke
			(width 0.072898)
			(type default)
		)
		(layer "F.Cu")
	)
	(gr_arc
		(start 76.898754 -67.601084)
		(mid 77.168894 -67.522748)
		(end 77.355192 -67.312032)
		(stroke
			(width 0.072898)
			(type default)
		)
		(layer "F.Cu")
	)
	(gr_arc
		(start 77.283818 -93.800168)
		(mid 77.097453 -93.589615)
		(end 76.82738 -93.51137)
		(stroke
			(width 0.072898)
			(type default)
		)
		(layer "F.Cu")
	)
	(gr_arc
		(start 77.283818 -87.399368)
		(mid 77.097453 -87.188815)
		(end 76.82738 -87.11057)
		(stroke
			(width 0.072898)
			(type default)
		)
		(layer "F.Cu")
	)
	(gr_arc
		(start 77.283818 -80.998568)
		(mid 77.097453 -80.788015)
		(end 76.82738 -80.70977)
		(stroke
			(width 0.072898)
			(type default)
		)
		(layer "F.Cu")
	)
	(gr_arc
		(start 77.283818 -74.597768)
		(mid 77.097453 -74.387215)
		(end 76.82738 -74.30897)
		(stroke
			(width 0.072898)
			(type default)
		)
		(layer "F.Cu")
	)
	(gr_arc
		(start 77.355192 -68.201032)
		(mid 77.168802 -67.990541)
		(end 76.898754 -67.912234)
		(stroke
			(width 0.072898)
			(type default)
		)
		(layer "F.Cu")
	)
	(gr_arc
		(start 77.424788 -89.999566)
		(mid 77.802125 -89.924509)
		(end 78.122018 -89.710768)
		(stroke
			(width 0.072898)
			(type default)
		)
		(layer "F.Cu")
	)
	(gr_arc
		(start 77.424788 -83.598766)
		(mid 77.802125 -83.523709)
		(end 78.122018 -83.309968)
		(stroke
			(width 0.072898)
			(type default)
		)
		(layer "F.Cu")
	)
	(gr_arc
		(start 77.424788 -77.197966)
		(mid 77.802125 -77.122909)
		(end 78.122018 -76.909168)
		(stroke
			(width 0.072898)
			(type default)
		)
		(layer "F.Cu")
	)
	(gr_arc
		(start 77.424788 -70.797166)
		(mid 77.802125 -70.722109)
		(end 78.122018 -70.508368)
		(stroke
			(width 0.072898)
			(type default)
		)
		(layer "F.Cu")
	)
	(gr_arc
		(start 78.122018 -90.599768)
		(mid 77.802125 -90.386027)
		(end 77.424788 -90.31097)
		(stroke
			(width 0.072898)
			(type default)
		)
		(layer "F.Cu")
	)
	(gr_arc
		(start 78.122018 -84.198968)
		(mid 77.802125 -83.985227)
		(end 77.424788 -83.91017)
		(stroke
			(width 0.072898)
			(type default)
		)
		(layer "F.Cu")
	)
	(gr_arc
		(start 78.122018 -77.798168)
		(mid 77.802125 -77.584427)
		(end 77.424788 -77.50937)
		(stroke
			(width 0.072898)
			(type default)
		)
		(layer "F.Cu")
	)
	(gr_arc
		(start 78.122018 -71.397368)
		(mid 77.802125 -71.183627)
		(end 77.424788 -71.10857)
		(stroke
			(width 0.072898)
			(type default)
		)
		(layer "F.Cu")
	)
	(gr_line
		(start 79.925164 -95.350076)
		(end 81.058258 -95.350076)
		(stroke
			(width 0.072898)
			(type default)
		)
		(layer "F.Cu")
	)
	(gr_line
		(start 79.925164 -94.549976)
		(end 81.057242 -94.549976)
		(stroke
			(width 0.072898)
			(type default)
		)
		(layer "F.Cu")
	)
	(gr_line
		(start 79.925164 -92.14993)
		(end 81.08061 -92.14993)
		(stroke
			(width 0.072898)
			(type default)
		)
		(layer "F.Cu")
	)
	(gr_line
		(start 79.925164 -91.350084)
		(end 81.077562 -91.350084)
		(stroke
			(width 0.072898)
			(type default)
		)
		(layer "F.Cu")
	)
	(gr_line
		(start 79.925164 -88.950038)
		(end 81.058258 -88.950038)
		(stroke
			(width 0.072898)
			(type default)
		)
		(layer "F.Cu")
	)
	(gr_line
		(start 79.925164 -88.149938)
		(end 81.059782 -88.149938)
		(stroke
			(width 0.072898)
			(type default)
		)
		(layer "F.Cu")
	)
	(gr_line
		(start 79.925164 -85.750146)
		(end 81.066132 -85.750146)
		(stroke
			(width 0.072898)
			(type default)
		)
		(layer "F.Cu")
	)
	(gr_line
		(start 79.925164 -84.950046)
		(end 81.091786 -84.950046)
		(stroke
			(width 0.072898)
			(type default)
		)
		(layer "F.Cu")
	)
	(gr_line
		(start 79.925164 -82.55)
		(end 81.058258 -82.55)
		(stroke
			(width 0.072898)
			(type default)
		)
		(layer "F.Cu")
	)
	(gr_line
		(start 79.925164 -81.7499)
		(end 81.057242 -81.7499)
		(stroke
			(width 0.072898)
			(type default)
		)
		(layer "F.Cu")
	)
	(gr_line
		(start 79.925164 -79.350108)
		(end 81.084166 -79.350108)
		(stroke
			(width 0.072898)
			(type default)
		)
		(layer "F.Cu")
	)
	(gr_line
		(start 79.925164 -78.550008)
		(end 81.07934 -78.550008)
		(stroke
			(width 0.072898)
			(type default)
		)
		(layer "F.Cu")
	)
	(gr_line
		(start 79.925164 -76.149962)
		(end 81.070958 -76.149962)
		(stroke
			(width 0.072898)
			(type default)
		)
		(layer "F.Cu")
	)
	(gr_line
		(start 79.925164 -75.350116)
		(end 81.044796 -75.350116)
		(stroke
			(width 0.072898)
			(type default)
		)
		(layer "F.Cu")
	)
	(gr_line
		(start 79.925164 -72.95007)
		(end 80.95234 -72.95007)
		(stroke
			(width 0.072898)
			(type default)
		)
		(layer "F.Cu")
	)
	(gr_line
		(start 79.925164 -72.14997)
		(end 80.964278 -72.14997)
		(stroke
			(width 0.072898)
			(type default)
		)
		(layer "F.Cu")
	)
	(gr_line
		(start 80.95234 -72.95007)
		(end 81.13649 -72.76592)
		(stroke
			(width 0.072898)
			(type default)
		)
		(layer "F.Cu")
	)
	(gr_line
		(start 80.964278 -72.14997)
		(end 81.13649 -72.322182)
		(stroke
			(width 0.072898)
			(type default)
		)
		(layer "F.Cu")
	)
	(gr_line
		(start 81.044796 -75.350116)
		(end 81.236058 -75.541378)
		(stroke
			(width 0.072898)
			(type default)
		)
		(layer "F.Cu")
	)
	(gr_line
		(start 81.057242 -94.549976)
		(end 81.236058 -94.728792)
		(stroke
			(width 0.072898)
			(type default)
		)
		(layer "F.Cu")
	)
	(gr_line
		(start 81.057242 -81.7499)
		(end 81.236058 -81.928716)
		(stroke
			(width 0.072898)
			(type default)
		)
		(layer "F.Cu")
	)
	(gr_line
		(start 81.058258 -95.350076)
		(end 81.236058 -95.172276)
		(stroke
			(width 0.072898)
			(type default)
		)
		(layer "F.Cu")
	)
	(gr_line
		(start 81.058258 -88.950038)
		(end 81.237328 -88.770968)
		(stroke
			(width 0.072898)
			(type default)
		)
		(layer "F.Cu")
	)
	(gr_line
		(start 81.058258 -82.55)
		(end 81.236058 -82.3722)
		(stroke
			(width 0.072898)
			(type default)
		)
		(layer "F.Cu")
	)
	(gr_line
		(start 81.059782 -88.149938)
		(end 81.237328 -88.327484)
		(stroke
			(width 0.072898)
			(type default)
		)
		(layer "F.Cu")
	)
	(gr_line
		(start 81.066132 -85.750146)
		(end 81.25714 -85.559138)
		(stroke
			(width 0.072898)
			(type default)
		)
		(layer "F.Cu")
	)
	(gr_line
		(start 81.070958 -76.149962)
		(end 81.236058 -75.984862)
		(stroke
			(width 0.072898)
			(type default)
		)
		(layer "F.Cu")
	)
	(gr_line
		(start 81.077562 -91.350084)
		(end 81.25714 -91.529662)
		(stroke
			(width 0.072898)
			(type default)
		)
		(layer "F.Cu")
	)
	(gr_line
		(start 81.07934 -78.550008)
		(end 81.259934 -78.730602)
		(stroke
			(width 0.072898)
			(type default)
		)
		(layer "F.Cu")
	)
	(gr_line
		(start 81.08061 -92.14993)
		(end 81.25714 -91.9734)
		(stroke
			(width 0.072898)
			(type default)
		)
		(layer "F.Cu")
	)
	(gr_line
		(start 81.084166 -79.350108)
		(end 81.259934 -79.17434)
		(stroke
			(width 0.072898)
			(type default)
		)
		(layer "F.Cu")
	)
	(gr_line
		(start 81.091786 -84.950046)
		(end 81.25714 -85.1154)
		(stroke
			(width 0.072898)
			(type default)
		)
		(layer "F.Cu")
	)
	(gr_arc
		(start 82.660998 -94.78137)
		(mid 83.038335 -94.706313)
		(end 83.358228 -94.492572)
		(stroke
			(width 0.072898)
			(type default)
		)
		(layer "F.Cu")
	)
	(gr_arc
		(start 82.660998 -81.981294)
		(mid 83.038335 -81.906237)
		(end 83.358228 -81.692496)
		(stroke
			(width 0.072898)
			(type default)
		)
		(layer "F.Cu")
	)
	(gr_arc
		(start 82.660998 -75.593956)
		(mid 83.038335 -75.518899)
		(end 83.358228 -75.305158)
		(stroke
			(width 0.072898)
			(type default)
		)
		(layer "F.Cu")
	)
	(gr_arc
		(start 82.662268 -88.380062)
		(mid 83.039605 -88.305005)
		(end 83.359498 -88.091264)
		(stroke
			(width 0.072898)
			(type default)
		)
		(layer "F.Cu")
	)
	(gr_arc
		(start 83.358228 -95.381572)
		(mid 83.038336 -95.167827)
		(end 82.660998 -95.092774)
		(stroke
			(width 0.072898)
			(type default)
		)
		(layer "F.Cu")
	)
	(gr_arc
		(start 83.358228 -82.581496)
		(mid 83.038332 -82.367767)
		(end 82.660998 -82.292698)
		(stroke
			(width 0.072898)
			(type default)
		)
		(layer "F.Cu")
	)
	(gr_arc
		(start 83.358228 -76.194158)
		(mid 83.038335 -75.980416)
		(end 82.660998 -75.90536)
		(stroke
			(width 0.072898)
			(type default)
		)
		(layer "F.Cu")
	)
	(gr_arc
		(start 83.359498 -88.980264)
		(mid 83.039604 -88.766531)
		(end 82.662268 -88.691466)
		(stroke
			(width 0.072898)
			(type default)
		)
		(layer "F.Cu")
	)
	(gr_arc
		(start 84.165948 -72.387714)
		(mid 84.543285 -72.312657)
		(end 84.863178 -72.098916)
		(stroke
			(width 0.072898)
			(type default)
		)
		(layer "F.Cu")
	)
	(gr_arc
		(start 84.286598 -91.595194)
		(mid 84.663935 -91.520137)
		(end 84.983828 -91.306396)
		(stroke
			(width 0.072898)
			(type default)
		)
		(layer "F.Cu")
	)
	(gr_arc
		(start 84.286598 -85.180932)
		(mid 84.663935 -85.105875)
		(end 84.983828 -84.892134)
		(stroke
			(width 0.072898)
			(type default)
		)
		(layer "F.Cu")
	)
	(gr_arc
		(start 84.289392 -78.796134)
		(mid 84.666729 -78.721077)
		(end 84.986622 -78.507336)
		(stroke
			(width 0.072898)
			(type default)
		)
		(layer "F.Cu")
	)
	(gr_arc
		(start 84.863178 -72.987916)
		(mid 84.543286 -72.774167)
		(end 84.165948 -72.699118)
		(stroke
			(width 0.072898)
			(type default)
		)
		(layer "F.Cu")
	)
	(gr_line
		(start 84.903056 -153.072592)
		(end 85.13191 -153.301446)
		(stroke
			(width 0.072898)
			(type default)
		)
		(layer "F.Cu")
	)
	(gr_arc
		(start 84.983828 -92.195396)
		(mid 84.663932 -91.981667)
		(end 84.286598 -91.906598)
		(stroke
			(width 0.072898)
			(type default)
		)
		(layer "F.Cu")
	)
	(gr_arc
		(start 84.983828 -85.781134)
		(mid 84.663934 -85.567397)
		(end 84.286598 -85.492336)
		(stroke
			(width 0.072898)
			(type default)
		)
		(layer "F.Cu")
	)
	(gr_arc
		(start 84.986622 -79.396336)
		(mid 84.666728 -79.182601)
		(end 84.289392 -79.107538)
		(stroke
			(width 0.072898)
			(type default)
		)
		(layer "F.Cu")
	)
	(gr_line
		(start 85.575648 -153.301446)
		(end 85.804502 -153.072592)
		(stroke
			(width 0.072898)
			(type default)
		)
		(layer "F.Cu")
	)
	(gr_line
		(start 86.7664 -156.708348)
		(end 86.995254 -156.479494)
		(stroke
			(width 0.072898)
			(type default)
		)
		(layer "F.Cu")
	)
	(gr_line
		(start 86.7664 -155.806902)
		(end 86.995254 -156.035756)
		(stroke
			(width 0.072898)
			(type default)
		)
		(layer "F.Cu")
	)
	(gr_line
		(start 86.80577 -159.316674)
		(end 87.034624 -159.08782)
		(stroke
			(width 0.072898)
			(type default)
		)
		(layer "F.Cu")
	)
	(gr_line
		(start 86.80577 -158.415228)
		(end 87.034624 -158.644082)
		(stroke
			(width 0.072898)
			(type default)
		)
		(layer "F.Cu")
	)
	(gr_line
		(start 88.000078 -18.222976)
		(end 88.000078 -18.979896)
		(stroke
			(width 0.072898)
			(type default)
		)
		(layer "F.Cu")
	)
	(gr_line
		(start 88.000078 -18.222976)
		(end 88.14689 -18.076164)
		(stroke
			(width 0.072898)
			(type default)
		)
		(layer "F.Cu")
	)
	(gr_line
		(start 88.000078 -17.485868)
		(end 88.14689 -17.63268)
		(stroke
			(width 0.072898)
			(type default)
		)
		(layer "F.Cu")
	)
	(gr_line
		(start 88.000078 -16.9799)
		(end 88.000078 -17.485868)
		(stroke
			(width 0.072898)
			(type default)
		)
		(layer "F.Cu")
	)
	(gr_line
		(start 88.009222 -156.424122)
		(end 88.091518 -156.424122)
		(stroke
			(width 0.072898)
			(type default)
		)
		(layer "F.Cu")
	)
	(gr_line
		(start 88.320372 -156.212794)
		(end 88.402668 -156.212794)
		(stroke
			(width 0.072898)
			(type default)
		)
		(layer "F.Cu")
	)
	(gr_line
		(start 88.893142 -157.574742)
		(end 88.923876 -157.605476)
		(stroke
			(width 0.072898)
			(type default)
		)
		(layer "F.Cu")
	)
	(gr_line
		(start 88.893142 -157.131258)
		(end 88.918796 -157.105604)
		(stroke
			(width 0.072898)
			(type default)
		)
		(layer "F.Cu")
	)
	(gr_line
		(start 88.918796 -157.105604)
		(end 89.881456 -157.105604)
		(stroke
			(width 0.072898)
			(type default)
		)
		(layer "F.Cu")
	)
	(gr_line
		(start 88.923876 -157.605476)
		(end 89.792556 -157.605476)
		(stroke
			(width 0.072898)
			(type default)
		)
		(layer "F.Cu")
	)
	(gr_line
		(start 88.956388 -155.00985)
		(end 89.051892 -155.105354)
		(stroke
			(width 0.072898)
			(type default)
		)
		(layer "F.Cu")
	)
	(gr_line
		(start 88.962992 -154.693874)
		(end 89.051892 -154.605482)
		(stroke
			(width 0.072898)
			(type default)
		)
		(layer "F.Cu")
	)
	(gr_line
		(start 89.027 -156.605478)
		(end 89.881456 -156.605478)
		(stroke
			(width 0.072898)
			(type default)
		)
		(layer "F.Cu")
	)
	(gr_line
		(start 89.029286 -156.16428)
		(end 89.08796 -156.105606)
		(stroke
			(width 0.072898)
			(type default)
		)
		(layer "F.Cu")
	)
	(gr_line
		(start 89.051892 -155.105354)
		(end 89.881456 -155.105354)
		(stroke
			(width 0.072898)
			(type default)
		)
		(layer "F.Cu")
	)
	(gr_line
		(start 89.051892 -154.605482)
		(end 89.881456 -154.605482)
		(stroke
			(width 0.072898)
			(type default)
		)
		(layer "F.Cu")
	)
	(gr_line
		(start 89.08796 -156.105606)
		(end 89.881456 -156.105606)
		(stroke
			(width 0.072898)
			(type default)
		)
		(layer "F.Cu")
	)
	(gr_line
		(start 90.97391 -17.193514)
		(end 91.13647 -17.356074)
		(stroke
			(width 0.072898)
			(type default)
		)
		(layer "F.Cu")
	)
	(gr_line
		(start 91.13647 -17.356074)
		(end 91.57462 -17.356074)
		(stroke
			(width 0.072898)
			(type default)
		)
		(layer "F.Cu")
	)
	(gr_line
		(start 91.28506 -16.879824)
		(end 91.42603 -16.879824)
		(stroke
			(width 0.072898)
			(type default)
		)
		(layer "F.Cu")
	)
	(gr_line
		(start 91.57462 -17.356074)
		(end 91.73718 -17.193514)
		(stroke
			(width 0.072898)
			(type default)
		)
		(layer "F.Cu")
	)
	(gr_line
		(start 92.18041 -17.193514)
		(end 92.34297 -17.356074)
		(stroke
			(width 0.072898)
			(type default)
		)
		(layer "F.Cu")
	)
	(gr_line
		(start 92.34297 -17.356074)
		(end 92.783914 -17.356074)
		(stroke
			(width 0.072898)
			(type default)
		)
		(layer "F.Cu")
	)
	(gr_line
		(start 92.49156 -16.879824)
		(end 94.283276 -16.879824)
		(stroke
			(width 0.072898)
			(type default)
		)
		(layer "F.Cu")
	)
	(gr_line
		(start 92.783914 -17.356074)
		(end 92.94622 -17.193768)
		(stroke
			(width 0.072898)
			(type default)
		)
		(layer "F.Cu")
	)
	(gr_line
		(start 92.94622 -17.193768)
		(end 94.270068 -17.193768)
		(stroke
			(width 0.072898)
			(type default)
		)
		(layer "F.Cu")
	)
	(gr_line
		(start 93.251782 -159.305244)
		(end 93.279976 -159.333438)
		(stroke
			(width 0.072898)
			(type default)
		)
		(layer "F.Cu")
	)
	(gr_line
		(start 93.251782 -158.47568)
		(end 93.251782 -159.305244)
		(stroke
			(width 0.072898)
			(type default)
		)
		(layer "F.Cu")
	)
	(gr_line
		(start 93.72346 -159.333438)
		(end 93.751654 -159.305244)
		(stroke
			(width 0.072898)
			(type default)
		)
		(layer "F.Cu")
	)
	(gr_line
		(start 93.751654 -158.47568)
		(end 93.751654 -159.305244)
		(stroke
			(width 0.072898)
			(type default)
		)
		(layer "F.Cu")
	)
	(gr_line
		(start 94.270068 -17.193768)
		(end 94.488 -17.4117)
		(stroke
			(width 0.072898)
			(type default)
		)
		(layer "F.Cu")
	)
	(gr_line
		(start 94.283276 -16.879824)
		(end 94.488 -16.6751)
		(stroke
			(width 0.072898)
			(type default)
		)
		(layer "F.Cu")
	)
	(gr_line
		(start 94.488 -17.4117)
		(end 94.634558 -17.265142)
		(stroke
			(width 0.072898)
			(type default)
		)
		(layer "F.Cu")
	)
	(gr_line
		(start 94.488 -16.6751)
		(end 94.634558 -16.821658)
		(stroke
			(width 0.072898)
			(type default)
		)
		(layer "F.Cu")
	)
	(gr_line
		(start 98.408998 -164.146992)
		(end 98.637852 -164.375846)
		(stroke
			(width 0.072898)
			(type default)
		)
		(layer "F.Cu")
	)
	(gr_line
		(start 98.408998 -163.703254)
		(end 98.637852 -163.4744)
		(stroke
			(width 0.072898)
			(type default)
		)
		(layer "F.Cu")
	)
	(gr_line
		(start 98.439732 -19.913092)
		(end 98.701098 -20.174458)
		(stroke
			(width 0.072898)
			(type default)
		)
		(layer "F.Cu")
	)
	(gr_line
		(start 98.439732 -19.240246)
		(end 98.439732 -19.913092)
		(stroke
			(width 0.072898)
			(type default)
		)
		(layer "F.Cu")
	)
	(gr_line
		(start 98.439732 -16.858996)
		(end 98.439732 -17.563846)
		(stroke
			(width 0.072898)
			(type default)
		)
		(layer "F.Cu")
	)
	(gr_line
		(start 98.439732 -16.858996)
		(end 98.667316 -16.631412)
		(stroke
			(width 0.072898)
			(type default)
		)
		(layer "F.Cu")
	)
	(gr_line
		(start 98.509582 -21.06422)
		(end 98.738436 -20.835366)
		(stroke
			(width 0.072898)
			(type default)
		)
		(layer "F.Cu")
	)
	(gr_line
		(start 99.1108 -16.631412)
		(end 99.404932 -16.925544)
		(stroke
			(width 0.072898)
			(type default)
		)
		(layer "F.Cu")
	)
	(gr_line
		(start 99.144582 -20.174458)
		(end 99.404932 -19.914108)
		(stroke
			(width 0.072898)
			(type default)
		)
		(layer "F.Cu")
	)
	(gr_line
		(start 99.182174 -20.835366)
		(end 99.411028 -21.06422)
		(stroke
			(width 0.072898)
			(type default)
		)
		(layer "F.Cu")
	)
	(gr_line
		(start 99.404932 -19.240246)
		(end 99.404932 -19.914108)
		(stroke
			(width 0.072898)
			(type default)
		)
		(layer "F.Cu")
	)
	(gr_line
		(start 99.404932 -16.925544)
		(end 99.404932 -17.563846)
		(stroke
			(width 0.072898)
			(type default)
		)
		(layer "F.Cu")
	)
	(gr_line
		(start 101.834696 -39.597584)
		(end 102.06355 -39.36873)
		(stroke
			(width 0.072898)
			(type default)
		)
		(layer "F.Cu")
	)
	(gr_line
		(start 102.507288 -39.36873)
		(end 102.736142 -39.597584)
		(stroke
			(width 0.072898)
			(type default)
		)
		(layer "F.Cu")
	)
	(gr_line
		(start 111.578136 -23.217632)
		(end 111.727996 -23.367492)
		(stroke
			(width 0.072898)
			(type default)
		)
		(layer "F.Cu")
	)
	(gr_line
		(start 111.727996 -23.367492)
		(end 112.166146 -23.367492)
		(stroke
			(width 0.072898)
			(type default)
		)
		(layer "F.Cu")
	)
	(gr_line
		(start 111.889286 -22.903942)
		(end 112.004856 -22.903942)
		(stroke
			(width 0.072898)
			(type default)
		)
		(layer "F.Cu")
	)
	(gr_line
		(start 112.166146 -23.367492)
		(end 112.316006 -23.217632)
		(stroke
			(width 0.072898)
			(type default)
		)
		(layer "F.Cu")
	)
	(gr_line
		(start 112.759236 -23.217632)
		(end 112.909096 -23.367492)
		(stroke
			(width 0.072898)
			(type default)
		)
		(layer "F.Cu")
	)
	(gr_line
		(start 112.909096 -23.367492)
		(end 113.347246 -23.367492)
		(stroke
			(width 0.072898)
			(type default)
		)
		(layer "F.Cu")
	)
	(gr_line
		(start 113.070386 -22.903942)
		(end 113.185956 -22.903942)
		(stroke
			(width 0.072898)
			(type default)
		)
		(layer "F.Cu")
	)
	(gr_line
		(start 113.347246 -23.367492)
		(end 113.497106 -23.217632)
		(stroke
			(width 0.072898)
			(type default)
		)
		(layer "F.Cu")
	)
	(gr_line
		(start 113.940336 -23.217632)
		(end 114.090196 -23.367492)
		(stroke
			(width 0.072898)
			(type default)
		)
		(layer "F.Cu")
	)
	(gr_line
		(start 114.090196 -23.367492)
		(end 114.528346 -23.367492)
		(stroke
			(width 0.072898)
			(type default)
		)
		(layer "F.Cu")
	)
	(gr_line
		(start 114.251486 -22.903942)
		(end 114.367056 -22.903942)
		(stroke
			(width 0.072898)
			(type default)
		)
		(layer "F.Cu")
	)
	(gr_line
		(start 114.3 -45.001942)
		(end 114.3 -45.39996)
		(stroke
			(width 0.072898)
			(type default)
		)
		(layer "F.Cu")
	)
	(gr_line
		(start 114.3 -45.001942)
		(end 114.379756 -44.922186)
		(stroke
			(width 0.072898)
			(type default)
		)
		(layer "F.Cu")
	)
	(gr_line
		(start 114.3 -44.398692)
		(end 114.379756 -44.478448)
		(stroke
			(width 0.072898)
			(type default)
		)
		(layer "F.Cu")
	)
	(gr_line
		(start 114.3 -44.000166)
		(end 114.3 -44.398692)
		(stroke
			(width 0.072898)
			(type default)
		)
		(layer "F.Cu")
	)
	(gr_line
		(start 114.528346 -23.367492)
		(end 114.678206 -23.217632)
		(stroke
			(width 0.072898)
			(type default)
		)
		(layer "F.Cu")
	)
	(gr_line
		(start 128.467866 -26.211276)
		(end 128.51511 -26.211276)
		(stroke
			(width 0.072898)
			(type default)
		)
		(layer "F.Cu")
	)
	(gr_arc
		(start 128.846072 -26.542238)
		(mid 128.749135 -26.308213)
		(end 128.51511 -26.211276)
		(stroke
			(width 0.072898)
			(type default)
		)
		(layer "F.Cu")
	)
	(gr_arc
		(start 129.488184 -26.211276)
		(mid 129.254182 -26.30822)
		(end 129.157222 -26.542238)
		(stroke
			(width 0.072898)
			(type default)
		)
		(layer "F.Cu")
	)
	(gr_line
		(start 129.488184 -26.211276)
		(end 129.535174 -26.211276)
		(stroke
			(width 0.072898)
			(type default)
		)
		(layer "F.Cu")
	)
	(gr_line
		(start 130.29311 -27.165046)
		(end 130.337052 -27.193494)
		(stroke
			(width 0.072898)
			(type default)
		)
		(layer "F.Cu")
	)
	(gr_line
		(start 134.100062 -43.819064)
		(end 134.100062 -44.200064)
		(stroke
			(width 0.072898)
			(type default)
		)
		(layer "F.Cu")
	)
	(gr_arc
		(start 134.100062 -43.181016)
		(mid 134.147972 -43.296682)
		(end 134.263638 -43.344592)
		(stroke
			(width 0.072898)
			(type default)
		)
		(layer "F.Cu")
	)
	(gr_line
		(start 134.100062 -42.800016)
		(end 134.100062 -43.181016)
		(stroke
			(width 0.072898)
			(type default)
		)
		(layer "F.Cu")
	)
	(gr_arc
		(start 134.263384 -43.655742)
		(mid 134.147896 -43.703581)
		(end 134.100062 -43.819064)
		(stroke
			(width 0.072898)
			(type default)
		)
		(layer "F.Cu")
	)
	(gr_line
		(start 167.111934 -136.906)
		(end 167.201596 -136.995662)
		(stroke
			(width 0.072898)
			(type default)
		)
		(layer "F.Cu")
	)
	(gr_arc
		(start 167.201596 -136.995662)
		(mid 167.31615 -137.043112)
		(end 167.430704 -136.995662)
		(stroke
			(width 0.072898)
			(type default)
		)
		(layer "F.Cu")
	)
	(gr_line
		(start 167.650668 -137.444734)
		(end 167.74033 -137.534396)
		(stroke
			(width 0.072898)
			(type default)
		)
		(layer "F.Cu")
	)
	(gr_arc
		(start 167.650668 -137.216134)
		(mid 167.603357 -137.330424)
		(end 167.650668 -137.444734)
		(stroke
			(width 0.072898)
			(type default)
		)
		(layer "F.Cu")
	)
	(gr_line
		(start 170.440096 -138.321034)
		(end 170.529758 -138.410696)
		(stroke
			(width 0.072898)
			(type default)
		)
		(layer "F.Cu")
	)
	(gr_arc
		(start 170.529758 -138.410696)
		(mid 170.644312 -138.458146)
		(end 170.758866 -138.410696)
		(stroke
			(width 0.072898)
			(type default)
		)
		(layer "F.Cu")
	)
	(gr_line
		(start 170.97883 -138.859768)
		(end 171.068492 -138.94943)
		(stroke
			(width 0.072898)
			(type default)
		)
		(layer "F.Cu")
	)
	(gr_arc
		(start 170.97883 -138.631168)
		(mid 170.931454 -138.745477)
		(end 170.97883 -138.859768)
		(stroke
			(width 0.072898)
			(type default)
		)
		(layer "F.Cu")
	)
	(gr_line
		(start 171.150026 -135.71982)
		(end 171.174664 -135.744458)
		(stroke
			(width 0.072898)
			(type default)
		)
		(layer "F.Cu")
	)
	(gr_line
		(start 171.150026 -134.875016)
		(end 171.150026 -135.71982)
		(stroke
			(width 0.072898)
			(type default)
		)
		(layer "F.Cu")
	)
	(gr_line
		(start 171.618148 -135.744458)
		(end 171.649898 -135.712708)
		(stroke
			(width 0.072898)
			(type default)
		)
		(layer "F.Cu")
	)
	(gr_line
		(start 171.649898 -134.875016)
		(end 171.649898 -135.712708)
		(stroke
			(width 0.072898)
			(type default)
		)
		(layer "F.Cu")
	)
	(gr_line
		(start 172.649896 -135.71982)
		(end 172.674534 -135.744458)
		(stroke
			(width 0.072898)
			(type default)
		)
		(layer "F.Cu")
	)
	(gr_line
		(start 172.649896 -134.875016)
		(end 172.649896 -135.71982)
		(stroke
			(width 0.072898)
			(type default)
		)
		(layer "F.Cu")
	)
	(gr_line
		(start 173.118018 -135.744458)
		(end 173.152308 -135.710168)
		(stroke
			(width 0.072898)
			(type default)
		)
		(layer "F.Cu")
	)
	(gr_line
		(start 173.150022 -134.875016)
		(end 173.152308 -134.877302)
		(stroke
			(width 0.072898)
			(type default)
		)
		(layer "F.Cu")
	)
	(gr_line
		(start 173.152308 -134.877302)
		(end 173.152308 -135.710168)
		(stroke
			(width 0.072898)
			(type default)
		)
		(layer "F.Cu")
	)
	(gr_line
		(start 173.943772 -137.925048)
		(end 174.033434 -138.01471)
		(stroke
			(width 0.072898)
			(type default)
		)
		(layer "F.Cu")
	)
	(gr_arc
		(start 174.033434 -138.01471)
		(mid 174.147988 -138.06216)
		(end 174.262542 -138.01471)
		(stroke
			(width 0.072898)
			(type default)
		)
		(layer "F.Cu")
	)
	(gr_line
		(start 174.15002 -135.71982)
		(end 174.174658 -135.744458)
		(stroke
			(width 0.072898)
			(type default)
		)
		(layer "F.Cu")
	)
	(gr_line
		(start 174.15002 -134.875016)
		(end 174.15002 -135.71982)
		(stroke
			(width 0.072898)
			(type default)
		)
		(layer "F.Cu")
	)
	(gr_line
		(start 174.294292 -140.232892)
		(end 174.383954 -140.322554)
		(stroke
			(width 0.072898)
			(type default)
		)
		(layer "F.Cu")
	)
	(gr_arc
		(start 174.383954 -140.322554)
		(mid 174.498508 -140.370004)
		(end 174.613062 -140.322554)
		(stroke
			(width 0.072898)
			(type default)
		)
		(layer "F.Cu")
	)
	(gr_line
		(start 174.482506 -138.463782)
		(end 174.572168 -138.553444)
		(stroke
			(width 0.072898)
			(type default)
		)
		(layer "F.Cu")
	)
	(gr_arc
		(start 174.482506 -138.235182)
		(mid 174.435147 -138.349487)
		(end 174.482506 -138.463782)
		(stroke
			(width 0.072898)
			(type default)
		)
		(layer "F.Cu")
	)
	(gr_line
		(start 174.618142 -135.744458)
		(end 174.649892 -135.712708)
		(stroke
			(width 0.072898)
			(type default)
		)
		(layer "F.Cu")
	)
	(gr_line
		(start 174.649892 -134.875016)
		(end 174.649892 -135.712708)
		(stroke
			(width 0.072898)
			(type default)
		)
		(layer "F.Cu")
	)
	(gr_line
		(start 174.833026 -140.771626)
		(end 174.922688 -140.861288)
		(stroke
			(width 0.072898)
			(type default)
		)
		(layer "F.Cu")
	)
	(gr_arc
		(start 174.833026 -140.543026)
		(mid 174.785692 -140.657318)
		(end 174.833026 -140.771626)
		(stroke
			(width 0.072898)
			(type default)
		)
		(layer "F.Cu")
	)
	(gr_line
		(start 175.64989 -135.71982)
		(end 175.674528 -135.744458)
		(stroke
			(width 0.072898)
			(type default)
		)
		(layer "F.Cu")
	)
	(gr_line
		(start 175.64989 -134.875016)
		(end 175.64989 -135.71982)
		(stroke
			(width 0.072898)
			(type default)
		)
		(layer "F.Cu")
	)
	(gr_line
		(start 175.910748 -136.66089)
		(end 175.910748 -136.676638)
		(stroke
			(width 0.072898)
			(type default)
		)
		(layer "F.Cu")
	)
	(gr_line
		(start 176.055528 -136.34974)
		(end 176.055528 -136.365488)
		(stroke
			(width 0.072898)
			(type default)
		)
		(layer "F.Cu")
	)
	(gr_line
		(start 176.118012 -135.744458)
		(end 176.150016 -135.712454)
		(stroke
			(width 0.072898)
			(type default)
		)
		(layer "F.Cu")
	)
	(gr_line
		(start 176.150016 -134.875016)
		(end 176.150016 -135.712454)
		(stroke
			(width 0.072898)
			(type default)
		)
		(layer "F.Cu")
	)
	(gr_line
		(start 177.150014 -135.71982)
		(end 177.174652 -135.744458)
		(stroke
			(width 0.072898)
			(type default)
		)
		(layer "F.Cu")
	)
	(gr_line
		(start 177.150014 -134.875016)
		(end 177.150014 -135.71982)
		(stroke
			(width 0.072898)
			(type default)
		)
		(layer "F.Cu")
	)
	(gr_line
		(start 177.618136 -135.744458)
		(end 177.649886 -135.712708)
		(stroke
			(width 0.072898)
			(type default)
		)
		(layer "F.Cu")
	)
	(gr_line
		(start 177.649886 -134.875016)
		(end 177.649886 -135.712708)
		(stroke
			(width 0.072898)
			(type default)
		)
		(layer "F.Cu")
	)
	(gr_line
		(start 177.661062 -139.973812)
		(end 177.750724 -140.063474)
		(stroke
			(width 0.072898)
			(type default)
		)
		(layer "F.Cu")
	)
	(gr_arc
		(start 177.750724 -140.063474)
		(mid 177.865278 -140.110924)
		(end 177.979832 -140.063474)
		(stroke
			(width 0.072898)
			(type default)
		)
		(layer "F.Cu")
	)
	(gr_line
		(start 178.199796 -140.512546)
		(end 178.289458 -140.602208)
		(stroke
			(width 0.072898)
			(type default)
		)
		(layer "F.Cu")
	)
	(gr_arc
		(start 178.199796 -140.283946)
		(mid 178.152485 -140.398233)
		(end 178.199796 -140.512546)
		(stroke
			(width 0.072898)
			(type default)
		)
		(layer "F.Cu")
	)
	(gr_line
		(start 178.649884 -135.71982)
		(end 178.674522 -135.744458)
		(stroke
			(width 0.072898)
			(type default)
		)
		(layer "F.Cu")
	)
	(gr_line
		(start 178.649884 -134.875016)
		(end 178.649884 -135.71982)
		(stroke
			(width 0.072898)
			(type default)
		)
		(layer "F.Cu")
	)
	(gr_line
		(start 179.118006 -135.744458)
		(end 179.152296 -135.710168)
		(stroke
			(width 0.072898)
			(type default)
		)
		(layer "F.Cu")
	)
	(gr_line
		(start 179.15001 -134.875016)
		(end 179.152296 -134.877302)
		(stroke
			(width 0.072898)
			(type default)
		)
		(layer "F.Cu")
	)
	(gr_line
		(start 179.152296 -134.877302)
		(end 179.152296 -135.710168)
		(stroke
			(width 0.072898)
			(type default)
		)
		(layer "F.Cu")
	)
	(gr_line
		(start 180.005228 -140.168884)
		(end 180.09489 -140.258546)
		(stroke
			(width 0.072898)
			(type default)
		)
		(layer "F.Cu")
	)
	(gr_arc
		(start 180.09489 -140.258546)
		(mid 180.209444 -140.305996)
		(end 180.323998 -140.258546)
		(stroke
			(width 0.072898)
			(type default)
		)
		(layer "F.Cu")
	)
	(gr_line
		(start 180.150008 -135.71982)
		(end 180.174646 -135.744458)
		(stroke
			(width 0.072898)
			(type default)
		)
		(layer "F.Cu")
	)
	(gr_line
		(start 180.150008 -134.875016)
		(end 180.150008 -135.71982)
		(stroke
			(width 0.072898)
			(type default)
		)
		(layer "F.Cu")
	)
	(gr_line
		(start 180.543962 -140.707618)
		(end 180.633624 -140.79728)
		(stroke
			(width 0.072898)
			(type default)
		)
		(layer "F.Cu")
	)
	(gr_arc
		(start 180.543962 -140.479018)
		(mid 180.496641 -140.593313)
		(end 180.543962 -140.707618)
		(stroke
			(width 0.072898)
			(type default)
		)
		(layer "F.Cu")
	)
	(gr_line
		(start 180.61813 -135.744458)
		(end 180.64988 -135.712708)
		(stroke
			(width 0.072898)
			(type default)
		)
		(layer "F.Cu")
	)
	(gr_line
		(start 180.64988 -134.875016)
		(end 180.64988 -135.712708)
		(stroke
			(width 0.072898)
			(type default)
		)
		(layer "F.Cu")
	)
	(gr_line
		(start 181.649878 -135.71982)
		(end 181.674516 -135.744458)
		(stroke
			(width 0.072898)
			(type default)
		)
		(layer "F.Cu")
	)
	(gr_line
		(start 181.649878 -134.875016)
		(end 181.649878 -135.71982)
		(stroke
			(width 0.072898)
			(type default)
		)
		(layer "F.Cu")
	)
	(gr_line
		(start 182.118 -135.744458)
		(end 182.150004 -135.712454)
		(stroke
			(width 0.072898)
			(type default)
		)
		(layer "F.Cu")
	)
	(gr_line
		(start 182.150004 -134.875016)
		(end 182.150004 -135.712454)
		(stroke
			(width 0.072898)
			(type default)
		)
		(layer "F.Cu")
	)
	(gr_line
		(start 182.328566 -139.663424)
		(end 182.418228 -139.753086)
		(stroke
			(width 0.072898)
			(type default)
		)
		(layer "F.Cu")
	)
	(gr_arc
		(start 182.418228 -139.753086)
		(mid 182.532782 -139.800536)
		(end 182.647336 -139.753086)
		(stroke
			(width 0.072898)
			(type default)
		)
		(layer "F.Cu")
	)
	(gr_line
		(start 182.8673 -140.202158)
		(end 182.956962 -140.29182)
		(stroke
			(width 0.072898)
			(type default)
		)
		(layer "F.Cu")
	)
	(gr_arc
		(start 182.8673 -139.973558)
		(mid 182.819926 -140.08787)
		(end 182.8673 -140.202158)
		(stroke
			(width 0.072898)
			(type default)
		)
		(layer "F.Cu")
	)
	(gr_line
		(start 183.016144 -132.973826)
		(end 183.143144 -132.973826)
		(stroke
			(width 0.072898)
			(type default)
		)
		(layer "F.Cu")
	)
	(gr_line
		(start 183.150002 -133.981444)
		(end 183.150002 -134.875016)
		(stroke
			(width 0.072898)
			(type default)
		)
		(layer "F.Cu")
	)
	(gr_line
		(start 183.150002 -133.981444)
		(end 183.178196 -133.95325)
		(stroke
			(width 0.072898)
			(type default)
		)
		(layer "F.Cu")
	)
	(gr_line
		(start 183.304688 -133.31825)
		(end 183.304688 -133.44017)
		(stroke
			(width 0.072898)
			(type default)
		)
		(layer "F.Cu")
	)
	(gr_arc
		(start 183.304688 -133.13537)
		(mid 183.257365 -133.021145)
		(end 183.143144 -132.973826)
		(stroke
			(width 0.072898)
			(type default)
		)
		(layer "F.Cu")
	)
	(gr_line
		(start 183.55564 -133.6294)
		(end 183.55564 -133.75132)
		(stroke
			(width 0.072898)
			(type default)
		)
		(layer "F.Cu")
	)
	(gr_line
		(start 183.621934 -133.95325)
		(end 183.649874 -133.98119)
		(stroke
			(width 0.072898)
			(type default)
		)
		(layer "F.Cu")
	)
	(gr_line
		(start 183.649874 -133.98119)
		(end 183.649874 -134.875016)
		(stroke
			(width 0.072898)
			(type default)
		)
		(layer "F.Cu")
	)
	(gr_arc
		(start 183.778144 -132.973826)
		(mid 183.663556 -133.02129)
		(end 183.616092 -133.135878)
		(stroke
			(width 0.072898)
			(type default)
		)
		(layer "F.Cu")
	)
	(gr_line
		(start 183.778144 -132.973826)
		(end 183.905144 -132.973826)
		(stroke
			(width 0.072898)
			(type default)
		)
		(layer "F.Cu")
	)
	(gr_line
		(start 185.085228 -139.686284)
		(end 185.17489 -139.775946)
		(stroke
			(width 0.072898)
			(type default)
		)
		(layer "F.Cu")
	)
	(gr_arc
		(start 185.17489 -139.775946)
		(mid 185.289444 -139.823396)
		(end 185.403998 -139.775946)
		(stroke
			(width 0.072898)
			(type default)
		)
		(layer "F.Cu")
	)
	(gr_line
		(start 185.623962 -140.225018)
		(end 185.713624 -140.31468)
		(stroke
			(width 0.072898)
			(type default)
		)
		(layer "F.Cu")
	)
	(gr_arc
		(start 185.623962 -139.996418)
		(mid 185.576641 -140.110713)
		(end 185.623962 -140.225018)
		(stroke
			(width 0.072898)
			(type default)
		)
		(layer "F.Cu")
	)
	(gr_line
		(start 192.090802 -139.258802)
		(end 192.180464 -139.348464)
		(stroke
			(width 0.072898)
			(type default)
		)
		(layer "F.Cu")
	)
	(gr_arc
		(start 192.180464 -139.348464)
		(mid 192.295018 -139.395914)
		(end 192.409572 -139.348464)
		(stroke
			(width 0.072898)
			(type default)
		)
		(layer "F.Cu")
	)
	(gr_line
		(start 192.629536 -139.797536)
		(end 192.719198 -139.887198)
		(stroke
			(width 0.072898)
			(type default)
		)
		(layer "F.Cu")
	)
	(gr_arc
		(start 192.629536 -139.568936)
		(mid 192.582206 -139.683225)
		(end 192.629536 -139.797536)
		(stroke
			(width 0.072898)
			(type default)
		)
		(layer "F.Cu")
	)
	(gr_line
		(start 195.138802 -140.401802)
		(end 195.228464 -140.491464)
		(stroke
			(width 0.072898)
			(type default)
		)
		(layer "F.Cu")
	)
	(gr_arc
		(start 195.228464 -140.491464)
		(mid 195.343018 -140.538914)
		(end 195.457572 -140.491464)
		(stroke
			(width 0.072898)
			(type default)
		)
		(layer "F.Cu")
	)
	(gr_line
		(start 195.677536 -140.940536)
		(end 195.767198 -141.030198)
		(stroke
			(width 0.072898)
			(type default)
		)
		(layer "F.Cu")
	)
	(gr_arc
		(start 195.677536 -140.711936)
		(mid 195.630206 -140.826225)
		(end 195.677536 -140.940536)
		(stroke
			(width 0.072898)
			(type default)
		)
		(layer "F.Cu")
	)
	(gr_line
		(start 196.149976 -135.71982)
		(end 196.174614 -135.744458)
		(stroke
			(width 0.072898)
			(type default)
		)
		(layer "F.Cu")
	)
	(gr_line
		(start 196.149976 -134.875016)
		(end 196.149976 -135.71982)
		(stroke
			(width 0.072898)
			(type default)
		)
		(layer "F.Cu")
	)
	(gr_line
		(start 196.618098 -135.744458)
		(end 196.649848 -135.712708)
		(stroke
			(width 0.072898)
			(type default)
		)
		(layer "F.Cu")
	)
	(gr_line
		(start 196.649848 -134.875016)
		(end 196.649848 -135.712708)
		(stroke
			(width 0.072898)
			(type default)
		)
		(layer "F.Cu")
	)
	(gr_line
		(start 197.649846 -135.71982)
		(end 197.674484 -135.744458)
		(stroke
			(width 0.072898)
			(type default)
		)
		(layer "F.Cu")
	)
	(gr_line
		(start 197.649846 -134.875016)
		(end 197.649846 -135.71982)
		(stroke
			(width 0.072898)
			(type default)
		)
		(layer "F.Cu")
	)
	(gr_line
		(start 197.805802 -140.655802)
		(end 197.895464 -140.745464)
		(stroke
			(width 0.072898)
			(type default)
		)
		(layer "F.Cu")
	)
	(gr_arc
		(start 197.895464 -140.745464)
		(mid 198.010018 -140.792914)
		(end 198.124572 -140.745464)
		(stroke
			(width 0.072898)
			(type default)
		)
		(layer "F.Cu")
	)
	(gr_line
		(start 197.985126 -136.947656)
		(end 198.048626 -136.884156)
		(stroke
			(width 0.072898)
			(type default)
		)
		(layer "F.Cu")
	)
	(gr_line
		(start 198.117968 -135.744458)
		(end 198.152258 -135.710168)
		(stroke
			(width 0.072898)
			(type default)
		)
		(layer "F.Cu")
	)
	(gr_line
		(start 198.149972 -134.875016)
		(end 198.152258 -134.877302)
		(stroke
			(width 0.072898)
			(type default)
		)
		(layer "F.Cu")
	)
	(gr_line
		(start 198.152258 -134.877302)
		(end 198.152258 -135.710168)
		(stroke
			(width 0.072898)
			(type default)
		)
		(layer "F.Cu")
	)
	(gr_line
		(start 198.344536 -141.194536)
		(end 198.434198 -141.284198)
		(stroke
			(width 0.072898)
			(type default)
		)
		(layer "F.Cu")
	)
	(gr_arc
		(start 198.344536 -140.965936)
		(mid 198.297206 -141.080225)
		(end 198.344536 -141.194536)
		(stroke
			(width 0.072898)
			(type default)
		)
		(layer "F.Cu")
	)
	(gr_line
		(start 199.14997 -135.71982)
		(end 199.174608 -135.744458)
		(stroke
			(width 0.072898)
			(type default)
		)
		(layer "F.Cu")
	)
	(gr_line
		(start 199.14997 -134.875016)
		(end 199.14997 -135.71982)
		(stroke
			(width 0.072898)
			(type default)
		)
		(layer "F.Cu")
	)
	(gr_line
		(start 199.618092 -135.744458)
		(end 199.649842 -135.712708)
		(stroke
			(width 0.072898)
			(type default)
		)
		(layer "F.Cu")
	)
	(gr_line
		(start 199.649842 -134.875016)
		(end 199.649842 -135.712708)
		(stroke
			(width 0.072898)
			(type default)
		)
		(layer "F.Cu")
	)
	(gr_line
		(start 200.218802 -140.909802)
		(end 200.308464 -140.999464)
		(stroke
			(width 0.072898)
			(type default)
		)
		(layer "F.Cu")
	)
	(gr_arc
		(start 200.308464 -140.999464)
		(mid 200.423018 -141.046914)
		(end 200.537572 -140.999464)
		(stroke
			(width 0.072898)
			(type default)
		)
		(layer "F.Cu")
	)
	(gr_line
		(start 200.64984 -135.71982)
		(end 200.674478 -135.744458)
		(stroke
			(width 0.072898)
			(type default)
		)
		(layer "F.Cu")
	)
	(gr_line
		(start 200.64984 -134.875016)
		(end 200.64984 -135.71982)
		(stroke
			(width 0.072898)
			(type default)
		)
		(layer "F.Cu")
	)
	(gr_line
		(start 200.757536 -141.448536)
		(end 200.847198 -141.538198)
		(stroke
			(width 0.072898)
			(type default)
		)
		(layer "F.Cu")
	)
	(gr_arc
		(start 200.757536 -141.219936)
		(mid 200.710206 -141.334225)
		(end 200.757536 -141.448536)
		(stroke
			(width 0.072898)
			(type default)
		)
		(layer "F.Cu")
	)
	(gr_line
		(start 201.117962 -135.744458)
		(end 201.152252 -135.710168)
		(stroke
			(width 0.072898)
			(type default)
		)
		(layer "F.Cu")
	)
	(gr_line
		(start 201.149966 -134.875016)
		(end 201.152252 -134.877302)
		(stroke
			(width 0.072898)
			(type default)
		)
		(layer "F.Cu")
	)
	(gr_line
		(start 201.152252 -134.877302)
		(end 201.152252 -135.710168)
		(stroke
			(width 0.072898)
			(type default)
		)
		(layer "F.Cu")
	)
	(gr_line
		(start 202.149964 -135.71982)
		(end 202.174602 -135.744458)
		(stroke
			(width 0.072898)
			(type default)
		)
		(layer "F.Cu")
	)
	(gr_line
		(start 202.149964 -134.875016)
		(end 202.149964 -135.71982)
		(stroke
			(width 0.072898)
			(type default)
		)
		(layer "F.Cu")
	)
	(gr_line
		(start 202.618086 -135.744458)
		(end 202.649836 -135.712708)
		(stroke
			(width 0.072898)
			(type default)
		)
		(layer "F.Cu")
	)
	(gr_line
		(start 202.631802 -140.782802)
		(end 202.721464 -140.872464)
		(stroke
			(width 0.072898)
			(type default)
		)
		(layer "F.Cu")
	)
	(gr_line
		(start 202.649836 -134.875016)
		(end 202.649836 -135.712708)
		(stroke
			(width 0.072898)
			(type default)
		)
		(layer "F.Cu")
	)
	(gr_arc
		(start 202.721464 -140.872464)
		(mid 202.836018 -140.919914)
		(end 202.950572 -140.872464)
		(stroke
			(width 0.072898)
			(type default)
		)
		(layer "F.Cu")
	)
	(gr_line
		(start 203.170536 -141.321536)
		(end 203.260198 -141.411198)
		(stroke
			(width 0.072898)
			(type default)
		)
		(layer "F.Cu")
	)
	(gr_arc
		(start 203.170536 -141.092936)
		(mid 203.123206 -141.207225)
		(end 203.170536 -141.321536)
		(stroke
			(width 0.072898)
			(type default)
		)
		(layer "F.Cu")
	)
	(gr_line
		(start 203.649834 -135.71982)
		(end 203.674472 -135.744458)
		(stroke
			(width 0.072898)
			(type default)
		)
		(layer "F.Cu")
	)
	(gr_line
		(start 203.649834 -134.875016)
		(end 203.649834 -135.71982)
		(stroke
			(width 0.072898)
			(type default)
		)
		(layer "F.Cu")
	)
	(gr_line
		(start 204.117956 -135.744458)
		(end 204.14996 -135.712454)
		(stroke
			(width 0.072898)
			(type default)
		)
		(layer "F.Cu")
	)
	(gr_line
		(start 204.14996 -134.875016)
		(end 204.14996 -135.712454)
		(stroke
			(width 0.072898)
			(type default)
		)
		(layer "F.Cu")
	)
	(gr_line
		(start 204.917802 -140.909802)
		(end 205.007464 -140.999464)
		(stroke
			(width 0.072898)
			(type default)
		)
		(layer "F.Cu")
	)
	(gr_arc
		(start 205.007464 -140.999464)
		(mid 205.122018 -141.046914)
		(end 205.236572 -140.999464)
		(stroke
			(width 0.072898)
			(type default)
		)
		(layer "F.Cu")
	)
	(gr_line
		(start 205.149958 -135.71982)
		(end 205.174596 -135.744458)
		(stroke
			(width 0.072898)
			(type default)
		)
		(layer "F.Cu")
	)
	(gr_line
		(start 205.149958 -134.875016)
		(end 205.149958 -135.71982)
		(stroke
			(width 0.072898)
			(type default)
		)
		(layer "F.Cu")
	)
	(gr_line
		(start 205.237588 -136.86028)
		(end 205.301088 -136.92378)
		(stroke
			(width 0.072898)
			(type default)
		)
		(layer "F.Cu")
	)
	(gr_line
		(start 205.456536 -141.448536)
		(end 205.546198 -141.538198)
		(stroke
			(width 0.072898)
			(type default)
		)
		(layer "F.Cu")
	)
	(gr_arc
		(start 205.456536 -141.219936)
		(mid 205.409206 -141.334225)
		(end 205.456536 -141.448536)
		(stroke
			(width 0.072898)
			(type default)
		)
		(layer "F.Cu")
	)
	(gr_arc
		(start 205.590394 -136.77265)
		(mid 205.5909 -136.773286)
		(end 205.59141 -136.77392)
		(stroke
			(width 0.072898)
			(type default)
		)
		(layer "F.Cu")
	)
	(gr_line
		(start 205.61808 -135.744458)
		(end 205.64983 -135.712708)
		(stroke
			(width 0.072898)
			(type default)
		)
		(layer "F.Cu")
	)
	(gr_line
		(start 205.64983 -134.875016)
		(end 205.64983 -135.712708)
		(stroke
			(width 0.072898)
			(type default)
		)
		(layer "F.Cu")
	)
	(gr_line
		(start 206.441802 -139.258802)
		(end 206.531464 -139.348464)
		(stroke
			(width 0.072898)
			(type default)
		)
		(layer "F.Cu")
	)
	(gr_arc
		(start 206.531464 -139.348464)
		(mid 206.646018 -139.395914)
		(end 206.760572 -139.348464)
		(stroke
			(width 0.072898)
			(type default)
		)
		(layer "F.Cu")
	)
	(gr_line
		(start 206.649828 -135.71982)
		(end 206.674466 -135.744458)
		(stroke
			(width 0.072898)
			(type default)
		)
		(layer "F.Cu")
	)
	(gr_line
		(start 206.649828 -134.875016)
		(end 206.649828 -135.71982)
		(stroke
			(width 0.072898)
			(type default)
		)
		(layer "F.Cu")
	)
	(gr_line
		(start 206.737458 -136.527032)
		(end 206.800958 -136.590532)
		(stroke
			(width 0.072898)
			(type default)
		)
		(layer "F.Cu")
	)
	(gr_line
		(start 206.980536 -139.797536)
		(end 207.070198 -139.887198)
		(stroke
			(width 0.072898)
			(type default)
		)
		(layer "F.Cu")
	)
	(gr_arc
		(start 206.980536 -139.56919)
		(mid 206.933332 -139.683374)
		(end 206.980536 -139.797536)
		(stroke
			(width 0.072898)
			(type default)
		)
		(layer "F.Cu")
	)
	(gr_line
		(start 207.11795 -135.744458)
		(end 207.15224 -135.710168)
		(stroke
			(width 0.072898)
			(type default)
		)
		(layer "F.Cu")
	)
	(gr_line
		(start 207.149954 -134.875016)
		(end 207.15224 -134.877302)
		(stroke
			(width 0.072898)
			(type default)
		)
		(layer "F.Cu")
	)
	(gr_line
		(start 207.15224 -134.877302)
		(end 207.15224 -135.710168)
		(stroke
			(width 0.072898)
			(type default)
		)
		(layer "F.Cu")
	)
	(gr_line
		(start 208.149952 -135.78332)
		(end 208.162906 -135.796274)
		(stroke
			(width 0.072898)
			(type default)
		)
		(layer "F.Cu")
	)
	(gr_line
		(start 208.149952 -134.875016)
		(end 208.149952 -135.78332)
		(stroke
			(width 0.072898)
			(type default)
		)
		(layer "F.Cu")
	)
	(gr_line
		(start 208.606644 -135.796274)
		(end 208.649824 -135.753094)
		(stroke
			(width 0.072898)
			(type default)
		)
		(layer "F.Cu")
	)
	(gr_line
		(start 208.649824 -134.875016)
		(end 208.649824 -135.753094)
		(stroke
			(width 0.072898)
			(type default)
		)
		(layer "F.Cu")
	)
	(gr_line
		(start 209.20583 -138.99515)
		(end 209.26933 -139.05865)
		(stroke
			(width 0.072898)
			(type default)
		)
		(layer "F.Cu")
	)
	(gr_line
		(start 209.616802 -140.528802)
		(end 209.706464 -140.618464)
		(stroke
			(width 0.072898)
			(type default)
		)
		(layer "F.Cu")
	)
	(gr_arc
		(start 209.706464 -140.618464)
		(mid 209.821018 -140.665914)
		(end 209.935572 -140.618464)
		(stroke
			(width 0.072898)
			(type default)
		)
		(layer "F.Cu")
	)
	(gr_line
		(start 210.155536 -141.067536)
		(end 210.245198 -141.157198)
		(stroke
			(width 0.072898)
			(type default)
		)
		(layer "F.Cu")
	)
	(gr_arc
		(start 210.155536 -140.838936)
		(mid 210.108206 -140.953225)
		(end 210.155536 -141.067536)
		(stroke
			(width 0.072898)
			(type default)
		)
		(layer "F.Cu")
	)
	(gr_line
		(start 213.33333 -138.87704)
		(end 213.422992 -138.966702)
		(stroke
			(width 0.072898)
			(type default)
		)
		(layer "F.Cu")
	)
	(gr_arc
		(start 213.422992 -139.195302)
		(mid 213.47034 -139.081001)
		(end 213.422992 -138.966702)
		(stroke
			(width 0.072898)
			(type default)
		)
		(layer "F.Cu")
	)
	(gr_arc
		(start 213.872064 -139.415774)
		(mid 213.75751 -139.368324)
		(end 213.642956 -139.415774)
		(stroke
			(width 0.072898)
			(type default)
		)
		(layer "F.Cu")
	)
	(gr_line
		(start 213.872064 -139.415774)
		(end 213.961726 -139.505436)
		(stroke
			(width 0.072898)
			(type default)
		)
		(layer "F.Cu")
	)
	(gr_line
		(start 20.821396 -141.833092)
		(end 21.044916 -141.609572)
		(stroke
			(width 0.06223)
			(type default)
		)
		(layer "B.Cu")
	)
	(gr_line
		(start 20.82165 -140.808202)
		(end 21.044916 -141.031468)
		(stroke
			(width 0.06223)
			(type default)
		)
		(layer "B.Cu")
	)
	(gr_line
		(start 21.923502 -141.650212)
		(end 22.0345 -141.76121)
		(stroke
			(width 0.06223)
			(type default)
		)
		(layer "B.Cu")
	)
	(gr_line
		(start 21.923502 -141.072108)
		(end 22.0345 -140.96111)
		(stroke
			(width 0.06223)
			(type default)
		)
		(layer "B.Cu")
	)
	(gr_line
		(start 77.132434 -67.978274)
		(end 77.355192 -68.201032)
		(stroke
			(width 0.072898)
			(type default)
		)
		(layer "B.Cu")
	)
	(gr_line
		(start 77.132434 -67.53479)
		(end 77.355192 -67.312032)
		(stroke
			(width 0.072898)
			(type default)
		)
		(layer "B.Cu")
	)
	(gr_line
		(start 77.283818 -93.800168)
		(end 77.506576 -93.57741)
		(stroke
			(width 0.072898)
			(type default)
		)
		(layer "B.Cu")
	)
	(gr_line
		(start 77.283818 -92.911168)
		(end 77.506576 -93.133926)
		(stroke
			(width 0.072898)
			(type default)
		)
		(layer "B.Cu")
	)
	(gr_line
		(start 77.283818 -87.399368)
		(end 77.506576 -87.17661)
		(stroke
			(width 0.072898)
			(type default)
		)
		(layer "B.Cu")
	)
	(gr_line
		(start 77.283818 -86.510368)
		(end 77.506576 -86.733126)
		(stroke
			(width 0.072898)
			(type default)
		)
		(layer "B.Cu")
	)
	(gr_line
		(start 77.283818 -80.998568)
		(end 77.506576 -80.77581)
		(stroke
			(width 0.072898)
			(type default)
		)
		(layer "B.Cu")
	)
	(gr_line
		(start 77.283818 -80.109568)
		(end 77.506576 -80.332326)
		(stroke
			(width 0.072898)
			(type default)
		)
		(layer "B.Cu")
	)
	(gr_line
		(start 77.283818 -74.597768)
		(end 77.506576 -74.37501)
		(stroke
			(width 0.072898)
			(type default)
		)
		(layer "B.Cu")
	)
	(gr_line
		(start 77.283818 -73.708768)
		(end 77.506576 -73.931526)
		(stroke
			(width 0.072898)
			(type default)
		)
		(layer "B.Cu")
	)
	(gr_line
		(start 78.122018 -90.599768)
		(end 78.344776 -90.37701)
		(stroke
			(width 0.072898)
			(type default)
		)
		(layer "B.Cu")
	)
	(gr_line
		(start 78.122018 -89.710768)
		(end 78.344776 -89.933526)
		(stroke
			(width 0.072898)
			(type default)
		)
		(layer "B.Cu")
	)
	(gr_line
		(start 78.122018 -84.198968)
		(end 78.344776 -83.97621)
		(stroke
			(width 0.072898)
			(type default)
		)
		(layer "B.Cu")
	)
	(gr_line
		(start 78.122018 -83.309968)
		(end 78.344776 -83.532726)
		(stroke
			(width 0.072898)
			(type default)
		)
		(layer "B.Cu")
	)
	(gr_line
		(start 78.122018 -77.798168)
		(end 78.344776 -77.57541)
		(stroke
			(width 0.072898)
			(type default)
		)
		(layer "B.Cu")
	)
	(gr_line
		(start 78.122018 -76.909168)
		(end 78.344776 -77.131926)
		(stroke
			(width 0.072898)
			(type default)
		)
		(layer "B.Cu")
	)
	(gr_line
		(start 78.122018 -71.397368)
		(end 78.344776 -71.17461)
		(stroke
			(width 0.072898)
			(type default)
		)
		(layer "B.Cu")
	)
	(gr_line
		(start 78.122018 -70.508368)
		(end 78.344776 -70.731126)
		(stroke
			(width 0.072898)
			(type default)
		)
		(layer "B.Cu")
	)
	(gr_line
		(start 78.919832 -87.10295)
		(end 78.983332 -87.03945)
		(stroke
			(width 0.072898)
			(type default)
		)
		(layer "B.Cu")
	)
	(gr_line
		(start 79.565246 -86.0171)
		(end 79.628746 -85.9536)
		(stroke
			(width 0.072898)
			(type default)
		)
		(layer "B.Cu")
	)
	(gr_line
		(start 83.567778 -84.51215)
		(end 83.631278 -84.44865)
		(stroke
			(width 0.072898)
			(type default)
		)
		(layer "B.Cu")
	)
	(gr_line
		(start 84.823554 -82.8167)
		(end 84.887054 -82.7532)
		(stroke
			(width 0.072898)
			(type default)
		)
		(layer "B.Cu")
	)
	(gr_line
		(start 85.276182 -74.8538)
		(end 85.339682 -74.7903)
		(stroke
			(width 0.072898)
			(type default)
		)
		(layer "B.Cu")
	)
	(gr_line
		(start 85.479636 -70.4088)
		(end 85.543136 -70.3453)
		(stroke
			(width 0.072898)
			(type default)
		)
		(layer "B.Cu")
	)
	(gr_line
		(start 86.40445 -76.46035)
		(end 86.46795 -76.39685)
		(stroke
			(width 0.072898)
			(type default)
		)
		(layer "B.Cu")
	)
	(gr_line
		(start 86.516464 -64.799972)
		(end 86.555072 -64.761364)
		(stroke
			(width 0.072898)
			(type default)
		)
		(layer "B.Cu")
	)
	(gr_line
		(start 86.555072 -64.761364)
		(end 86.566502 -64.708024)
		(stroke
			(width 0.072898)
			(type default)
		)
		(layer "B.Cu")
	)
	(gr_line
		(start 86.90102 -44.972732)
		(end 86.906608 -44.998894)
		(stroke
			(width 0.072898)
			(type default)
		)
		(layer "B.Cu")
	)
	(gr_line
		(start 86.90102 -44.972732)
		(end 86.906862 -44.945808)
		(stroke
			(width 0.072898)
			(type default)
		)
		(layer "B.Cu")
	)
	(gr_line
		(start 86.938104 -61.448188)
		(end 87.076788 -60.792614)
		(stroke
			(width 0.072898)
			(type default)
		)
		(layer "B.Cu")
	)
	(gr_line
		(start 87.01024 -52.734972)
		(end 87.015828 -52.761134)
		(stroke
			(width 0.072898)
			(type default)
		)
		(layer "B.Cu")
	)
	(gr_line
		(start 87.01024 -52.734972)
		(end 87.016082 -52.708048)
		(stroke
			(width 0.072898)
			(type default)
		)
		(layer "B.Cu")
	)
	(gr_line
		(start 87.182706 -60.292742)
		(end 87.32139 -59.637422)
		(stroke
			(width 0.072898)
			(type default)
		)
		(layer "B.Cu")
	)
	(gr_line
		(start 87.224362 -85.65134)
		(end 87.23376 -85.637116)
		(stroke
			(width 0.072898)
			(type default)
		)
		(layer "B.Cu")
	)
	(gr_line
		(start 87.23376 -85.637116)
		(end 87.23757 -85.61959)
		(stroke
			(width 0.072898)
			(type default)
		)
		(layer "B.Cu")
	)
	(gr_line
		(start 87.237824 -61.546994)
		(end 87.415878 -61.43117)
		(stroke
			(width 0.072898)
			(type default)
		)
		(layer "B.Cu")
	)
	(gr_line
		(start 87.389716 -83.408012)
		(end 87.393526 -83.390486)
		(stroke
			(width 0.072898)
			(type default)
		)
		(layer "B.Cu")
	)
	(gr_line
		(start 87.390986 -60.824618)
		(end 87.506556 -61.002672)
		(stroke
			(width 0.072898)
			(type default)
		)
		(layer "B.Cu")
	)
	(gr_line
		(start 87.393526 -83.390486)
		(end 87.402924 -83.376262)
		(stroke
			(width 0.072898)
			(type default)
		)
		(layer "B.Cu")
	)
	(gr_line
		(start 87.415878 -61.43117)
		(end 87.506556 -61.002672)
		(stroke
			(width 0.072898)
			(type default)
		)
		(layer "B.Cu")
	)
	(gr_line
		(start 87.427308 -59.137296)
		(end 87.565992 -58.481976)
		(stroke
			(width 0.072898)
			(type default)
		)
		(layer "B.Cu")
	)
	(gr_line
		(start 87.48268 -60.391548)
		(end 87.66048 -60.275724)
		(stroke
			(width 0.072898)
			(type default)
		)
		(layer "B.Cu")
	)
	(gr_line
		(start 87.50808 -68.380102)
		(end 87.547196 -68.340986)
		(stroke
			(width 0.072898)
			(type default)
		)
		(layer "B.Cu")
	)
	(gr_line
		(start 87.547196 -68.340986)
		(end 87.558118 -68.28663)
		(stroke
			(width 0.072898)
			(type default)
		)
		(layer "B.Cu")
	)
	(gr_line
		(start 87.635588 -59.669172)
		(end 87.751158 -59.847226)
		(stroke
			(width 0.072898)
			(type default)
		)
		(layer "B.Cu")
	)
	(gr_line
		(start 87.66048 -60.275724)
		(end 87.751158 -59.847226)
		(stroke
			(width 0.072898)
			(type default)
		)
		(layer "B.Cu")
	)
	(gr_line
		(start 87.67191 -57.98185)
		(end 87.810594 -57.327292)
		(stroke
			(width 0.072898)
			(type default)
		)
		(layer "B.Cu")
	)
	(gr_line
		(start 87.727282 -59.236102)
		(end 87.905082 -59.120278)
		(stroke
			(width 0.072898)
			(type default)
		)
		(layer "B.Cu")
	)
	(gr_line
		(start 87.88019 -58.513726)
		(end 87.99576 -58.69178)
		(stroke
			(width 0.072898)
			(type default)
		)
		(layer "B.Cu")
	)
	(gr_line
		(start 87.887302 -72.242426)
		(end 87.925402 -72.204326)
		(stroke
			(width 0.072898)
			(type default)
		)
		(layer "B.Cu")
	)
	(gr_line
		(start 87.905082 -59.120278)
		(end 87.99576 -58.69178)
		(stroke
			(width 0.072898)
			(type default)
		)
		(layer "B.Cu")
	)
	(gr_line
		(start 87.925402 -72.204326)
		(end 87.936324 -72.152002)
		(stroke
			(width 0.072898)
			(type default)
		)
		(layer "B.Cu")
	)
	(gr_line
		(start 87.971884 -58.080656)
		(end 88.149684 -57.964832)
		(stroke
			(width 0.072898)
			(type default)
		)
		(layer "B.Cu")
	)
	(gr_line
		(start 88.09355 -49.083214)
		(end 88.099392 -49.110138)
		(stroke
			(width 0.072898)
			(type default)
		)
		(layer "B.Cu")
	)
	(gr_line
		(start 88.093804 -49.1363)
		(end 88.099392 -49.110138)
		(stroke
			(width 0.072898)
			(type default)
		)
		(layer "B.Cu")
	)
	(gr_line
		(start 88.111076 -87.17153)
		(end 88.120474 -87.157306)
		(stroke
			(width 0.072898)
			(type default)
		)
		(layer "B.Cu")
	)
	(gr_line
		(start 88.120474 -87.157306)
		(end 88.124284 -87.13978)
		(stroke
			(width 0.072898)
			(type default)
		)
		(layer "B.Cu")
	)
	(gr_line
		(start 88.124792 -57.35828)
		(end 88.240616 -57.536334)
		(stroke
			(width 0.072898)
			(type default)
		)
		(layer "B.Cu")
	)
	(gr_line
		(start 88.149684 -57.964832)
		(end 88.240616 -57.536334)
		(stroke
			(width 0.072898)
			(type default)
		)
		(layer "B.Cu")
	)
	(gr_line
		(start 88.210644 -56.886856)
		(end 88.216486 -56.91378)
		(stroke
			(width 0.072898)
			(type default)
		)
		(layer "B.Cu")
	)
	(gr_line
		(start 88.210898 -56.940196)
		(end 88.216486 -56.91378)
		(stroke
			(width 0.072898)
			(type default)
		)
		(layer "B.Cu")
	)
	(gr_line
		(start 88.251284 -38.624002)
		(end 88.38946 -37.974016)
		(stroke
			(width 0.072898)
			(type default)
		)
		(layer "B.Cu")
	)
	(gr_line
		(start 88.383364 -52.783232)
		(end 88.388444 -52.80787)
		(stroke
			(width 0.072898)
			(type default)
		)
		(layer "B.Cu")
	)
	(gr_line
		(start 88.383364 -52.783232)
		(end 88.388444 -52.758086)
		(stroke
			(width 0.072898)
			(type default)
		)
		(layer "B.Cu")
	)
	(gr_line
		(start 88.496902 -37.468556)
		(end 88.635078 -36.818316)
		(stroke
			(width 0.072898)
			(type default)
		)
		(layer "B.Cu")
	)
	(gr_line
		(start 88.497664 -83.884516)
		(end 88.501474 -83.86699)
		(stroke
			(width 0.072898)
			(type default)
		)
		(layer "B.Cu")
	)
	(gr_line
		(start 88.501474 -83.86699)
		(end 88.510872 -83.852766)
		(stroke
			(width 0.072898)
			(type default)
		)
		(layer "B.Cu")
	)
	(gr_line
		(start 88.550496 -38.72484)
		(end 88.728296 -38.60927)
		(stroke
			(width 0.072898)
			(type default)
		)
		(layer "B.Cu")
	)
	(gr_line
		(start 88.65743 -90.31732)
		(end 88.666828 -90.303096)
		(stroke
			(width 0.072898)
			(type default)
		)
		(layer "B.Cu")
	)
	(gr_line
		(start 88.666828 -90.303096)
		(end 88.670638 -90.28557)
		(stroke
			(width 0.072898)
			(type default)
		)
		(layer "B.Cu")
	)
	(gr_line
		(start 88.704166 -38.002972)
		(end 88.819482 -38.180772)
		(stroke
			(width 0.072898)
			(type default)
		)
		(layer "B.Cu")
	)
	(gr_line
		(start 88.728296 -38.60927)
		(end 88.819482 -38.180772)
		(stroke
			(width 0.072898)
			(type default)
		)
		(layer "B.Cu")
	)
	(gr_line
		(start 88.742774 -36.312856)
		(end 88.880696 -35.66414)
		(stroke
			(width 0.072898)
			(type default)
		)
		(layer "B.Cu")
	)
	(gr_line
		(start 88.751664 -47.307754)
		(end 88.757252 -47.333916)
		(stroke
			(width 0.072898)
			(type default)
		)
		(layer "B.Cu")
	)
	(gr_line
		(start 88.751664 -47.307754)
		(end 88.757506 -47.279814)
		(stroke
			(width 0.072898)
			(type default)
		)
		(layer "B.Cu")
	)
	(gr_line
		(start 88.796114 -37.569648)
		(end 88.973914 -37.454078)
		(stroke
			(width 0.072898)
			(type default)
		)
		(layer "B.Cu")
	)
	(gr_line
		(start 88.888316 -35.628072)
		(end 88.889586 -35.621722)
		(stroke
			(width 0.072898)
			(type default)
		)
		(layer "B.Cu")
	)
	(gr_line
		(start 88.949784 -36.84778)
		(end 89.0651 -37.02558)
		(stroke
			(width 0.072898)
			(type default)
		)
		(layer "B.Cu")
	)
	(gr_line
		(start 88.973914 -37.454078)
		(end 89.0651 -37.02558)
		(stroke
			(width 0.072898)
			(type default)
		)
		(layer "B.Cu")
	)
	(gr_line
		(start 88.988392 -35.15741)
		(end 89.126314 -34.508948)
		(stroke
			(width 0.072898)
			(type default)
		)
		(layer "B.Cu")
	)
	(gr_line
		(start 89.04097 -72.647302)
		(end 89.051384 -72.6313)
		(stroke
			(width 0.072898)
			(type default)
		)
		(layer "B.Cu")
	)
	(gr_line
		(start 89.041732 -36.414456)
		(end 89.219532 -36.298886)
		(stroke
			(width 0.072898)
			(type default)
		)
		(layer "B.Cu")
	)
	(gr_line
		(start 89.051384 -72.6313)
		(end 89.055448 -72.61225)
		(stroke
			(width 0.072898)
			(type default)
		)
		(layer "B.Cu")
	)
	(gr_line
		(start 89.133934 -34.47288)
		(end 89.226136 -34.039302)
		(stroke
			(width 0.072898)
			(type default)
		)
		(layer "B.Cu")
	)
	(gr_line
		(start 89.19337 -35.68954)
		(end 89.217246 -35.577526)
		(stroke
			(width 0.072898)
			(type default)
		)
		(layer "B.Cu")
	)
	(gr_line
		(start 89.195402 -35.692588)
		(end 89.310718 -35.870388)
		(stroke
			(width 0.072898)
			(type default)
		)
		(layer "B.Cu")
	)
	(gr_line
		(start 89.219532 -36.298886)
		(end 89.310718 -35.870388)
		(stroke
			(width 0.072898)
			(type default)
		)
		(layer "B.Cu")
	)
	(gr_line
		(start 89.23401 -34.002218)
		(end 89.23782 -33.984692)
		(stroke
			(width 0.072898)
			(type default)
		)
		(layer "B.Cu")
	)
	(gr_line
		(start 89.23782 -33.984692)
		(end 89.247218 -33.970468)
		(stroke
			(width 0.072898)
			(type default)
		)
		(layer "B.Cu")
	)
	(gr_line
		(start 89.287604 -35.25901)
		(end 89.46515 -35.143694)
		(stroke
			(width 0.072898)
			(type default)
		)
		(layer "B.Cu")
	)
	(gr_line
		(start 89.43975 -49.040542)
		(end 89.440004 -49.04105)
		(stroke
			(width 0.072898)
			(type default)
		)
		(layer "B.Cu")
	)
	(gr_line
		(start 89.440004 -49.040796)
		(end 89.445084 -49.06518)
		(stroke
			(width 0.072898)
			(type default)
		)
		(layer "B.Cu")
	)
	(gr_line
		(start 89.440258 -49.08931)
		(end 89.445084 -49.06518)
		(stroke
			(width 0.072898)
			(type default)
		)
		(layer "B.Cu")
	)
	(gr_line
		(start 89.44102 -34.537396)
		(end 89.556336 -34.715196)
		(stroke
			(width 0.072898)
			(type default)
		)
		(layer "B.Cu")
	)
	(gr_line
		(start 89.46515 -35.143694)
		(end 89.556336 -34.715196)
		(stroke
			(width 0.072898)
			(type default)
		)
		(layer "B.Cu")
	)
	(gr_line
		(start 89.619074 -53.086762)
		(end 89.624408 -53.11267)
		(stroke
			(width 0.072898)
			(type default)
		)
		(layer "B.Cu")
	)
	(gr_line
		(start 89.619074 -53.086762)
		(end 89.624408 -53.061362)
		(stroke
			(width 0.072898)
			(type default)
		)
		(layer "B.Cu")
	)
	(gr_line
		(start 89.624408 -53.061108)
		(end 89.624662 -53.0606)
		(stroke
			(width 0.072898)
			(type default)
		)
		(layer "B.Cu")
	)
	(gr_line
		(start 89.629996 -84.27466)
		(end 89.633806 -84.257134)
		(stroke
			(width 0.072898)
			(type default)
		)
		(layer "B.Cu")
	)
	(gr_line
		(start 89.633806 -84.257134)
		(end 89.643204 -84.24291)
		(stroke
			(width 0.072898)
			(type default)
		)
		(layer "B.Cu")
	)
	(gr_line
		(start 89.692734 -57.57037)
		(end 89.692734 -57.570624)
		(stroke
			(width 0.072898)
			(type default)
		)
		(layer "B.Cu")
	)
	(gr_line
		(start 89.692734 -57.57037)
		(end 89.697814 -57.595262)
		(stroke
			(width 0.072898)
			(type default)
		)
		(layer "B.Cu")
	)
	(gr_line
		(start 89.692988 -57.619392)
		(end 89.697814 -57.595262)
		(stroke
			(width 0.072898)
			(type default)
		)
		(layer "B.Cu")
	)
	(gr_line
		(start 90.701368 -38.13302)
		(end 90.705178 -38.115494)
		(stroke
			(width 0.072898)
			(type default)
		)
		(layer "B.Cu")
	)
	(gr_line
		(start 90.705178 -38.115494)
		(end 90.714576 -38.10127)
		(stroke
			(width 0.072898)
			(type default)
		)
		(layer "B.Cu")
	)
	(gr_line
		(start 90.833702 -73.94575)
		(end 90.843862 -73.930002)
		(stroke
			(width 0.072898)
			(type default)
		)
		(layer "B.Cu")
	)
	(gr_line
		(start 90.843862 -73.930002)
		(end 90.847418 -73.912222)
		(stroke
			(width 0.072898)
			(type default)
		)
		(layer "B.Cu")
	)
	(gr_line
		(start 90.913712 -57.856628)
		(end 90.919046 -57.83072)
		(stroke
			(width 0.072898)
			(type default)
		)
		(layer "B.Cu")
	)
	(gr_line
		(start 90.913712 -57.804558)
		(end 90.913712 -57.804812)
		(stroke
			(width 0.072898)
			(type default)
		)
		(layer "B.Cu")
	)
	(gr_line
		(start 90.913712 -57.804558)
		(end 90.919046 -57.83072)
		(stroke
			(width 0.072898)
			(type default)
		)
		(layer "B.Cu")
	)
	(gr_line
		(start 91.012264 -54.167786)
		(end 91.017852 -54.193948)
		(stroke
			(width 0.072898)
			(type default)
		)
		(layer "B.Cu")
	)
	(gr_line
		(start 91.012264 -54.167786)
		(end 91.018106 -54.140862)
		(stroke
			(width 0.072898)
			(type default)
		)
		(layer "B.Cu")
	)
	(gr_line
		(start 91.114118 -31.096204)
		(end 91.129104 -31.07309)
		(stroke
			(width 0.072898)
			(type default)
		)
		(layer "B.Cu")
	)
	(gr_line
		(start 91.129104 -31.07309)
		(end 91.152218 -31.058104)
		(stroke
			(width 0.072898)
			(type default)
		)
		(layer "B.Cu")
	)
	(gr_line
		(start 91.607132 -49.337722)
		(end 91.61272 -49.363884)
		(stroke
			(width 0.072898)
			(type default)
		)
		(layer "B.Cu")
	)
	(gr_line
		(start 91.607132 -49.337722)
		(end 91.612974 -49.310798)
		(stroke
			(width 0.072898)
			(type default)
		)
		(layer "B.Cu")
	)
	(gr_line
		(start 91.935554 -74.74458)
		(end 91.945714 -74.728832)
		(stroke
			(width 0.072898)
			(type default)
		)
		(layer "B.Cu")
	)
	(gr_line
		(start 91.945714 -74.728832)
		(end 91.94927 -74.710798)
		(stroke
			(width 0.072898)
			(type default)
		)
		(layer "B.Cu")
	)
	(gr_line
		(start 92.13215 -57.94121)
		(end 92.137992 -57.968388)
		(stroke
			(width 0.072898)
			(type default)
		)
		(layer "B.Cu")
	)
	(gr_line
		(start 92.132404 -57.994804)
		(end 92.137992 -57.968388)
		(stroke
			(width 0.072898)
			(type default)
		)
		(layer "B.Cu")
	)
	(gr_line
		(start 92.135452 -50.326544)
		(end 92.141294 -50.353468)
		(stroke
			(width 0.072898)
			(type default)
		)
		(layer "B.Cu")
	)
	(gr_line
		(start 92.135706 -50.37963)
		(end 92.141294 -50.353468)
		(stroke
			(width 0.072898)
			(type default)
		)
		(layer "B.Cu")
	)
	(gr_line
		(start 92.68587 -55.476902)
		(end 92.691458 -55.503826)
		(stroke
			(width 0.072898)
			(type default)
		)
		(layer "B.Cu")
	)
	(gr_line
		(start 92.68587 -55.476902)
		(end 92.691712 -55.449978)
		(stroke
			(width 0.072898)
			(type default)
		)
		(layer "B.Cu")
	)
	(gr_line
		(start 93.020642 -75.300332)
		(end 93.03131 -75.283822)
		(stroke
			(width 0.072898)
			(type default)
		)
		(layer "B.Cu")
	)
	(gr_line
		(start 93.03131 -75.283822)
		(end 93.035374 -75.264518)
		(stroke
			(width 0.072898)
			(type default)
		)
		(layer "B.Cu")
	)
	(gr_line
		(start 93.06941 -36.744402)
		(end 93.073728 -36.724082)
		(stroke
			(width 0.072898)
			(type default)
		)
		(layer "B.Cu")
	)
	(gr_line
		(start 93.073728 -36.724082)
		(end 93.085158 -36.707064)
		(stroke
			(width 0.072898)
			(type default)
		)
		(layer "B.Cu")
	)
	(gr_line
		(start 93.236542 -47.37608)
		(end 93.241368 -47.400464)
		(stroke
			(width 0.072898)
			(type default)
		)
		(layer "B.Cu")
	)
	(gr_line
		(start 93.236542 -47.37608)
		(end 93.241622 -47.35195)
		(stroke
			(width 0.072898)
			(type default)
		)
		(layer "B.Cu")
	)
	(gr_line
		(start 93.241622 -47.351442)
		(end 93.241622 -47.35195)
		(stroke
			(width 0.072898)
			(type default)
		)
		(layer "B.Cu")
	)
	(gr_line
		(start 93.862906 -59.516518)
		(end 93.868748 -59.543696)
		(stroke
			(width 0.072898)
			(type default)
		)
		(layer "B.Cu")
	)
	(gr_line
		(start 93.86316 -59.570112)
		(end 93.868748 -59.543696)
		(stroke
			(width 0.072898)
			(type default)
		)
		(layer "B.Cu")
	)
	(gr_line
		(start 94.119446 -50.251106)
		(end 94.124526 -50.226976)
		(stroke
			(width 0.072898)
			(type default)
		)
		(layer "B.Cu")
	)
	(gr_line
		(start 94.1197 -50.202592)
		(end 94.1197 -50.202846)
		(stroke
			(width 0.072898)
			(type default)
		)
		(layer "B.Cu")
	)
	(gr_line
		(start 94.1197 -50.202592)
		(end 94.124526 -50.226976)
		(stroke
			(width 0.072898)
			(type default)
		)
		(layer "B.Cu")
	)
	(gr_line
		(start 94.130876 -75.769216)
		(end 94.141544 -75.752706)
		(stroke
			(width 0.072898)
			(type default)
		)
		(layer "B.Cu")
	)
	(gr_line
		(start 94.141544 -75.752706)
		(end 94.145608 -75.733402)
		(stroke
			(width 0.072898)
			(type default)
		)
		(layer "B.Cu")
	)
	(gr_line
		(start 94.152466 -37.361114)
		(end 94.15653 -37.341048)
		(stroke
			(width 0.072898)
			(type default)
		)
		(layer "B.Cu")
	)
	(gr_line
		(start 94.15653 -37.341048)
		(end 94.168214 -37.323776)
		(stroke
			(width 0.072898)
			(type default)
		)
		(layer "B.Cu")
	)
	(gr_line
		(start 94.336362 -56.391302)
		(end 94.34195 -56.417464)
		(stroke
			(width 0.072898)
			(type default)
		)
		(layer "B.Cu")
	)
	(gr_line
		(start 94.336362 -56.391302)
		(end 94.342204 -56.364378)
		(stroke
			(width 0.072898)
			(type default)
		)
		(layer "B.Cu")
	)
	(gr_line
		(start 94.460568 -29.281374)
		(end 94.483682 -29.266388)
		(stroke
			(width 0.072898)
			(type default)
		)
		(layer "B.Cu")
	)
	(gr_line
		(start 94.483682 -29.266388)
		(end 94.498668 -29.243274)
		(stroke
			(width 0.072898)
			(type default)
		)
		(layer "B.Cu")
	)
	(gr_line
		(start 94.490032 -46.991016)
		(end 94.495366 -47.016924)
		(stroke
			(width 0.072898)
			(type default)
		)
		(layer "B.Cu")
	)
	(gr_line
		(start 94.490032 -46.991016)
		(end 94.49562 -46.964854)
		(stroke
			(width 0.072898)
			(type default)
		)
		(layer "B.Cu")
	)
	(gr_line
		(start 95.20809 -58.996072)
		(end 95.213678 -59.02198)
		(stroke
			(width 0.072898)
			(type default)
		)
		(layer "B.Cu")
	)
	(gr_line
		(start 95.208344 -59.047126)
		(end 95.213678 -59.02198)
		(stroke
			(width 0.072898)
			(type default)
		)
		(layer "B.Cu")
	)
	(gr_line
		(start 95.251778 -37.896292)
		(end 95.255588 -37.877496)
		(stroke
			(width 0.072898)
			(type default)
		)
		(layer "B.Cu")
	)
	(gr_line
		(start 95.254064 -76.172314)
		(end 95.263462 -76.15809)
		(stroke
			(width 0.072898)
			(type default)
		)
		(layer "B.Cu")
	)
	(gr_line
		(start 95.255588 -37.877496)
		(end 95.26651 -37.860986)
		(stroke
			(width 0.072898)
			(type default)
		)
		(layer "B.Cu")
	)
	(gr_line
		(start 95.263462 -76.15809)
		(end 95.267272 -76.140564)
		(stroke
			(width 0.072898)
			(type default)
		)
		(layer "B.Cu")
	)
	(gr_line
		(start 95.602298 -55.950358)
		(end 95.607886 -55.97652)
		(stroke
			(width 0.072898)
			(type default)
		)
		(layer "B.Cu")
	)
	(gr_line
		(start 95.602298 -55.950358)
		(end 95.60814 -55.923434)
		(stroke
			(width 0.072898)
			(type default)
		)
		(layer "B.Cu")
	)
	(gr_line
		(start 95.670624 -47.0027)
		(end 95.675958 -47.028354)
		(stroke
			(width 0.072898)
			(type default)
		)
		(layer "B.Cu")
	)
	(gr_line
		(start 95.670624 -47.0027)
		(end 95.676212 -46.977046)
		(stroke
			(width 0.072898)
			(type default)
		)
		(layer "B.Cu")
	)
	(gr_line
		(start 95.702374 -51.461924)
		(end 95.707962 -51.436524)
		(stroke
			(width 0.072898)
			(type default)
		)
		(layer "B.Cu")
	)
	(gr_line
		(start 95.702628 -51.410362)
		(end 95.707962 -51.436524)
		(stroke
			(width 0.072898)
			(type default)
		)
		(layer "B.Cu")
	)
	(gr_line
		(start 96.319086 -38.390068)
		(end 96.323404 -38.369748)
		(stroke
			(width 0.072898)
			(type default)
		)
		(layer "B.Cu")
	)
	(gr_line
		(start 96.323404 -38.369748)
		(end 96.334834 -38.352476)
		(stroke
			(width 0.072898)
			(type default)
		)
		(layer "B.Cu")
	)
	(gr_line
		(start 96.49206 -58.638694)
		(end 96.497394 -58.66384)
		(stroke
			(width 0.072898)
			(type default)
		)
		(layer "B.Cu")
	)
	(gr_line
		(start 96.492314 -58.68797)
		(end 96.497394 -58.66384)
		(stroke
			(width 0.072898)
			(type default)
		)
		(layer "B.Cu")
	)
	(gr_line
		(start 96.496886 -25.595834)
		(end 96.511872 -25.57272)
		(stroke
			(width 0.072898)
			(type default)
		)
		(layer "B.Cu")
	)
	(gr_line
		(start 96.511872 -25.57272)
		(end 96.534986 -25.557734)
		(stroke
			(width 0.072898)
			(type default)
		)
		(layer "B.Cu")
	)
	(gr_line
		(start 96.854264 -55.57774)
		(end 96.860614 -55.548022)
		(stroke
			(width 0.072898)
			(type default)
		)
		(layer "B.Cu")
	)
	(gr_line
		(start 96.854264 -55.57774)
		(end 96.861376 -55.611268)
		(stroke
			(width 0.072898)
			(type default)
		)
		(layer "B.Cu")
	)
	(gr_line
		(start 96.863408 -47.078646)
		(end 96.868742 -47.1043)
		(stroke
			(width 0.072898)
			(type default)
		)
		(layer "B.Cu")
	)
	(gr_line
		(start 96.863408 -47.078646)
		(end 96.868996 -47.052738)
		(stroke
			(width 0.072898)
			(type default)
		)
		(layer "B.Cu")
	)
	(gr_line
		(start 96.88068 -51.433476)
		(end 96.886014 -51.40833)
		(stroke
			(width 0.072898)
			(type default)
		)
		(layer "B.Cu")
	)
	(gr_line
		(start 96.88068 -51.382422)
		(end 96.886014 -51.40833)
		(stroke
			(width 0.072898)
			(type default)
		)
		(layer "B.Cu")
	)
	(gr_line
		(start 97.291652 -25.066244)
		(end 97.849944 -24.703786)
		(stroke
			(width 0.072898)
			(type default)
		)
		(layer "B.Cu")
	)
	(gr_line
		(start 97.398332 -38.874446)
		(end 97.402142 -38.85565)
		(stroke
			(width 0.072898)
			(type default)
		)
		(layer "B.Cu")
	)
	(gr_line
		(start 97.402142 -38.85565)
		(end 97.413064 -38.83914)
		(stroke
			(width 0.072898)
			(type default)
		)
		(layer "B.Cu")
	)
	(gr_line
		(start 97.432114 -25.3492)
		(end 97.639632 -25.393396)
		(stroke
			(width 0.072898)
			(type default)
		)
		(layer "B.Cu")
	)
	(gr_line
		(start 97.639632 -25.393396)
		(end 98.00717 -25.154636)
		(stroke
			(width 0.072898)
			(type default)
		)
		(layer "B.Cu")
	)
	(gr_line
		(start 97.763584 -58.405776)
		(end 97.768918 -58.38063)
		(stroke
			(width 0.072898)
			(type default)
		)
		(layer "B.Cu")
	)
	(gr_line
		(start 97.763584 -58.354722)
		(end 97.768918 -58.38063)
		(stroke
			(width 0.072898)
			(type default)
		)
		(layer "B.Cu")
	)
	(gr_line
		(start 98.00717 -25.154636)
		(end 98.051112 -24.947118)
		(stroke
			(width 0.072898)
			(type default)
		)
		(layer "B.Cu")
	)
	(gr_line
		(start 98.050858 -51.444906)
		(end 98.056446 -51.418998)
		(stroke
			(width 0.072898)
			(type default)
		)
		(layer "B.Cu")
	)
	(gr_line
		(start 98.051112 -51.39309)
		(end 98.056446 -51.418998)
		(stroke
			(width 0.072898)
			(type default)
		)
		(layer "B.Cu")
	)
	(gr_line
		(start 98.065844 -47.129446)
		(end 98.07067 -47.153576)
		(stroke
			(width 0.072898)
			(type default)
		)
		(layer "B.Cu")
	)
	(gr_line
		(start 98.065844 -47.129446)
		(end 98.070924 -47.105316)
		(stroke
			(width 0.072898)
			(type default)
		)
		(layer "B.Cu")
	)
	(gr_line
		(start 98.070924 -47.104808)
		(end 98.070924 -47.105316)
		(stroke
			(width 0.072898)
			(type default)
		)
		(layer "B.Cu")
	)
	(gr_line
		(start 98.08718 -55.359808)
		(end 98.092768 -55.38597)
		(stroke
			(width 0.072898)
			(type default)
		)
		(layer "B.Cu")
	)
	(gr_line
		(start 98.08718 -55.359808)
		(end 98.093022 -55.332884)
		(stroke
			(width 0.072898)
			(type default)
		)
		(layer "B.Cu")
	)
	(gr_line
		(start 98.28149 -24.423624)
		(end 98.840544 -24.060658)
		(stroke
			(width 0.072898)
			(type default)
		)
		(layer "B.Cu")
	)
	(gr_line
		(start 98.281998 -26.453338)
		(end 98.296984 -26.430478)
		(stroke
			(width 0.072898)
			(type default)
		)
		(layer "B.Cu")
	)
	(gr_line
		(start 98.296984 -26.430478)
		(end 98.319844 -26.415238)
		(stroke
			(width 0.072898)
			(type default)
		)
		(layer "B.Cu")
	)
	(gr_line
		(start 98.422714 -24.706072)
		(end 98.630232 -24.750014)
		(stroke
			(width 0.072898)
			(type default)
		)
		(layer "B.Cu")
	)
	(gr_line
		(start 98.478848 -39.480998)
		(end 98.482912 -39.460932)
		(stroke
			(width 0.072898)
			(type default)
		)
		(layer "B.Cu")
	)
	(gr_line
		(start 98.482912 -39.460932)
		(end 98.494596 -39.44366)
		(stroke
			(width 0.072898)
			(type default)
		)
		(layer "B.Cu")
	)
	(gr_line
		(start 98.630232 -24.750014)
		(end 98.99777 -24.511254)
		(stroke
			(width 0.072898)
			(type default)
		)
		(layer "B.Cu")
	)
	(gr_line
		(start 98.637852 -164.375846)
		(end 98.866706 -164.146992)
		(stroke
			(width 0.072898)
			(type default)
		)
		(layer "B.Cu")
	)
	(gr_line
		(start 98.637852 -163.4744)
		(end 98.866706 -163.703254)
		(stroke
			(width 0.072898)
			(type default)
		)
		(layer "B.Cu")
	)
	(gr_line
		(start 98.99777 -24.511254)
		(end 99.041712 -24.30399)
		(stroke
			(width 0.072898)
			(type default)
		)
		(layer "B.Cu")
	)
	(gr_line
		(start 99.039172 -58.34253)
		(end 99.045014 -58.369454)
		(stroke
			(width 0.072898)
			(type default)
		)
		(layer "B.Cu")
	)
	(gr_line
		(start 99.039426 -58.395616)
		(end 99.045014 -58.369454)
		(stroke
			(width 0.072898)
			(type default)
		)
		(layer "B.Cu")
	)
	(gr_line
		(start 99.238816 -51.43754)
		(end 99.243896 -51.41341)
		(stroke
			(width 0.072898)
			(type default)
		)
		(layer "B.Cu")
	)
	(gr_line
		(start 99.23907 -51.389026)
		(end 99.243896 -51.41341)
		(stroke
			(width 0.072898)
			(type default)
		)
		(layer "B.Cu")
	)
	(gr_line
		(start 99.27336 -23.77948)
		(end 99.830636 -23.417784)
		(stroke
			(width 0.072898)
			(type default)
		)
		(layer "B.Cu")
	)
	(gr_line
		(start 99.355402 -27.23007)
		(end 99.369372 -27.208988)
		(stroke
			(width 0.072898)
			(type default)
		)
		(layer "B.Cu")
	)
	(gr_line
		(start 99.369372 -27.208988)
		(end 99.389946 -27.195272)
		(stroke
			(width 0.072898)
			(type default)
		)
		(layer "B.Cu")
	)
	(gr_line
		(start 99.413314 -24.06269)
		(end 99.620832 -24.106886)
		(stroke
			(width 0.072898)
			(type default)
		)
		(layer "B.Cu")
	)
	(gr_line
		(start 99.582224 -39.992808)
		(end 99.586288 -39.972742)
		(stroke
			(width 0.072898)
			(type default)
		)
		(layer "B.Cu")
	)
	(gr_line
		(start 99.586288 -39.972742)
		(end 99.597972 -39.95547)
		(stroke
			(width 0.072898)
			(type default)
		)
		(layer "B.Cu")
	)
	(gr_line
		(start 99.620832 -24.106886)
		(end 99.98837 -23.868126)
		(stroke
			(width 0.072898)
			(type default)
		)
		(layer "B.Cu")
	)
	(gr_line
		(start 99.98837 -23.868126)
		(end 100.032312 -23.660862)
		(stroke
			(width 0.072898)
			(type default)
		)
		(layer "B.Cu")
	)
	(gr_line
		(start 100.173282 -28.314396)
		(end 100.185982 -28.295346)
		(stroke
			(width 0.072898)
			(type default)
		)
		(layer "B.Cu")
	)
	(gr_line
		(start 100.185982 -28.295346)
		(end 100.204778 -28.282646)
		(stroke
			(width 0.072898)
			(type default)
		)
		(layer "B.Cu")
	)
	(gr_line
		(start 100.262944 -23.13686)
		(end 100.820474 -22.77491)
		(stroke
			(width 0.072898)
			(type default)
		)
		(layer "B.Cu")
	)
	(gr_line
		(start 100.403914 -23.419562)
		(end 100.611432 -23.463504)
		(stroke
			(width 0.072898)
			(type default)
		)
		(layer "B.Cu")
	)
	(gr_line
		(start 100.611432 -23.463504)
		(end 100.97897 -23.224744)
		(stroke
			(width 0.072898)
			(type default)
		)
		(layer "B.Cu")
	)
	(gr_line
		(start 100.84689 -22.757892)
		(end 101.126544 -22.576282)
		(stroke
			(width 0.072898)
			(type default)
		)
		(layer "B.Cu")
	)
	(gr_line
		(start 100.94595 -29.31033)
		(end 100.959412 -29.290264)
		(stroke
			(width 0.072898)
			(type default)
		)
		(layer "B.Cu")
	)
	(gr_line
		(start 100.959412 -29.290264)
		(end 100.979478 -29.276802)
		(stroke
			(width 0.072898)
			(type default)
		)
		(layer "B.Cu")
	)
	(gr_line
		(start 100.97897 -23.224744)
		(end 101.022912 -23.01748)
		(stroke
			(width 0.072898)
			(type default)
		)
		(layer "B.Cu")
	)
	(gr_line
		(start 101.023674 -23.013924)
		(end 101.023674 -23.014178)
		(stroke
			(width 0.072898)
			(type default)
		)
		(layer "B.Cu")
	)
	(gr_line
		(start 101.023674 -23.013924)
		(end 101.320854 -22.821138)
		(stroke
			(width 0.072898)
			(type default)
		)
		(layer "B.Cu")
	)
	(gr_line
		(start 101.255068 -22.492716)
		(end 101.29901 -22.464268)
		(stroke
			(width 0.072898)
			(type default)
		)
		(layer "B.Cu")
	)
	(gr_line
		(start 101.628194 -30.40253)
		(end 101.640894 -30.38348)
		(stroke
			(width 0.072898)
			(type default)
		)
		(layer "B.Cu")
	)
	(gr_line
		(start 101.640894 -30.38348)
		(end 101.65969 -30.37078)
		(stroke
			(width 0.072898)
			(type default)
		)
		(layer "B.Cu")
	)
	(gr_line
		(start 101.834696 -39.597584)
		(end 102.06355 -39.826438)
		(stroke
			(width 0.072898)
			(type default)
		)
		(layer "B.Cu")
	)
	(gr_line
		(start 102.018084 -23.957026)
		(end 102.063296 -23.9268)
		(stroke
			(width 0.072898)
			(type default)
		)
		(layer "B.Cu")
	)
	(gr_line
		(start 102.074472 -31.82493)
		(end 102.087934 -31.804864)
		(stroke
			(width 0.072898)
			(type default)
		)
		(layer "B.Cu")
	)
	(gr_line
		(start 102.087934 -31.804864)
		(end 102.108 -31.791402)
		(stroke
			(width 0.072898)
			(type default)
		)
		(layer "B.Cu")
	)
	(gr_line
		(start 102.493826 -25.12568)
		(end 102.539292 -25.0952)
		(stroke
			(width 0.072898)
			(type default)
		)
		(layer "B.Cu")
	)
	(gr_line
		(start 102.507288 -39.826438)
		(end 102.736142 -39.597584)
		(stroke
			(width 0.072898)
			(type default)
		)
		(layer "B.Cu")
	)
	(gr_line
		(start 102.567232 -33.333944)
		(end 102.579932 -33.314894)
		(stroke
			(width 0.072898)
			(type default)
		)
		(layer "B.Cu")
	)
	(gr_line
		(start 102.579932 -33.314894)
		(end 102.599998 -33.301432)
		(stroke
			(width 0.072898)
			(type default)
		)
		(layer "B.Cu")
	)
	(gr_line
		(start 103.078534 -34.735262)
		(end 103.091234 -34.716466)
		(stroke
			(width 0.072898)
			(type default)
		)
		(layer "B.Cu")
	)
	(gr_line
		(start 103.091234 -34.716466)
		(end 103.110284 -34.703766)
		(stroke
			(width 0.072898)
			(type default)
		)
		(layer "B.Cu")
	)
	(gr_line
		(start 103.182674 -26.29408)
		(end 103.228394 -26.2636)
		(stroke
			(width 0.072898)
			(type default)
		)
		(layer "B.Cu")
	)
	(gr_line
		(start 103.643938 -29.047948)
		(end 103.661972 -29.035756)
		(stroke
			(width 0.072898)
			(type default)
		)
		(layer "B.Cu")
	)
	(gr_line
		(start 103.661972 -29.035756)
		(end 103.683816 -29.031184)
		(stroke
			(width 0.072898)
			(type default)
		)
		(layer "B.Cu")
	)
	(gr_line
		(start 103.73487 -27.43708)
		(end 103.78059 -27.4066)
		(stroke
			(width 0.072898)
			(type default)
		)
		(layer "B.Cu")
	)
	(gr_line
		(start 104.163876 -34.00171)
		(end 104.182672 -33.989264)
		(stroke
			(width 0.072898)
			(type default)
		)
		(layer "B.Cu")
	)
	(gr_line
		(start 104.182672 -33.989264)
		(end 104.204008 -33.9852)
		(stroke
			(width 0.072898)
			(type default)
		)
		(layer "B.Cu")
	)
	(gr_line
		(start 104.723946 -30.04693)
		(end 104.74198 -30.034738)
		(stroke
			(width 0.072898)
			(type default)
		)
		(layer "B.Cu")
	)
	(gr_line
		(start 104.74198 -30.034738)
		(end 104.76357 -30.03042)
		(stroke
			(width 0.072898)
			(type default)
		)
		(layer "B.Cu")
	)
	(gr_line
		(start 105.951782 -31.075376)
		(end 105.97007 -31.063438)
		(stroke
			(width 0.072898)
			(type default)
		)
		(layer "B.Cu")
	)
	(gr_line
		(start 105.97007 -31.063438)
		(end 105.991406 -31.05912)
		(stroke
			(width 0.072898)
			(type default)
		)
		(layer "B.Cu")
	)
	(gr_arc
		(start 106.93654 -33.744662)
		(mid 107.052046 -33.696666)
		(end 107.099862 -33.581086)
		(stroke
			(width 0.072898)
			(type default)
		)
		(layer "B.Cu")
	)
	(gr_arc
		(start 107.099862 -34.219134)
		(mid 107.052026 -34.103648)
		(end 106.93654 -34.055812)
		(stroke
			(width 0.072898)
			(type default)
		)
		(layer "B.Cu")
	)
	(gr_line
		(start 107.099862 -34.219134)
		(end 107.099862 -34.600134)
		(stroke
			(width 0.072898)
			(type default)
		)
		(layer "B.Cu")
	)
	(gr_line
		(start 107.099862 -33.200086)
		(end 107.099862 -33.581086)
		(stroke
			(width 0.072898)
			(type default)
		)
		(layer "B.Cu")
	)
	(gr_line
		(start 108.26115 -22.777958)
		(end 108.41101 -22.927818)
		(stroke
			(width 0.072898)
			(type default)
		)
		(layer "B.Cu")
	)
	(gr_line
		(start 108.41101 -22.927818)
		(end 108.84916 -22.927818)
		(stroke
			(width 0.072898)
			(type default)
		)
		(layer "B.Cu")
	)
	(gr_line
		(start 108.5723 -22.464268)
		(end 108.68787 -22.464268)
		(stroke
			(width 0.072898)
			(type default)
		)
		(layer "B.Cu")
	)
	(gr_arc
		(start 108.736638 -32.544512)
		(mid 108.852096 -32.496662)
		(end 108.89996 -32.38119)
		(stroke
			(width 0.072898)
			(type default)
		)
		(layer "B.Cu")
	)
	(gr_line
		(start 108.84916 -22.927818)
		(end 108.99902 -22.777958)
		(stroke
			(width 0.072898)
			(type default)
		)
		(layer "B.Cu")
	)
	(gr_arc
		(start 108.89996 -33.018984)
		(mid 108.852124 -32.903498)
		(end 108.736638 -32.855662)
		(stroke
			(width 0.072898)
			(type default)
		)
		(layer "B.Cu")
	)
	(gr_line
		(start 108.89996 -33.018984)
		(end 108.89996 -33.399984)
		(stroke
			(width 0.072898)
			(type default)
		)
		(layer "B.Cu")
	)
	(gr_line
		(start 108.89996 -32.00019)
		(end 108.89996 -32.38119)
		(stroke
			(width 0.072898)
			(type default)
		)
		(layer "B.Cu")
	)
	(gr_line
		(start 109.44225 -22.777958)
		(end 109.59211 -22.927818)
		(stroke
			(width 0.072898)
			(type default)
		)
		(layer "B.Cu")
	)
	(gr_line
		(start 109.59211 -22.927818)
		(end 110.03026 -22.927818)
		(stroke
			(width 0.072898)
			(type default)
		)
		(layer "B.Cu")
	)
	(gr_line
		(start 109.7534 -22.464268)
		(end 109.86897 -22.464268)
		(stroke
			(width 0.072898)
			(type default)
		)
		(layer "B.Cu")
	)
	(gr_line
		(start 110.03026 -22.927818)
		(end 110.18012 -22.777958)
		(stroke
			(width 0.072898)
			(type default)
		)
		(layer "B.Cu")
	)
	(gr_arc
		(start 110.536482 -33.744662)
		(mid 110.652154 -33.696757)
		(end 110.700058 -33.581086)
		(stroke
			(width 0.072898)
			(type default)
		)
		(layer "B.Cu")
	)
	(gr_line
		(start 110.62335 -22.777958)
		(end 110.77321 -22.927818)
		(stroke
			(width 0.072898)
			(type default)
		)
		(layer "B.Cu")
	)
	(gr_arc
		(start 110.700058 -34.219134)
		(mid 110.652222 -34.103648)
		(end 110.536736 -34.055812)
		(stroke
			(width 0.072898)
			(type default)
		)
		(layer "B.Cu")
	)
	(gr_line
		(start 110.700058 -34.219134)
		(end 110.700058 -34.600134)
		(stroke
			(width 0.072898)
			(type default)
		)
		(layer "B.Cu")
	)
	(gr_line
		(start 110.700058 -33.200086)
		(end 110.700058 -33.581086)
		(stroke
			(width 0.072898)
			(type default)
		)
		(layer "B.Cu")
	)
	(gr_line
		(start 110.77321 -22.927818)
		(end 111.21136 -22.927818)
		(stroke
			(width 0.072898)
			(type default)
		)
		(layer "B.Cu")
	)
	(gr_line
		(start 110.9345 -22.464268)
		(end 111.05007 -22.464268)
		(stroke
			(width 0.072898)
			(type default)
		)
		(layer "B.Cu")
	)
	(gr_line
		(start 111.21136 -22.927818)
		(end 111.36122 -22.777958)
		(stroke
			(width 0.072898)
			(type default)
		)
		(layer "B.Cu")
	)
	(gr_line
		(start 111.80445 -22.777958)
		(end 111.95431 -22.927818)
		(stroke
			(width 0.072898)
			(type default)
		)
		(layer "B.Cu")
	)
	(gr_line
		(start 111.95431 -22.927818)
		(end 112.39246 -22.927818)
		(stroke
			(width 0.072898)
			(type default)
		)
		(layer "B.Cu")
	)
	(gr_line
		(start 112.1156 -22.464268)
		(end 112.23117 -22.464268)
		(stroke
			(width 0.072898)
			(type default)
		)
		(layer "B.Cu")
	)
	(gr_arc
		(start 112.33658 -32.544512)
		(mid 112.452075 -32.496683)
		(end 112.499902 -32.38119)
		(stroke
			(width 0.072898)
			(type default)
		)
		(layer "B.Cu")
	)
	(gr_line
		(start 112.39246 -22.927818)
		(end 112.54232 -22.777958)
		(stroke
			(width 0.072898)
			(type default)
		)
		(layer "B.Cu")
	)
	(gr_arc
		(start 112.499902 -33.018984)
		(mid 112.452066 -32.903498)
		(end 112.33658 -32.855662)
		(stroke
			(width 0.072898)
			(type default)
		)
		(layer "B.Cu")
	)
	(gr_line
		(start 112.499902 -33.018984)
		(end 112.499902 -33.399984)
		(stroke
			(width 0.072898)
			(type default)
		)
		(layer "B.Cu")
	)
	(gr_line
		(start 112.499902 -32.00019)
		(end 112.499902 -32.38119)
		(stroke
			(width 0.072898)
			(type default)
		)
		(layer "B.Cu")
	)
	(gr_arc
		(start 114.136424 -33.744662)
		(mid 114.252069 -33.696742)
		(end 114.3 -33.581086)
		(stroke
			(width 0.072898)
			(type default)
		)
		(layer "B.Cu")
	)
	(gr_arc
		(start 114.3 -34.219134)
		(mid 114.252164 -34.103648)
		(end 114.136678 -34.055812)
		(stroke
			(width 0.072898)
			(type default)
		)
		(layer "B.Cu")
	)
	(gr_line
		(start 114.3 -34.219134)
		(end 114.3 -34.600134)
		(stroke
			(width 0.072898)
			(type default)
		)
		(layer "B.Cu")
	)
	(gr_line
		(start 114.3 -33.200086)
		(end 114.3 -33.581086)
		(stroke
			(width 0.072898)
			(type default)
		)
		(layer "B.Cu")
	)
	(gr_arc
		(start 115.936522 -32.544512)
		(mid 116.05199 -32.496668)
		(end 116.099844 -32.38119)
		(stroke
			(width 0.072898)
			(type default)
		)
		(layer "B.Cu")
	)
	(gr_arc
		(start 116.099844 -33.018984)
		(mid 116.052008 -32.903498)
		(end 115.936522 -32.855662)
		(stroke
			(width 0.072898)
			(type default)
		)
		(layer "B.Cu")
	)
	(gr_line
		(start 116.099844 -33.018984)
		(end 116.099844 -33.399984)
		(stroke
			(width 0.072898)
			(type default)
		)
		(layer "B.Cu")
	)
	(gr_line
		(start 116.099844 -32.00019)
		(end 116.099844 -32.38119)
		(stroke
			(width 0.072898)
			(type default)
		)
		(layer "B.Cu")
	)
	(gr_arc
		(start 117.736366 -33.744662)
		(mid 117.852049 -33.696763)
		(end 117.899942 -33.581086)
		(stroke
			(width 0.072898)
			(type default)
		)
		(layer "B.Cu")
	)
	(gr_arc
		(start 117.899942 -34.219134)
		(mid 117.852106 -34.103648)
		(end 117.73662 -34.055812)
		(stroke
			(width 0.072898)
			(type default)
		)
		(layer "B.Cu")
	)
	(gr_line
		(start 117.899942 -34.219134)
		(end 117.899942 -34.600134)
		(stroke
			(width 0.072898)
			(type default)
		)
		(layer "B.Cu")
	)
	(gr_line
		(start 117.899942 -33.200086)
		(end 117.899942 -33.581086)
		(stroke
			(width 0.072898)
			(type default)
		)
		(layer "B.Cu")
	)
	(gr_arc
		(start 119.536718 -32.544512)
		(mid 119.652189 -32.496669)
		(end 119.70004 -32.38119)
		(stroke
			(width 0.072898)
			(type default)
		)
		(layer "B.Cu")
	)
	(gr_line
		(start 119.70004 -43.819064)
		(end 119.70004 -44.200064)
		(stroke
			(width 0.072898)
			(type default)
		)
		(layer "B.Cu")
	)
	(gr_arc
		(start 119.70004 -43.181016)
		(mid 119.74795 -43.296682)
		(end 119.863616 -43.344592)
		(stroke
			(width 0.072898)
			(type default)
		)
		(layer "B.Cu")
	)
	(gr_line
		(start 119.70004 -42.800016)
		(end 119.70004 -43.181016)
		(stroke
			(width 0.072898)
			(type default)
		)
		(layer "B.Cu")
	)
	(gr_arc
		(start 119.70004 -33.018984)
		(mid 119.652204 -32.903498)
		(end 119.536718 -32.855662)
		(stroke
			(width 0.072898)
			(type default)
		)
		(layer "B.Cu")
	)
	(gr_line
		(start 119.70004 -33.018984)
		(end 119.70004 -33.399984)
		(stroke
			(width 0.072898)
			(type default)
		)
		(layer "B.Cu")
	)
	(gr_line
		(start 119.70004 -32.00019)
		(end 119.70004 -32.38119)
		(stroke
			(width 0.072898)
			(type default)
		)
		(layer "B.Cu")
	)
	(gr_arc
		(start 119.863362 -43.655742)
		(mid 119.747888 -43.703589)
		(end 119.70004 -43.819064)
		(stroke
			(width 0.072898)
			(type default)
		)
		(layer "B.Cu")
	)
	(gr_arc
		(start 128.536446 -33.744662)
		(mid 128.652112 -33.696752)
		(end 128.700022 -33.581086)
		(stroke
			(width 0.072898)
			(type default)
		)
		(layer "B.Cu")
	)
	(gr_arc
		(start 128.700022 -34.219134)
		(mid 128.652198 -34.103626)
		(end 128.5367 -34.055812)
		(stroke
			(width 0.072898)
			(type default)
		)
		(layer "B.Cu")
	)
	(gr_line
		(start 128.700022 -34.219134)
		(end 128.700022 -34.600134)
		(stroke
			(width 0.072898)
			(type default)
		)
		(layer "B.Cu")
	)
	(gr_line
		(start 128.700022 -33.200086)
		(end 128.700022 -33.581086)
		(stroke
			(width 0.072898)
			(type default)
		)
		(layer "B.Cu")
	)
	(gr_arc
		(start 130.336544 -32.544512)
		(mid 130.45203 -32.496676)
		(end 130.499866 -32.38119)
		(stroke
			(width 0.072898)
			(type default)
		)
		(layer "B.Cu")
	)
	(gr_arc
		(start 130.499866 -33.018984)
		(mid 130.452027 -32.903493)
		(end 130.336544 -32.855662)
		(stroke
			(width 0.072898)
			(type default)
		)
		(layer "B.Cu")
	)
	(gr_line
		(start 130.499866 -33.018984)
		(end 130.499866 -33.399984)
		(stroke
			(width 0.072898)
			(type default)
		)
		(layer "B.Cu")
	)
	(gr_line
		(start 130.499866 -32.00019)
		(end 130.499866 -32.38119)
		(stroke
			(width 0.072898)
			(type default)
		)
		(layer "B.Cu")
	)
	(gr_arc
		(start 132.136388 -33.744662)
		(mid 132.252054 -33.696752)
		(end 132.299964 -33.581086)
		(stroke
			(width 0.072898)
			(type default)
		)
		(layer "B.Cu")
	)
	(gr_arc
		(start 132.299964 -34.219134)
		(mid 132.252143 -34.103611)
		(end 132.136642 -34.055812)
		(stroke
			(width 0.072898)
			(type default)
		)
		(layer "B.Cu")
	)
	(gr_line
		(start 132.299964 -34.219134)
		(end 132.299964 -34.600134)
		(stroke
			(width 0.072898)
			(type default)
		)
		(layer "B.Cu")
	)
	(gr_line
		(start 132.299964 -33.200086)
		(end 132.299964 -33.581086)
		(stroke
			(width 0.072898)
			(type default)
		)
		(layer "B.Cu")
	)
	(gr_arc
		(start 133.93674 -32.544512)
		(mid 134.052226 -32.496676)
		(end 134.100062 -32.38119)
		(stroke
			(width 0.072898)
			(type default)
		)
		(layer "B.Cu")
	)
	(gr_arc
		(start 134.100062 -33.018984)
		(mid 134.052223 -32.903494)
		(end 133.93674 -32.855662)
		(stroke
			(width 0.072898)
			(type default)
		)
		(layer "B.Cu")
	)
	(gr_line
		(start 134.100062 -33.018984)
		(end 134.100062 -33.399984)
		(stroke
			(width 0.072898)
			(type default)
		)
		(layer "B.Cu")
	)
	(gr_line
		(start 134.100062 -32.00019)
		(end 134.100062 -32.38119)
		(stroke
			(width 0.072898)
			(type default)
		)
		(layer "B.Cu")
	)
	(gr_arc
		(start 135.73633 -33.744662)
		(mid 135.851996 -33.696752)
		(end 135.899906 -33.581086)
		(stroke
			(width 0.072898)
			(type default)
		)
		(layer "B.Cu")
	)
	(gr_arc
		(start 135.899906 -34.219134)
		(mid 135.852081 -34.103632)
		(end 135.736584 -34.055812)
		(stroke
			(width 0.072898)
			(type default)
		)
		(layer "B.Cu")
	)
	(gr_line
		(start 135.899906 -34.219134)
		(end 135.899906 -34.600134)
		(stroke
			(width 0.072898)
			(type default)
		)
		(layer "B.Cu")
	)
	(gr_line
		(start 135.899906 -33.200086)
		(end 135.899906 -33.581086)
		(stroke
			(width 0.072898)
			(type default)
		)
		(layer "B.Cu")
	)
	(gr_arc
		(start 137.536682 -32.544512)
		(mid 137.652168 -32.496676)
		(end 137.700004 -32.38119)
		(stroke
			(width 0.072898)
			(type default)
		)
		(layer "B.Cu")
	)
	(gr_arc
		(start 137.700004 -33.018984)
		(mid 137.652161 -32.903515)
		(end 137.536682 -32.855662)
		(stroke
			(width 0.072898)
			(type default)
		)
		(layer "B.Cu")
	)
	(gr_line
		(start 137.700004 -33.018984)
		(end 137.700004 -33.399984)
		(stroke
			(width 0.072898)
			(type default)
		)
		(layer "B.Cu")
	)
	(gr_line
		(start 137.700004 -32.00019)
		(end 137.700004 -32.38119)
		(stroke
			(width 0.072898)
			(type default)
		)
		(layer "B.Cu")
	)
	(gr_arc
		(start 139.336272 -33.744662)
		(mid 139.451938 -33.696752)
		(end 139.499848 -33.581086)
		(stroke
			(width 0.072898)
			(type default)
		)
		(layer "B.Cu")
	)
	(gr_arc
		(start 139.499848 -34.219134)
		(mid 139.452026 -34.103617)
		(end 139.336526 -34.055812)
		(stroke
			(width 0.072898)
			(type default)
		)
		(layer "B.Cu")
	)
	(gr_line
		(start 139.499848 -34.219134)
		(end 139.499848 -34.600134)
		(stroke
			(width 0.072898)
			(type default)
		)
		(layer "B.Cu")
	)
	(gr_line
		(start 139.499848 -33.200086)
		(end 139.499848 -33.581086)
		(stroke
			(width 0.072898)
			(type default)
		)
		(layer "B.Cu")
	)
	(gr_arc
		(start 141.136624 -32.544512)
		(mid 141.25211 -32.496676)
		(end 141.299946 -32.38119)
		(stroke
			(width 0.072898)
			(type default)
		)
		(layer "B.Cu")
	)
	(gr_arc
		(start 141.299946 -33.018984)
		(mid 141.252106 -32.9035)
		(end 141.136624 -32.855662)
		(stroke
			(width 0.072898)
			(type default)
		)
		(layer "B.Cu")
	)
	(gr_line
		(start 141.299946 -33.018984)
		(end 141.299946 -33.399984)
		(stroke
			(width 0.072898)
			(type default)
		)
		(layer "B.Cu")
	)
	(gr_line
		(start 141.299946 -32.00019)
		(end 141.299946 -32.38119)
		(stroke
			(width 0.072898)
			(type default)
		)
		(layer "B.Cu")
	)
	(gr_line
		(start 142.261082 -30.039564)
		(end 142.352268 -30.057852)
		(stroke
			(width 0.072898)
			(type default)
		)
		(layer "B.Cu")
	)
	(gr_line
		(start 142.352268 -30.057852)
		(end 142.403322 -30.136338)
		(stroke
			(width 0.072898)
			(type default)
		)
		(layer "B.Cu")
	)
	(gr_line
		(start 142.65148 -28.882848)
		(end 142.672816 -28.887166)
		(stroke
			(width 0.072898)
			(type default)
		)
		(layer "B.Cu")
	)
	(gr_line
		(start 142.672816 -28.887166)
		(end 142.69085 -28.89885)
		(stroke
			(width 0.072898)
			(type default)
		)
		(layer "B.Cu")
	)
	(gr_line
		(start 143.36903 -29.33954)
		(end 143.392144 -29.354526)
		(stroke
			(width 0.072898)
			(type default)
		)
		(layer "B.Cu")
	)
	(gr_line
		(start 143.392144 -29.354526)
		(end 143.40713 -29.37764)
		(stroke
			(width 0.072898)
			(type default)
		)
		(layer "B.Cu")
	)
	(gr_line
		(start 143.454374 -27.859482)
		(end 143.47571 -27.863546)
		(stroke
			(width 0.072898)
			(type default)
		)
		(layer "B.Cu")
	)
	(gr_line
		(start 143.47571 -27.863546)
		(end 143.493744 -27.875738)
		(stroke
			(width 0.072898)
			(type default)
		)
		(layer "B.Cu")
	)
	(gr_line
		(start 143.843756 -26.570178)
		(end 143.866108 -26.57475)
		(stroke
			(width 0.072898)
			(type default)
		)
		(layer "B.Cu")
	)
	(gr_line
		(start 143.866108 -26.57475)
		(end 143.884142 -26.586942)
		(stroke
			(width 0.072898)
			(type default)
		)
		(layer "B.Cu")
	)
	(gr_line
		(start 144.502886 -28.548076)
		(end 144.522952 -28.561538)
		(stroke
			(width 0.072898)
			(type default)
		)
		(layer "B.Cu")
	)
	(gr_line
		(start 144.522952 -28.561538)
		(end 144.536414 -28.581604)
		(stroke
			(width 0.072898)
			(type default)
		)
		(layer "B.Cu")
	)
	(gr_line
		(start 144.708118 -25.547066)
		(end 144.729708 -25.551384)
		(stroke
			(width 0.072898)
			(type default)
		)
		(layer "B.Cu")
	)
	(gr_line
		(start 144.729708 -25.551384)
		(end 144.747742 -25.563576)
		(stroke
			(width 0.072898)
			(type default)
		)
		(layer "B.Cu")
	)
	(gr_line
		(start 145.615152 -24.55672)
		(end 145.636742 -24.561038)
		(stroke
			(width 0.072898)
			(type default)
		)
		(layer "B.Cu")
	)
	(gr_line
		(start 145.636742 -24.561038)
		(end 145.654776 -24.57323)
		(stroke
			(width 0.072898)
			(type default)
		)
		(layer "B.Cu")
	)
	(gr_line
		(start 145.911062 -27.937968)
		(end 145.931128 -27.95143)
		(stroke
			(width 0.072898)
			(type default)
		)
		(layer "B.Cu")
	)
	(gr_line
		(start 145.931128 -27.95143)
		(end 145.94459 -27.971496)
		(stroke
			(width 0.072898)
			(type default)
		)
		(layer "B.Cu")
	)
	(gr_line
		(start 146.43227 -23.1521)
		(end 146.45513 -23.156672)
		(stroke
			(width 0.072898)
			(type default)
		)
		(layer "B.Cu")
	)
	(gr_line
		(start 146.45513 -23.156672)
		(end 146.47418 -23.169626)
		(stroke
			(width 0.072898)
			(type default)
		)
		(layer "B.Cu")
	)
	(gr_line
		(start 146.82851 -21.692616)
		(end 146.851116 -21.697188)
		(stroke
			(width 0.072898)
			(type default)
		)
		(layer "B.Cu")
	)
	(gr_line
		(start 146.851116 -21.697188)
		(end 146.869912 -21.709888)
		(stroke
			(width 0.072898)
			(type default)
		)
		(layer "B.Cu")
	)
	(gr_line
		(start 146.934174 -27.021028)
		(end 146.95424 -27.03449)
		(stroke
			(width 0.072898)
			(type default)
		)
		(layer "B.Cu")
	)
	(gr_line
		(start 146.95424 -27.03449)
		(end 146.967702 -27.054556)
		(stroke
			(width 0.072898)
			(type default)
		)
		(layer "B.Cu")
	)
	(gr_line
		(start 147.73148 -38.343078)
		(end 147.742148 -38.359588)
		(stroke
			(width 0.072898)
			(type default)
		)
		(layer "B.Cu")
	)
	(gr_line
		(start 147.742148 -38.359588)
		(end 147.746212 -38.378638)
		(stroke
			(width 0.072898)
			(type default)
		)
		(layer "B.Cu")
	)
	(gr_line
		(start 147.999704 -26.138886)
		(end 148.017738 -26.151078)
		(stroke
			(width 0.072898)
			(type default)
		)
		(layer "B.Cu")
	)
	(gr_line
		(start 148.017738 -26.151078)
		(end 148.029422 -26.168604)
		(stroke
			(width 0.072898)
			(type default)
		)
		(layer "B.Cu")
	)
	(gr_line
		(start 148.347938 -43.465242)
		(end 148.438616 -43.893994)
		(stroke
			(width 0.072898)
			(type default)
		)
		(layer "B.Cu")
	)
	(gr_line
		(start 148.347938 -43.465242)
		(end 148.463508 -43.287696)
		(stroke
			(width 0.072898)
			(type default)
		)
		(layer "B.Cu")
	)
	(gr_line
		(start 148.438616 -43.893994)
		(end 148.616162 -44.009564)
		(stroke
			(width 0.072898)
			(type default)
		)
		(layer "B.Cu")
	)
	(gr_line
		(start 148.592286 -44.620688)
		(end 148.682964 -45.04944)
		(stroke
			(width 0.072898)
			(type default)
		)
		(layer "B.Cu")
	)
	(gr_line
		(start 148.592286 -44.620688)
		(end 148.707856 -44.443142)
		(stroke
			(width 0.072898)
			(type default)
		)
		(layer "B.Cu")
	)
	(gr_line
		(start 148.682964 -45.04944)
		(end 148.860764 -45.165264)
		(stroke
			(width 0.072898)
			(type default)
		)
		(layer "B.Cu")
	)
	(gr_line
		(start 148.778214 -43.259248)
		(end 148.915374 -43.907964)
		(stroke
			(width 0.072898)
			(type default)
		)
		(layer "B.Cu")
	)
	(gr_line
		(start 148.836634 -45.776388)
		(end 148.927312 -46.204886)
		(stroke
			(width 0.072898)
			(type default)
		)
		(layer "B.Cu")
	)
	(gr_line
		(start 148.836634 -45.776388)
		(end 148.952458 -45.598588)
		(stroke
			(width 0.072898)
			(type default)
		)
		(layer "B.Cu")
	)
	(gr_line
		(start 148.927312 -46.204886)
		(end 149.105112 -46.32071)
		(stroke
			(width 0.072898)
			(type default)
		)
		(layer "B.Cu")
	)
	(gr_line
		(start 149.022562 -44.414694)
		(end 149.159722 -45.06341)
		(stroke
			(width 0.072898)
			(type default)
		)
		(layer "B.Cu")
	)
	(gr_line
		(start 149.080982 -46.931834)
		(end 149.17166 -47.360586)
		(stroke
			(width 0.072898)
			(type default)
		)
		(layer "B.Cu")
	)
	(gr_line
		(start 149.080982 -46.931834)
		(end 149.196806 -46.754034)
		(stroke
			(width 0.072898)
			(type default)
		)
		(layer "B.Cu")
	)
	(gr_line
		(start 149.17166 -47.360586)
		(end 149.34946 -47.47641)
		(stroke
			(width 0.072898)
			(type default)
		)
		(layer "B.Cu")
	)
	(gr_line
		(start 149.266402 -38.400736)
		(end 149.276562 -38.416484)
		(stroke
			(width 0.072898)
			(type default)
		)
		(layer "B.Cu")
	)
	(gr_line
		(start 149.26691 -45.57014)
		(end 149.404324 -46.220126)
		(stroke
			(width 0.072898)
			(type default)
		)
		(layer "B.Cu")
	)
	(gr_line
		(start 149.276562 -38.416484)
		(end 149.280118 -38.434264)
		(stroke
			(width 0.072898)
			(type default)
		)
		(layer "B.Cu")
	)
	(gr_line
		(start 149.511258 -46.72457)
		(end 149.648926 -47.37608)
		(stroke
			(width 0.072898)
			(type default)
		)
		(layer "B.Cu")
	)
	(gr_line
		(start 149.533102 -41.880536)
		(end 149.623526 -42.309288)
		(stroke
			(width 0.072898)
			(type default)
		)
		(layer "B.Cu")
	)
	(gr_line
		(start 149.533102 -41.880536)
		(end 149.648926 -41.70299)
		(stroke
			(width 0.072898)
			(type default)
		)
		(layer "B.Cu")
	)
	(gr_line
		(start 149.540976 -25.230074)
		(end 149.559264 -25.24252)
		(stroke
			(width 0.072898)
			(type default)
		)
		(layer "B.Cu")
	)
	(gr_line
		(start 149.559264 -25.24252)
		(end 149.57171 -25.260808)
		(stroke
			(width 0.072898)
			(type default)
		)
		(layer "B.Cu")
	)
	(gr_line
		(start 149.623526 -42.309288)
		(end 149.801326 -42.425112)
		(stroke
			(width 0.072898)
			(type default)
		)
		(layer "B.Cu")
	)
	(gr_line
		(start 149.776942 -43.036236)
		(end 149.867366 -43.464734)
		(stroke
			(width 0.072898)
			(type default)
		)
		(layer "B.Cu")
	)
	(gr_line
		(start 149.776942 -43.036236)
		(end 149.892766 -42.858436)
		(stroke
			(width 0.072898)
			(type default)
		)
		(layer "B.Cu")
	)
	(gr_line
		(start 149.867366 -43.464734)
		(end 150.045166 -43.580812)
		(stroke
			(width 0.072898)
			(type default)
		)
		(layer "B.Cu")
	)
	(gr_line
		(start 149.963632 -41.674542)
		(end 150.100284 -42.323766)
		(stroke
			(width 0.072898)
			(type default)
		)
		(layer "B.Cu")
	)
	(gr_line
		(start 150.020782 -44.191682)
		(end 150.111206 -44.620434)
		(stroke
			(width 0.072898)
			(type default)
		)
		(layer "B.Cu")
	)
	(gr_line
		(start 150.020782 -44.191682)
		(end 150.136606 -44.014136)
		(stroke
			(width 0.072898)
			(type default)
		)
		(layer "B.Cu")
	)
	(gr_line
		(start 150.111206 -44.620434)
		(end 150.288752 -44.736512)
		(stroke
			(width 0.072898)
			(type default)
		)
		(layer "B.Cu")
	)
	(gr_line
		(start 150.207218 -42.829988)
		(end 150.34387 -43.47845)
		(stroke
			(width 0.072898)
			(type default)
		)
		(layer "B.Cu")
	)
	(gr_line
		(start 150.264368 -45.347382)
		(end 150.354792 -45.776134)
		(stroke
			(width 0.072898)
			(type default)
		)
		(layer "B.Cu")
	)
	(gr_line
		(start 150.264368 -45.347382)
		(end 150.380192 -45.169836)
		(stroke
			(width 0.072898)
			(type default)
		)
		(layer "B.Cu")
	)
	(gr_line
		(start 150.354792 -45.776134)
		(end 150.532592 -45.892212)
		(stroke
			(width 0.072898)
			(type default)
		)
		(layer "B.Cu")
	)
	(gr_line
		(start 150.451058 -43.986958)
		(end 150.587964 -44.635928)
		(stroke
			(width 0.072898)
			(type default)
		)
		(layer "B.Cu")
	)
	(gr_line
		(start 150.619968 -24.21636)
		(end 150.638002 -24.228552)
		(stroke
			(width 0.072898)
			(type default)
		)
		(layer "B.Cu")
	)
	(gr_line
		(start 150.638002 -24.228552)
		(end 150.649686 -24.246078)
		(stroke
			(width 0.072898)
			(type default)
		)
		(layer "B.Cu")
	)
	(gr_line
		(start 150.69439 -45.13961)
		(end 150.832058 -45.791882)
		(stroke
			(width 0.072898)
			(type default)
		)
		(layer "B.Cu")
	)
	(gr_line
		(start 151.295862 -38.719506)
		(end 151.308054 -38.73754)
		(stroke
			(width 0.072898)
			(type default)
		)
		(layer "B.Cu")
	)
	(gr_line
		(start 151.308054 -38.73754)
		(end 151.312372 -38.75913)
		(stroke
			(width 0.072898)
			(type default)
		)
		(layer "B.Cu")
	)
	(gr_line
		(start 151.679656 -43.012868)
		(end 151.765762 -43.442382)
		(stroke
			(width 0.072898)
			(type default)
		)
		(layer "B.Cu")
	)
	(gr_line
		(start 151.679656 -43.012868)
		(end 151.805386 -42.8244)
		(stroke
			(width 0.072898)
			(type default)
		)
		(layer "B.Cu")
	)
	(gr_line
		(start 151.765762 -43.442382)
		(end 151.954484 -43.568112)
		(stroke
			(width 0.072898)
			(type default)
		)
		(layer "B.Cu")
	)
	(gr_line
		(start 151.915368 -44.19092)
		(end 152.001474 -44.620434)
		(stroke
			(width 0.072898)
			(type default)
		)
		(layer "B.Cu")
	)
	(gr_line
		(start 151.915368 -44.19092)
		(end 152.041352 -44.002198)
		(stroke
			(width 0.072898)
			(type default)
		)
		(layer "B.Cu")
	)
	(gr_line
		(start 152.001474 -44.620434)
		(end 152.190196 -44.746164)
		(stroke
			(width 0.072898)
			(type default)
		)
		(layer "B.Cu")
	)
	(gr_line
		(start 152.120092 -42.797476)
		(end 152.254712 -43.471084)
		(stroke
			(width 0.072898)
			(type default)
		)
		(layer "B.Cu")
	)
	(gr_line
		(start 152.15108 -45.368972)
		(end 152.237186 -45.798486)
		(stroke
			(width 0.072898)
			(type default)
		)
		(layer "B.Cu")
	)
	(gr_line
		(start 152.15108 -45.368972)
		(end 152.27681 -45.18025)
		(stroke
			(width 0.072898)
			(type default)
		)
		(layer "B.Cu")
	)
	(gr_line
		(start 152.237186 -45.798486)
		(end 152.425654 -45.924216)
		(stroke
			(width 0.072898)
			(type default)
		)
		(layer "B.Cu")
	)
	(gr_line
		(start 152.35555 -43.97502)
		(end 152.49017 -44.64812)
		(stroke
			(width 0.072898)
			(type default)
		)
		(layer "B.Cu")
	)
	(gr_line
		(start 152.386792 -46.547024)
		(end 152.472898 -46.976792)
		(stroke
			(width 0.072898)
			(type default)
		)
		(layer "B.Cu")
	)
	(gr_line
		(start 152.386792 -46.547024)
		(end 152.512522 -46.358302)
		(stroke
			(width 0.072898)
			(type default)
		)
		(layer "B.Cu")
	)
	(gr_line
		(start 152.472898 -46.976792)
		(end 152.656286 -47.09922)
		(stroke
			(width 0.072898)
			(type default)
		)
		(layer "B.Cu")
	)
	(gr_line
		(start 152.591516 -45.154596)
		(end 152.725628 -45.825918)
		(stroke
			(width 0.072898)
			(type default)
		)
		(layer "B.Cu")
	)
	(gr_line
		(start 152.827228 -46.332394)
		(end 152.968706 -47.039784)
		(stroke
			(width 0.072898)
			(type default)
		)
		(layer "B.Cu")
	)
	(gr_line
		(start 152.89022 -40.18534)
		(end 152.976072 -40.614854)
		(stroke
			(width 0.072898)
			(type default)
		)
		(layer "B.Cu")
	)
	(gr_line
		(start 152.89022 -40.18534)
		(end 153.007822 -40.00881)
		(stroke
			(width 0.072898)
			(type default)
		)
		(layer "B.Cu")
	)
	(gr_line
		(start 152.966928 -47.04207)
		(end 152.968706 -47.039784)
		(stroke
			(width 0.072898)
			(type default)
		)
		(layer "B.Cu")
	)
	(gr_line
		(start 152.976072 -40.614854)
		(end 153.152348 -40.732456)
		(stroke
			(width 0.072898)
			(type default)
		)
		(layer "B.Cu")
	)
	(gr_line
		(start 153.040842 -38.617906)
		(end 153.053034 -38.63594)
		(stroke
			(width 0.072898)
			(type default)
		)
		(layer "B.Cu")
	)
	(gr_line
		(start 153.053034 -38.63594)
		(end 153.057098 -38.657276)
		(stroke
			(width 0.072898)
			(type default)
		)
		(layer "B.Cu")
	)
	(gr_line
		(start 153.121614 -41.34358)
		(end 153.20772 -41.773094)
		(stroke
			(width 0.072898)
			(type default)
		)
		(layer "B.Cu")
	)
	(gr_line
		(start 153.121614 -41.34358)
		(end 153.23947 -41.16705)
		(stroke
			(width 0.072898)
			(type default)
		)
		(layer "B.Cu")
	)
	(gr_line
		(start 153.20772 -41.773094)
		(end 153.383996 -41.890696)
		(stroke
			(width 0.072898)
			(type default)
		)
		(layer "B.Cu")
	)
	(gr_line
		(start 153.322528 -39.982902)
		(end 153.453084 -40.635428)
		(stroke
			(width 0.072898)
			(type default)
		)
		(layer "B.Cu")
	)
	(gr_line
		(start 153.353262 -42.501566)
		(end 153.439368 -42.931334)
		(stroke
			(width 0.072898)
			(type default)
		)
		(layer "B.Cu")
	)
	(gr_line
		(start 153.353262 -42.501566)
		(end 153.470864 -42.325036)
		(stroke
			(width 0.072898)
			(type default)
		)
		(layer "B.Cu")
	)
	(gr_line
		(start 153.439368 -42.931334)
		(end 153.615898 -43.048936)
		(stroke
			(width 0.072898)
			(type default)
		)
		(layer "B.Cu")
	)
	(gr_line
		(start 153.554176 -41.141142)
		(end 153.684732 -41.793668)
		(stroke
			(width 0.072898)
			(type default)
		)
		(layer "B.Cu")
	)
	(gr_line
		(start 153.58491 -43.659806)
		(end 153.671016 -44.089574)
		(stroke
			(width 0.072898)
			(type default)
		)
		(layer "B.Cu")
	)
	(gr_line
		(start 153.58491 -43.659806)
		(end 153.702766 -43.483276)
		(stroke
			(width 0.072898)
			(type default)
		)
		(layer "B.Cu")
	)
	(gr_line
		(start 153.671016 -44.089574)
		(end 153.847292 -44.206922)
		(stroke
			(width 0.072898)
			(type default)
		)
		(layer "B.Cu")
	)
	(gr_line
		(start 153.78557 -42.298366)
		(end 153.916634 -42.95267)
		(stroke
			(width 0.072898)
			(type default)
		)
		(layer "B.Cu")
	)
	(gr_line
		(start 154.017472 -43.457876)
		(end 154.148028 -44.110148)
		(stroke
			(width 0.072898)
			(type default)
		)
		(layer "B.Cu")
	)
	(gr_line
		(start 154.560016 -40.532304)
		(end 154.646122 -40.962072)
		(stroke
			(width 0.072898)
			(type default)
		)
		(layer "B.Cu")
	)
	(gr_line
		(start 154.560016 -40.532304)
		(end 154.677618 -40.356028)
		(stroke
			(width 0.072898)
			(type default)
		)
		(layer "B.Cu")
	)
	(gr_line
		(start 154.626564 -38.543738)
		(end 154.638756 -38.561772)
		(stroke
			(width 0.072898)
			(type default)
		)
		(layer "B.Cu")
	)
	(gr_line
		(start 154.638756 -38.561772)
		(end 154.643074 -38.583362)
		(stroke
			(width 0.072898)
			(type default)
		)
		(layer "B.Cu")
	)
	(gr_line
		(start 154.646122 -40.962072)
		(end 154.822398 -41.07942)
		(stroke
			(width 0.072898)
			(type default)
		)
		(layer "B.Cu")
	)
	(gr_line
		(start 154.685238 -126.453138)
		(end 154.689048 -126.472696)
		(stroke
			(width 0.072898)
			(type default)
		)
		(layer "B.Cu")
	)
	(gr_line
		(start 154.685238 -126.453138)
		(end 154.689302 -126.432564)
		(stroke
			(width 0.072898)
			(type default)
		)
		(layer "B.Cu")
	)
	(gr_line
		(start 154.791664 -41.690544)
		(end 154.877516 -42.120058)
		(stroke
			(width 0.072898)
			(type default)
		)
		(layer "B.Cu")
	)
	(gr_line
		(start 154.791664 -41.690544)
		(end 154.909266 -41.514268)
		(stroke
			(width 0.072898)
			(type default)
		)
		(layer "B.Cu")
	)
	(gr_line
		(start 154.825446 -41.081452)
		(end 154.877262 -41.340786)
		(stroke
			(width 0.072898)
			(type default)
		)
		(layer "B.Cu")
	)
	(gr_line
		(start 154.877516 -42.120058)
		(end 155.054046 -42.237914)
		(stroke
			(width 0.072898)
			(type default)
		)
		(layer "B.Cu")
	)
	(gr_line
		(start 154.992832 -40.333168)
		(end 155.121864 -40.978836)
		(stroke
			(width 0.072898)
			(type default)
		)
		(layer "B.Cu")
	)
	(gr_line
		(start 155.023312 -42.848784)
		(end 155.109164 -43.278298)
		(stroke
			(width 0.072898)
			(type default)
		)
		(layer "B.Cu")
	)
	(gr_line
		(start 155.023312 -42.848784)
		(end 155.140914 -42.672508)
		(stroke
			(width 0.072898)
			(type default)
		)
		(layer "B.Cu")
	)
	(gr_line
		(start 155.109164 -43.278298)
		(end 155.285694 -43.396154)
		(stroke
			(width 0.072898)
			(type default)
		)
		(layer "B.Cu")
	)
	(gr_line
		(start 155.129992 -41.01719)
		(end 155.14447 -41.090596)
		(stroke
			(width 0.072898)
			(type default)
		)
		(layer "B.Cu")
	)
	(gr_line
		(start 155.22448 -41.491662)
		(end 155.353766 -42.138346)
		(stroke
			(width 0.072898)
			(type default)
		)
		(layer "B.Cu")
	)
	(gr_line
		(start 155.25496 -44.00677)
		(end 155.340812 -44.436538)
		(stroke
			(width 0.072898)
			(type default)
		)
		(layer "B.Cu")
	)
	(gr_line
		(start 155.25496 -44.00677)
		(end 155.372562 -43.830494)
		(stroke
			(width 0.072898)
			(type default)
		)
		(layer "B.Cu")
	)
	(gr_line
		(start 155.340812 -44.436538)
		(end 155.517342 -44.554394)
		(stroke
			(width 0.072898)
			(type default)
		)
		(layer "B.Cu")
	)
	(gr_line
		(start 155.372054 -43.814238)
		(end 155.374594 -43.827446)
		(stroke
			(width 0.072898)
			(type default)
		)
		(layer "B.Cu")
	)
	(gr_line
		(start 155.456128 -42.649902)
		(end 155.585668 -43.297856)
		(stroke
			(width 0.072898)
			(type default)
		)
		(layer "B.Cu")
	)
	(gr_line
		(start 155.679394 -43.764454)
		(end 155.680156 -43.768264)
		(stroke
			(width 0.072898)
			(type default)
		)
		(layer "B.Cu")
	)
	(gr_line
		(start 155.687522 -43.805602)
		(end 155.817824 -44.457112)
		(stroke
			(width 0.072898)
			(type default)
		)
		(layer "B.Cu")
	)
	(gr_line
		(start 156.044646 -127.241808)
		(end 156.048456 -127.261366)
		(stroke
			(width 0.072898)
			(type default)
		)
		(layer "B.Cu")
	)
	(gr_line
		(start 156.044646 -127.241808)
		(end 156.04871 -127.221234)
		(stroke
			(width 0.072898)
			(type default)
		)
		(layer "B.Cu")
	)
	(gr_line
		(start 156.068522 -39.82847)
		(end 156.154374 -40.257984)
		(stroke
			(width 0.072898)
			(type default)
		)
		(layer "B.Cu")
	)
	(gr_line
		(start 156.068522 -39.82847)
		(end 156.186378 -39.65194)
		(stroke
			(width 0.072898)
			(type default)
		)
		(layer "B.Cu")
	)
	(gr_line
		(start 156.154374 -40.257984)
		(end 156.331158 -40.37584)
		(stroke
			(width 0.072898)
			(type default)
		)
		(layer "B.Cu")
	)
	(gr_line
		(start 156.232098 -38.329616)
		(end 156.246068 -38.350444)
		(stroke
			(width 0.072898)
			(type default)
		)
		(layer "B.Cu")
	)
	(gr_line
		(start 156.246068 -38.350444)
		(end 156.250894 -38.374574)
		(stroke
			(width 0.072898)
			(type default)
		)
		(layer "B.Cu")
	)
	(gr_line
		(start 156.30017 -40.986456)
		(end 156.386022 -41.416224)
		(stroke
			(width 0.072898)
			(type default)
		)
		(layer "B.Cu")
	)
	(gr_line
		(start 156.30017 -40.986456)
		(end 156.417772 -40.809926)
		(stroke
			(width 0.072898)
			(type default)
		)
		(layer "B.Cu")
	)
	(gr_line
		(start 156.386022 -41.416224)
		(end 156.562806 -41.53408)
		(stroke
			(width 0.072898)
			(type default)
		)
		(layer "B.Cu")
	)
	(gr_line
		(start 156.501084 -39.626286)
		(end 156.631386 -40.278558)
		(stroke
			(width 0.072898)
			(type default)
		)
		(layer "B.Cu")
	)
	(gr_line
		(start 156.531818 -42.144696)
		(end 156.61767 -42.574464)
		(stroke
			(width 0.072898)
			(type default)
		)
		(layer "B.Cu")
	)
	(gr_line
		(start 156.531818 -42.144696)
		(end 156.64942 -41.968166)
		(stroke
			(width 0.072898)
			(type default)
		)
		(layer "B.Cu")
	)
	(gr_line
		(start 156.61767 -42.574464)
		(end 156.7942 -42.692066)
		(stroke
			(width 0.072898)
			(type default)
		)
		(layer "B.Cu")
	)
	(gr_line
		(start 156.732732 -40.785288)
		(end 156.863034 -41.437052)
		(stroke
			(width 0.072898)
			(type default)
		)
		(layer "B.Cu")
	)
	(gr_line
		(start 156.763466 -43.302936)
		(end 156.849318 -43.73245)
		(stroke
			(width 0.072898)
			(type default)
		)
		(layer "B.Cu")
	)
	(gr_line
		(start 156.763466 -43.302936)
		(end 156.881068 -43.126406)
		(stroke
			(width 0.072898)
			(type default)
		)
		(layer "B.Cu")
	)
	(gr_line
		(start 156.849318 -43.73245)
		(end 157.025848 -43.850306)
		(stroke
			(width 0.072898)
			(type default)
		)
		(layer "B.Cu")
	)
	(gr_line
		(start 156.96438 -41.94175)
		(end 157.09519 -42.596308)
		(stroke
			(width 0.072898)
			(type default)
		)
		(layer "B.Cu")
	)
	(gr_line
		(start 157.196028 -43.100752)
		(end 157.326584 -43.753786)
		(stroke
			(width 0.072898)
			(type default)
		)
		(layer "B.Cu")
	)
	(gr_line
		(start 157.308804 -127.602488)
		(end 157.312868 -127.622554)
		(stroke
			(width 0.072898)
			(type default)
		)
		(layer "B.Cu")
	)
	(gr_line
		(start 157.308804 -127.602488)
		(end 157.312868 -127.581914)
		(stroke
			(width 0.072898)
			(type default)
		)
		(layer "B.Cu")
	)
	(gr_line
		(start 157.519878 -141.03223)
		(end 157.52445 -141.056868)
		(stroke
			(width 0.072898)
			(type default)
		)
		(layer "B.Cu")
	)
	(gr_line
		(start 157.52445 -141.056868)
		(end 157.538928 -141.078458)
		(stroke
			(width 0.072898)
			(type default)
		)
		(layer "B.Cu")
	)
	(gr_line
		(start 157.705298 -39.003986)
		(end 157.79115 -39.433754)
		(stroke
			(width 0.072898)
			(type default)
		)
		(layer "B.Cu")
	)
	(gr_line
		(start 157.705298 -39.003986)
		(end 157.823154 -38.827456)
		(stroke
			(width 0.072898)
			(type default)
		)
		(layer "B.Cu")
	)
	(gr_line
		(start 157.79115 -39.433754)
		(end 157.967934 -39.551356)
		(stroke
			(width 0.072898)
			(type default)
		)
		(layer "B.Cu")
	)
	(gr_line
		(start 157.884622 -37.584126)
		(end 157.898592 -37.604954)
		(stroke
			(width 0.072898)
			(type default)
		)
		(layer "B.Cu")
	)
	(gr_line
		(start 157.936946 -40.162226)
		(end 158.022798 -40.59174)
		(stroke
			(width 0.072898)
			(type default)
		)
		(layer "B.Cu")
	)
	(gr_line
		(start 157.936946 -40.162226)
		(end 158.054802 -39.985696)
		(stroke
			(width 0.072898)
			(type default)
		)
		(layer "B.Cu")
	)
	(gr_line
		(start 158.022798 -40.59174)
		(end 158.199582 -40.709596)
		(stroke
			(width 0.072898)
			(type default)
		)
		(layer "B.Cu")
	)
	(gr_line
		(start 158.168594 -41.320466)
		(end 158.254446 -41.74998)
		(stroke
			(width 0.072898)
			(type default)
		)
		(layer "B.Cu")
	)
	(gr_line
		(start 158.168594 -41.320466)
		(end 158.28645 -41.143936)
		(stroke
			(width 0.072898)
			(type default)
		)
		(layer "B.Cu")
	)
	(gr_line
		(start 158.191708 -39.071296)
		(end 158.26867 -39.456106)
		(stroke
			(width 0.072898)
			(type default)
		)
		(layer "B.Cu")
	)
	(gr_line
		(start 158.254446 -41.74998)
		(end 158.43123 -41.867836)
		(stroke
			(width 0.072898)
			(type default)
		)
		(layer "B.Cu")
	)
	(gr_line
		(start 158.369254 -39.958772)
		(end 158.500826 -40.615616)
		(stroke
			(width 0.072898)
			(type default)
		)
		(layer "B.Cu")
	)
	(gr_line
		(start 158.400242 -42.478452)
		(end 158.486094 -42.90822)
		(stroke
			(width 0.072898)
			(type default)
		)
		(layer "B.Cu")
	)
	(gr_line
		(start 158.400242 -42.478452)
		(end 158.517844 -42.301668)
		(stroke
			(width 0.072898)
			(type default)
		)
		(layer "B.Cu")
	)
	(gr_line
		(start 158.486094 -42.90822)
		(end 158.662624 -43.025822)
		(stroke
			(width 0.072898)
			(type default)
		)
		(layer "B.Cu")
	)
	(gr_line
		(start 158.572708 -140.25753)
		(end 158.57728 -140.282168)
		(stroke
			(width 0.072898)
			(type default)
		)
		(layer "B.Cu")
	)
	(gr_line
		(start 158.57728 -140.282168)
		(end 158.591758 -140.303758)
		(stroke
			(width 0.072898)
			(type default)
		)
		(layer "B.Cu")
	)
	(gr_line
		(start 158.588202 -128.126744)
		(end 158.59252 -128.148588)
		(stroke
			(width 0.072898)
			(type default)
		)
		(layer "B.Cu")
	)
	(gr_line
		(start 158.588202 -128.126744)
		(end 158.59252 -128.1049)
		(stroke
			(width 0.072898)
			(type default)
		)
		(layer "B.Cu")
	)
	(gr_line
		(start 158.59252 -128.104138)
		(end 158.59252 -128.104646)
		(stroke
			(width 0.072898)
			(type default)
		)
		(layer "B.Cu")
	)
	(gr_line
		(start 158.600902 -41.117266)
		(end 158.73222 -41.77284)
		(stroke
			(width 0.072898)
			(type default)
		)
		(layer "B.Cu")
	)
	(gr_line
		(start 158.832296 -42.273728)
		(end 158.94558 -42.840148)
		(stroke
			(width 0.072898)
			(type default)
		)
		(layer "B.Cu")
	)
	(gr_line
		(start 158.945326 -42.840148)
		(end 158.94558 -42.840148)
		(stroke
			(width 0.072898)
			(type default)
		)
		(layer "B.Cu")
	)
	(gr_line
		(start 158.945326 -42.840148)
		(end 158.96336 -42.930064)
		(stroke
			(width 0.072898)
			(type default)
		)
		(layer "B.Cu")
	)
	(gr_line
		(start 159.238188 -38.556438)
		(end 159.32404 -38.985952)
		(stroke
			(width 0.072898)
			(type default)
		)
		(layer "B.Cu")
	)
	(gr_line
		(start 159.238188 -38.556438)
		(end 159.356044 -38.379908)
		(stroke
			(width 0.072898)
			(type default)
		)
		(layer "B.Cu")
	)
	(gr_line
		(start 159.32404 -38.985952)
		(end 159.500824 -39.103808)
		(stroke
			(width 0.072898)
			(type default)
		)
		(layer "B.Cu")
	)
	(gr_line
		(start 159.447992 -37.288724)
		(end 159.461962 -37.309552)
		(stroke
			(width 0.072898)
			(type default)
		)
		(layer "B.Cu")
	)
	(gr_line
		(start 159.461962 -37.309552)
		(end 159.466788 -37.333682)
		(stroke
			(width 0.072898)
			(type default)
		)
		(layer "B.Cu")
	)
	(gr_line
		(start 159.469836 -39.714678)
		(end 159.555688 -40.144192)
		(stroke
			(width 0.072898)
			(type default)
		)
		(layer "B.Cu")
	)
	(gr_line
		(start 159.469836 -39.714678)
		(end 159.587692 -39.538148)
		(stroke
			(width 0.072898)
			(type default)
		)
		(layer "B.Cu")
	)
	(gr_line
		(start 159.555688 -144.068292)
		(end 159.56788 -144.08658)
		(stroke
			(width 0.072898)
			(type default)
		)
		(layer "B.Cu")
	)
	(gr_line
		(start 159.555688 -40.144192)
		(end 159.732472 -40.262048)
		(stroke
			(width 0.072898)
			(type default)
		)
		(layer "B.Cu")
	)
	(gr_line
		(start 159.56788 -144.08658)
		(end 159.586168 -144.098772)
		(stroke
			(width 0.072898)
			(type default)
		)
		(layer "B.Cu")
	)
	(gr_line
		(start 159.67075 -38.354)
		(end 159.80156 -39.00805)
		(stroke
			(width 0.072898)
			(type default)
		)
		(layer "B.Cu")
	)
	(gr_line
		(start 159.680402 -139.803124)
		(end 159.684974 -139.827762)
		(stroke
			(width 0.072898)
			(type default)
		)
		(layer "B.Cu")
	)
	(gr_line
		(start 159.684974 -139.827762)
		(end 159.699452 -139.849352)
		(stroke
			(width 0.072898)
			(type default)
		)
		(layer "B.Cu")
	)
	(gr_line
		(start 159.701484 -40.872664)
		(end 159.787336 -41.302432)
		(stroke
			(width 0.072898)
			(type default)
		)
		(layer "B.Cu")
	)
	(gr_line
		(start 159.701484 -40.872664)
		(end 159.81934 -40.696134)
		(stroke
			(width 0.072898)
			(type default)
		)
		(layer "B.Cu")
	)
	(gr_line
		(start 159.787336 -41.302432)
		(end 159.96412 -41.420288)
		(stroke
			(width 0.072898)
			(type default)
		)
		(layer "B.Cu")
	)
	(gr_line
		(start 159.902144 -39.511478)
		(end 160.033462 -40.167052)
		(stroke
			(width 0.072898)
			(type default)
		)
		(layer "B.Cu")
	)
	(gr_line
		(start 159.933132 -42.030904)
		(end 160.018984 -42.460672)
		(stroke
			(width 0.072898)
			(type default)
		)
		(layer "B.Cu")
	)
	(gr_line
		(start 159.933132 -42.030904)
		(end 160.050734 -41.85412)
		(stroke
			(width 0.072898)
			(type default)
		)
		(layer "B.Cu")
	)
	(gr_line
		(start 159.9565 -129.013458)
		(end 159.960818 -129.035302)
		(stroke
			(width 0.072898)
			(type default)
		)
		(layer "B.Cu")
	)
	(gr_line
		(start 159.9565 -129.013458)
		(end 159.960818 -128.991614)
		(stroke
			(width 0.072898)
			(type default)
		)
		(layer "B.Cu")
	)
	(gr_line
		(start 159.960818 -128.990852)
		(end 159.960818 -128.99136)
		(stroke
			(width 0.072898)
			(type default)
		)
		(layer "B.Cu")
	)
	(gr_line
		(start 160.018984 -42.460672)
		(end 160.195514 -42.57802)
		(stroke
			(width 0.072898)
			(type default)
		)
		(layer "B.Cu")
	)
	(gr_line
		(start 160.134046 -40.669972)
		(end 160.26511 -41.325292)
		(stroke
			(width 0.072898)
			(type default)
		)
		(layer "B.Cu")
	)
	(gr_line
		(start 160.365186 -41.82618)
		(end 160.47847 -42.3926)
		(stroke
			(width 0.072898)
			(type default)
		)
		(layer "B.Cu")
	)
	(gr_line
		(start 160.44291 -98.418904)
		(end 160.447736 -98.441764)
		(stroke
			(width 0.072898)
			(type default)
		)
		(layer "B.Cu")
	)
	(gr_line
		(start 160.443418 -98.464116)
		(end 160.447736 -98.441764)
		(stroke
			(width 0.072898)
			(type default)
		)
		(layer "B.Cu")
	)
	(gr_line
		(start 160.478216 -42.3926)
		(end 160.47847 -42.3926)
		(stroke
			(width 0.072898)
			(type default)
		)
		(layer "B.Cu")
	)
	(gr_line
		(start 160.478216 -42.3926)
		(end 160.495742 -42.48023)
		(stroke
			(width 0.072898)
			(type default)
		)
		(layer "B.Cu")
	)
	(gr_line
		(start 160.589214 -143.264128)
		(end 160.601406 -143.282416)
		(stroke
			(width 0.072898)
			(type default)
		)
		(layer "B.Cu")
	)
	(gr_line
		(start 160.601406 -143.282416)
		(end 160.619694 -143.294608)
		(stroke
			(width 0.072898)
			(type default)
		)
		(layer "B.Cu")
	)
	(gr_line
		(start 160.754822 -139.268962)
		(end 160.759394 -139.2936)
		(stroke
			(width 0.072898)
			(type default)
		)
		(layer "B.Cu")
	)
	(gr_line
		(start 160.759394 -139.2936)
		(end 160.773872 -139.31519)
		(stroke
			(width 0.072898)
			(type default)
		)
		(layer "B.Cu")
	)
	(gr_line
		(start 161.276538 -129.142998)
		(end 161.280856 -129.164588)
		(stroke
			(width 0.072898)
			(type default)
		)
		(layer "B.Cu")
	)
	(gr_line
		(start 161.276538 -129.142998)
		(end 161.280856 -129.121154)
		(stroke
			(width 0.072898)
			(type default)
		)
		(layer "B.Cu")
	)
	(gr_line
		(start 161.280856 -129.1209)
		(end 161.280856 -129.121154)
		(stroke
			(width 0.072898)
			(type default)
		)
		(layer "B.Cu")
	)
	(gr_line
		(start 161.38906 -142.353538)
		(end 161.401252 -142.371826)
		(stroke
			(width 0.072898)
			(type default)
		)
		(layer "B.Cu")
	)
	(gr_line
		(start 161.401252 -142.371826)
		(end 161.41954 -142.384018)
		(stroke
			(width 0.072898)
			(type default)
		)
		(layer "B.Cu")
	)
	(gr_line
		(start 161.76244 -138.306302)
		(end 161.767012 -138.33094)
		(stroke
			(width 0.072898)
			(type default)
		)
		(layer "B.Cu")
	)
	(gr_line
		(start 161.767012 -138.33094)
		(end 161.78149 -138.35253)
		(stroke
			(width 0.072898)
			(type default)
		)
		(layer "B.Cu")
	)
	(gr_line
		(start 161.941256 -98.46691)
		(end 161.946082 -98.490278)
		(stroke
			(width 0.072898)
			(type default)
		)
		(layer "B.Cu")
	)
	(gr_line
		(start 161.941764 -98.51263)
		(end 161.946082 -98.490278)
		(stroke
			(width 0.072898)
			(type default)
		)
		(layer "B.Cu")
	)
	(gr_line
		(start 162.298634 -141.575282)
		(end 162.310826 -141.59357)
		(stroke
			(width 0.072898)
			(type default)
		)
		(layer "B.Cu")
	)
	(gr_line
		(start 162.310826 -141.59357)
		(end 162.329114 -141.605762)
		(stroke
			(width 0.072898)
			(type default)
		)
		(layer "B.Cu")
	)
	(gr_line
		(start 162.57905 -129.217674)
		(end 162.583368 -129.239518)
		(stroke
			(width 0.072898)
			(type default)
		)
		(layer "B.Cu")
	)
	(gr_line
		(start 162.57905 -129.217674)
		(end 162.583368 -129.196084)
		(stroke
			(width 0.072898)
			(type default)
		)
		(layer "B.Cu")
	)
	(gr_line
		(start 162.583368 -129.195322)
		(end 162.583368 -129.19583)
		(stroke
			(width 0.072898)
			(type default)
		)
		(layer "B.Cu")
	)
	(gr_line
		(start 162.991292 -137.860024)
		(end 162.996118 -137.884408)
		(stroke
			(width 0.072898)
			(type default)
		)
		(layer "B.Cu")
	)
	(gr_line
		(start 162.996118 -137.884408)
		(end 163.010088 -137.905236)
		(stroke
			(width 0.072898)
			(type default)
		)
		(layer "B.Cu")
	)
	(gr_line
		(start 163.241482 -98.425762)
		(end 163.246054 -98.448622)
		(stroke
			(width 0.072898)
			(type default)
		)
		(layer "B.Cu")
	)
	(gr_line
		(start 163.241736 -98.470212)
		(end 163.246054 -98.448622)
		(stroke
			(width 0.072898)
			(type default)
		)
		(layer "B.Cu")
	)
	(gr_line
		(start 163.345622 -140.67155)
		(end 163.357814 -140.689838)
		(stroke
			(width 0.072898)
			(type default)
		)
		(layer "B.Cu")
	)
	(gr_line
		(start 163.357814 -140.689838)
		(end 163.376102 -140.70203)
		(stroke
			(width 0.072898)
			(type default)
		)
		(layer "B.Cu")
	)
	(gr_line
		(start 163.853876 -146.977354)
		(end 163.875466 -146.991832)
		(stroke
			(width 0.072898)
			(type default)
		)
		(layer "B.Cu")
	)
	(gr_line
		(start 163.875466 -146.991832)
		(end 163.900104 -146.996404)
		(stroke
			(width 0.072898)
			(type default)
		)
		(layer "B.Cu")
	)
	(gr_line
		(start 164.026088 -129.645918)
		(end 164.030406 -129.667762)
		(stroke
			(width 0.072898)
			(type default)
		)
		(layer "B.Cu")
	)
	(gr_line
		(start 164.026088 -129.645918)
		(end 164.030406 -129.624074)
		(stroke
			(width 0.072898)
			(type default)
		)
		(layer "B.Cu")
	)
	(gr_line
		(start 164.030406 -129.623312)
		(end 164.030406 -129.62382)
		(stroke
			(width 0.072898)
			(type default)
		)
		(layer "B.Cu")
	)
	(gr_line
		(start 164.12591 -137.173716)
		(end 164.130482 -137.198354)
		(stroke
			(width 0.072898)
			(type default)
		)
		(layer "B.Cu")
	)
	(gr_line
		(start 164.130482 -137.198354)
		(end 164.14496 -137.219944)
		(stroke
			(width 0.072898)
			(type default)
		)
		(layer "B.Cu")
	)
	(gr_line
		(start 164.178996 -139.637516)
		(end 164.191188 -139.655804)
		(stroke
			(width 0.072898)
			(type default)
		)
		(layer "B.Cu")
	)
	(gr_line
		(start 164.191188 -139.655804)
		(end 164.209476 -139.667996)
		(stroke
			(width 0.072898)
			(type default)
		)
		(layer "B.Cu")
	)
	(gr_line
		(start 164.385498 -145.835878)
		(end 164.407088 -145.850356)
		(stroke
			(width 0.072898)
			(type default)
		)
		(layer "B.Cu")
	)
	(gr_line
		(start 164.407088 -145.850356)
		(end 164.431726 -145.854928)
		(stroke
			(width 0.072898)
			(type default)
		)
		(layer "B.Cu")
	)
	(gr_line
		(start 164.811202 -144.672558)
		(end 164.832792 -144.687036)
		(stroke
			(width 0.072898)
			(type default)
		)
		(layer "B.Cu")
	)
	(gr_line
		(start 164.832792 -144.687036)
		(end 164.85743 -144.691608)
		(stroke
			(width 0.072898)
			(type default)
		)
		(layer "B.Cu")
	)
	(gr_line
		(start 164.898324 -97.86112)
		(end 164.90315 -97.884742)
		(stroke
			(width 0.072898)
			(type default)
		)
		(layer "B.Cu")
	)
	(gr_line
		(start 164.898578 -97.908364)
		(end 164.90315 -97.884742)
		(stroke
			(width 0.072898)
			(type default)
		)
		(layer "B.Cu")
	)
	(gr_line
		(start 165.219126 -143.555974)
		(end 165.240716 -143.570452)
		(stroke
			(width 0.072898)
			(type default)
		)
		(layer "B.Cu")
	)
	(gr_line
		(start 165.240716 -143.570452)
		(end 165.265354 -143.575024)
		(stroke
			(width 0.072898)
			(type default)
		)
		(layer "B.Cu")
	)
	(gr_line
		(start 165.364414 -136.529826)
		(end 165.370256 -136.559544)
		(stroke
			(width 0.072898)
			(type default)
		)
		(layer "B.Cu")
	)
	(gr_line
		(start 165.370256 -136.559544)
		(end 165.387782 -136.583928)
		(stroke
			(width 0.072898)
			(type default)
		)
		(layer "B.Cu")
	)
	(gr_line
		(start 165.388798 -139.06373)
		(end 165.400482 -139.081002)
		(stroke
			(width 0.072898)
			(type default)
		)
		(layer "B.Cu")
	)
	(gr_line
		(start 165.400482 -139.081002)
		(end 165.417754 -139.092686)
		(stroke
			(width 0.072898)
			(type default)
		)
		(layer "B.Cu")
	)
	(gr_line
		(start 166.1287 -142.55877)
		(end 166.15029 -142.573248)
		(stroke
			(width 0.072898)
			(type default)
		)
		(layer "B.Cu")
	)
	(gr_line
		(start 166.15029 -142.573248)
		(end 166.174928 -142.57782)
		(stroke
			(width 0.072898)
			(type default)
		)
		(layer "B.Cu")
	)
	(gr_line
		(start 166.47033 -97.719642)
		(end 166.475156 -97.743264)
		(stroke
			(width 0.072898)
			(type default)
		)
		(layer "B.Cu")
	)
	(gr_line
		(start 166.470584 -97.766886)
		(end 166.475156 -97.743264)
		(stroke
			(width 0.072898)
			(type default)
		)
		(layer "B.Cu")
	)
	(gr_line
		(start 166.796212 -138.543538)
		(end 166.82593 -138.584686)
		(stroke
			(width 0.072898)
			(type default)
		)
		(layer "B.Cu")
	)
	(gr_line
		(start 166.82593 -138.584686)
		(end 166.872158 -138.603482)
		(stroke
			(width 0.072898)
			(type default)
		)
		(layer "B.Cu")
	)
	(gr_line
		(start 166.999158 -141.54912)
		(end 167.020748 -141.563598)
		(stroke
			(width 0.072898)
			(type default)
		)
		(layer "B.Cu")
	)
	(gr_line
		(start 167.020748 -141.563598)
		(end 167.046148 -141.568678)
		(stroke
			(width 0.072898)
			(type default)
		)
		(layer "B.Cu")
	)
	(gr_line
		(start 167.09771 -140.226542)
		(end 167.118538 -140.240512)
		(stroke
			(width 0.072898)
			(type default)
		)
		(layer "B.Cu")
	)
	(gr_line
		(start 167.118538 -140.240512)
		(end 167.143176 -140.245338)
		(stroke
			(width 0.072898)
			(type default)
		)
		(layer "B.Cu")
	)
	(gr_line
		(start 167.994076 -97.088452)
		(end 167.998902 -97.112582)
		(stroke
			(width 0.072898)
			(type default)
		)
		(layer "B.Cu")
	)
	(gr_line
		(start 167.99433 -97.13595)
		(end 167.998902 -97.112582)
		(stroke
			(width 0.072898)
			(type default)
		)
		(layer "B.Cu")
	)
	(gr_line
		(start 168.66743 -139.34313)
		(end 168.68775 -139.351512)
		(stroke
			(width 0.072898)
			(type default)
		)
		(layer "B.Cu")
	)
	(gr_line
		(start 169.552874 -95.881444)
		(end 169.553128 -95.882206)
		(stroke
			(width 0.072898)
			(type default)
		)
		(layer "B.Cu")
	)
	(gr_line
		(start 169.553128 -95.928942)
		(end 169.5577 -95.905574)
		(stroke
			(width 0.072898)
			(type default)
		)
		(layer "B.Cu")
	)
	(gr_line
		(start 169.553128 -95.88246)
		(end 169.5577 -95.905574)
		(stroke
			(width 0.072898)
			(type default)
		)
		(layer "B.Cu")
	)
	(gr_line
		(start 170.440096 -138.321034)
		(end 170.529758 -138.410696)
		(stroke
			(width 0.072898)
			(type default)
		)
		(layer "B.Cu")
	)
	(gr_arc
		(start 170.529758 -138.639804)
		(mid 170.577242 -138.525235)
		(end 170.529758 -138.410696)
		(stroke
			(width 0.072898)
			(type default)
		)
		(layer "B.Cu")
	)
	(gr_arc
		(start 170.97883 -138.859768)
		(mid 170.86453 -138.812423)
		(end 170.75023 -138.859768)
		(stroke
			(width 0.072898)
			(type default)
		)
		(layer "B.Cu")
	)
	(gr_line
		(start 170.97883 -138.859768)
		(end 171.068492 -138.94943)
		(stroke
			(width 0.072898)
			(type default)
		)
		(layer "B.Cu")
	)
	(gr_line
		(start 171.109894 -95.553784)
		(end 171.11472 -95.577406)
		(stroke
			(width 0.072898)
			(type default)
		)
		(layer "B.Cu")
	)
	(gr_line
		(start 171.110148 -95.601028)
		(end 171.11472 -95.577406)
		(stroke
			(width 0.072898)
			(type default)
		)
		(layer "B.Cu")
	)
	(gr_line
		(start 174.294292 -140.232892)
		(end 174.383954 -140.322554)
		(stroke
			(width 0.072898)
			(type default)
		)
		(layer "B.Cu")
	)
	(gr_arc
		(start 174.383954 -140.551662)
		(mid 174.431409 -140.437106)
		(end 174.383954 -140.322554)
		(stroke
			(width 0.072898)
			(type default)
		)
		(layer "B.Cu")
	)
	(gr_arc
		(start 174.833026 -140.771626)
		(mid 174.718726 -140.724281)
		(end 174.604426 -140.771626)
		(stroke
			(width 0.072898)
			(type default)
		)
		(layer "B.Cu")
	)
	(gr_line
		(start 174.833026 -140.771626)
		(end 174.922688 -140.861288)
		(stroke
			(width 0.072898)
			(type default)
		)
		(layer "B.Cu")
	)
	(gr_line
		(start 174.977298 -143.110966)
		(end 174.997872 -143.11503)
		(stroke
			(width 0.072898)
			(type default)
		)
		(layer "B.Cu")
	)
	(gr_line
		(start 174.997872 -143.11503)
		(end 175.017684 -143.11122)
		(stroke
			(width 0.072898)
			(type default)
		)
		(layer "B.Cu")
	)
	(gr_line
		(start 175.161448 -144.324832)
		(end 175.181006 -144.328642)
		(stroke
			(width 0.072898)
			(type default)
		)
		(layer "B.Cu")
	)
	(gr_line
		(start 175.181006 -144.328642)
		(end 175.200564 -144.324832)
		(stroke
			(width 0.072898)
			(type default)
		)
		(layer "B.Cu")
	)
	(gr_line
		(start 176.660302 -145.789904)
		(end 176.67986 -145.793714)
		(stroke
			(width 0.072898)
			(type default)
		)
		(layer "B.Cu")
	)
	(gr_line
		(start 176.67986 -145.793714)
		(end 176.699418 -145.789904)
		(stroke
			(width 0.072898)
			(type default)
		)
		(layer "B.Cu")
	)
	(gr_line
		(start 178.180238 -147.280122)
		(end 178.199796 -147.283932)
		(stroke
			(width 0.072898)
			(type default)
		)
		(layer "B.Cu")
	)
	(gr_line
		(start 178.199796 -147.283932)
		(end 178.219608 -147.280122)
		(stroke
			(width 0.072898)
			(type default)
		)
		(layer "B.Cu")
	)
	(gr_line
		(start 178.209448 -148.533358)
		(end 178.229006 -148.537168)
		(stroke
			(width 0.072898)
			(type default)
		)
		(layer "B.Cu")
	)
	(gr_line
		(start 178.229006 -148.537422)
		(end 178.22926 -148.537422)
		(stroke
			(width 0.072898)
			(type default)
		)
		(layer "B.Cu")
	)
	(gr_line
		(start 178.229006 -148.537168)
		(end 178.229006 -148.537422)
		(stroke
			(width 0.072898)
			(type default)
		)
		(layer "B.Cu")
	)
	(gr_line
		(start 178.22926 -148.537422)
		(end 178.251612 -148.533104)
		(stroke
			(width 0.072898)
			(type default)
		)
		(layer "B.Cu")
	)
	(gr_line
		(start 179.319174 -149.993096)
		(end 179.338732 -149.996906)
		(stroke
			(width 0.072898)
			(type default)
		)
		(layer "B.Cu")
	)
	(gr_line
		(start 179.338732 -149.996906)
		(end 179.35829 -149.993096)
		(stroke
			(width 0.072898)
			(type default)
		)
		(layer "B.Cu")
	)
	(gr_line
		(start 179.515262 -142.26159)
		(end 179.603908 -142.244826)
		(stroke
			(width 0.072898)
			(type default)
		)
		(layer "B.Cu")
	)
	(gr_line
		(start 179.603908 -142.244826)
		(end 179.6542 -142.17015)
		(stroke
			(width 0.072898)
			(type default)
		)
		(layer "B.Cu")
	)
	(gr_line
		(start 179.962302 -141.713458)
		(end 179.99329 -141.667738)
		(stroke
			(width 0.072898)
			(type default)
		)
		(layer "B.Cu")
	)
	(gr_line
		(start 180.005228 -140.168884)
		(end 180.09489 -140.258546)
		(stroke
			(width 0.072898)
			(type default)
		)
		(layer "B.Cu")
	)
	(gr_arc
		(start 180.09489 -140.487654)
		(mid 180.142329 -140.3731)
		(end 180.09489 -140.258546)
		(stroke
			(width 0.072898)
			(type default)
		)
		(layer "B.Cu")
	)
	(gr_arc
		(start 180.543962 -140.707618)
		(mid 180.429662 -140.660273)
		(end 180.315362 -140.707618)
		(stroke
			(width 0.072898)
			(type default)
		)
		(layer "B.Cu")
	)
	(gr_line
		(start 180.543962 -140.707618)
		(end 180.633624 -140.79728)
		(stroke
			(width 0.072898)
			(type default)
		)
		(layer "B.Cu")
	)
	(gr_line
		(start 182.82285 -142.843504)
		(end 182.847488 -142.838932)
		(stroke
			(width 0.072898)
			(type default)
		)
		(layer "B.Cu")
	)
	(gr_line
		(start 182.847488 -142.838932)
		(end 182.869078 -142.824454)
		(stroke
			(width 0.072898)
			(type default)
		)
		(layer "B.Cu")
	)
	(gr_line
		(start 185.085228 -139.686284)
		(end 185.17489 -139.775946)
		(stroke
			(width 0.072898)
			(type default)
		)
		(layer "B.Cu")
	)
	(gr_arc
		(start 185.17489 -140.0048)
		(mid 185.222396 -139.890381)
		(end 185.17489 -139.775946)
		(stroke
			(width 0.072898)
			(type default)
		)
		(layer "B.Cu")
	)
	(gr_arc
		(start 185.623962 -140.225018)
		(mid 185.509662 -140.177673)
		(end 185.395362 -140.225018)
		(stroke
			(width 0.072898)
			(type default)
		)
		(layer "B.Cu")
	)
	(gr_line
		(start 185.623962 -140.225018)
		(end 185.713624 -140.31468)
		(stroke
			(width 0.072898)
			(type default)
		)
		(layer "B.Cu")
	)
	(gr_line
		(start 193.895472 -142.448534)
		(end 193.951606 -142.437612)
		(stroke
			(width 0.072898)
			(type default)
		)
		(layer "B.Cu")
	)
	(gr_line
		(start 195.138802 -140.401802)
		(end 195.228464 -140.491464)
		(stroke
			(width 0.072898)
			(type default)
		)
		(layer "B.Cu")
	)
	(gr_arc
		(start 195.228464 -140.720318)
		(mid 195.275991 -140.605894)
		(end 195.228464 -140.491464)
		(stroke
			(width 0.072898)
			(type default)
		)
		(layer "B.Cu")
	)
	(gr_arc
		(start 195.677536 -140.940536)
		(mid 195.563146 -140.893266)
		(end 195.448682 -140.940536)
		(stroke
			(width 0.072898)
			(type default)
		)
		(layer "B.Cu")
	)
	(gr_line
		(start 195.677536 -140.940536)
		(end 195.767198 -141.030198)
		(stroke
			(width 0.072898)
			(type default)
		)
		(layer "B.Cu")
	)
	(gr_line
		(start 199.194928 -143.201644)
		(end 199.219566 -143.197072)
		(stroke
			(width 0.072898)
			(type default)
		)
		(layer "B.Cu")
	)
	(gr_line
		(start 199.219566 -143.197072)
		(end 199.240648 -143.182848)
		(stroke
			(width 0.072898)
			(type default)
		)
		(layer "B.Cu")
	)
	(gr_line
		(start 200.218802 -140.909802)
		(end 200.308464 -140.999464)
		(stroke
			(width 0.072898)
			(type default)
		)
		(layer "B.Cu")
	)
	(gr_arc
		(start 200.308464 -141.228318)
		(mid 200.355991 -141.113894)
		(end 200.308464 -140.999464)
		(stroke
			(width 0.072898)
			(type default)
		)
		(layer "B.Cu")
	)
	(gr_arc
		(start 200.757536 -141.448536)
		(mid 200.643146 -141.401266)
		(end 200.528682 -141.448536)
		(stroke
			(width 0.072898)
			(type default)
		)
		(layer "B.Cu")
	)
	(gr_line
		(start 200.757536 -141.448536)
		(end 200.847198 -141.538198)
		(stroke
			(width 0.072898)
			(type default)
		)
		(layer "B.Cu")
	)
	(gr_line
		(start 203.744576 -143.552418)
		(end 203.767944 -143.547846)
		(stroke
			(width 0.072898)
			(type default)
		)
		(layer "B.Cu")
	)
	(gr_line
		(start 203.767944 -143.547846)
		(end 203.788264 -143.534384)
		(stroke
			(width 0.072898)
			(type default)
		)
		(layer "B.Cu")
	)
	(gr_line
		(start 204.640942 -145.078704)
		(end 204.66431 -145.074132)
		(stroke
			(width 0.072898)
			(type default)
		)
		(layer "B.Cu")
	)
	(gr_line
		(start 204.66431 -145.074132)
		(end 204.684122 -145.060924)
		(stroke
			(width 0.072898)
			(type default)
		)
		(layer "B.Cu")
	)
	(gr_line
		(start 204.917802 -140.909802)
		(end 205.007464 -140.999464)
		(stroke
			(width 0.072898)
			(type default)
		)
		(layer "B.Cu")
	)
	(gr_arc
		(start 205.007464 -141.228318)
		(mid 205.054991 -141.113894)
		(end 205.007464 -140.999464)
		(stroke
			(width 0.072898)
			(type default)
		)
		(layer "B.Cu")
	)
	(gr_arc
		(start 205.456536 -141.448536)
		(mid 205.342236 -141.401191)
		(end 205.227936 -141.448536)
		(stroke
			(width 0.072898)
			(type default)
		)
		(layer "B.Cu")
	)
	(gr_line
		(start 205.456536 -141.448536)
		(end 205.546198 -141.538198)
		(stroke
			(width 0.072898)
			(type default)
		)
		(layer "B.Cu")
	)
	(gr_line
		(start 209.616802 -140.528802)
		(end 209.706464 -140.618464)
		(stroke
			(width 0.072898)
			(type default)
		)
		(layer "B.Cu")
	)
	(gr_arc
		(start 209.706464 -140.847572)
		(mid 209.753924 -140.733013)
		(end 209.706464 -140.618464)
		(stroke
			(width 0.072898)
			(type default)
		)
		(layer "B.Cu")
	)
	(gr_arc
		(start 210.155536 -141.067536)
		(mid 210.041146 -141.020266)
		(end 209.926682 -141.067536)
		(stroke
			(width 0.072898)
			(type default)
		)
		(layer "B.Cu")
	)
	(gr_line
		(start 210.155536 -141.067536)
		(end 210.245198 -141.157198)
		(stroke
			(width 0.072898)
			(type default)
		)
		(layer "B.Cu")
	)
	(gr_line
		(start 0 -183.76392)
		(end 0 -0.999998)
		(stroke
			(width 1.524)
			(type default)
		)
		(layer "In1.Cu")
	)
	(gr_arc
		(start 0 -183.76392)
		(mid 0.026807 -183.993715)
		(end 0.105664 -184.211214)
		(stroke
			(width 1.524)
			(type default)
		)
		(layer "In1.Cu")
	)
	(gr_arc
		(start 0.999998 0)
		(mid 0.292893 -0.292893)
		(end 0 -0.999998)
		(stroke
			(width 1.524)
			(type default)
		)
		(layer "In1.Cu")
	)
	(gr_line
		(start 0.999998 0)
		(end 29.53004 0)
		(stroke
			(width 1.524)
			(type default)
		)
		(layer "In1.Cu")
	)
	(gr_line
		(start 4.723638 -193.447162)
		(end 0.105664 -184.211214)
		(stroke
			(width 1.524)
			(type default)
		)
		(layer "In1.Cu")
	)
	(gr_arc
		(start 4.723638 -193.447162)
		(mid 5.092281 -193.850645)
		(end 5.617972 -194.00012)
		(stroke
			(width 1.524)
			(type default)
		)
		(layer "In1.Cu")
	)
	(gr_arc
		(start 30.530038 -109.050074)
		(mid 30.822931 -109.757179)
		(end 31.530036 -110.050072)
		(stroke
			(width 1.524)
			(type default)
		)
		(layer "In1.Cu")
	)
	(gr_arc
		(start 30.530038 -0.999998)
		(mid 30.237147 -0.29288)
		(end 29.53004 0)
		(stroke
			(width 1.524)
			(type default)
		)
		(layer "In1.Cu")
	)
	(gr_line
		(start 30.530038 -0.999998)
		(end 30.530038 -109.050074)
		(stroke
			(width 1.524)
			(type default)
		)
		(layer "In1.Cu")
	)
	(gr_line
		(start 31.530036 -110.050072)
		(end 72.030082 -110.050072)
		(stroke
			(width 1.524)
			(type default)
		)
		(layer "In1.Cu")
	)
	(gr_arc
		(start 72.030082 -110.050072)
		(mid 72.737187 -109.757179)
		(end 73.03008 -109.050074)
		(stroke
			(width 1.524)
			(type default)
		)
		(layer "In1.Cu")
	)
	(gr_line
		(start 73.03008 -109.050074)
		(end 73.03008 -0.999998)
		(stroke
			(width 1.524)
			(type default)
		)
		(layer "In1.Cu")
	)
	(gr_arc
		(start 74.030078 0)
		(mid 73.322986 -0.2929)
		(end 73.03008 -0.999998)
		(stroke
			(width 1.524)
			(type default)
		)
		(layer "In1.Cu")
	)
	(gr_line
		(start 74.030078 0)
		(end 234.00004 0)
		(stroke
			(width 1.524)
			(type default)
		)
		(layer "In1.Cu")
	)
	(gr_rect
		(start 74.446384 -92.69603)
		(end 76.503784 -94.00413)
		(stroke
			(width 0)
			(type default)
		)
		(fill no)
		(layer "In1.Cu")
	)
	(gr_rect
		(start 74.446384 -89.496138)
		(end 76.503784 -90.803984)
		(stroke
			(width 0)
			(type default)
		)
		(fill no)
		(layer "In1.Cu")
	)
	(gr_rect
		(start 74.446384 -86.295992)
		(end 76.503784 -87.604092)
		(stroke
			(width 0)
			(type default)
		)
		(fill no)
		(layer "In1.Cu")
	)
	(gr_rect
		(start 74.446384 -83.0961)
		(end 76.503784 -84.403946)
		(stroke
			(width 0)
			(type default)
		)
		(fill no)
		(layer "In1.Cu")
	)
	(gr_rect
		(start 74.446384 -79.895954)
		(end 76.503784 -81.204054)
		(stroke
			(width 0)
			(type default)
		)
		(fill no)
		(layer "In1.Cu")
	)
	(gr_rect
		(start 74.446384 -76.696062)
		(end 76.503784 -78.003908)
		(stroke
			(width 0)
			(type default)
		)
		(fill no)
		(layer "In1.Cu")
	)
	(gr_rect
		(start 74.446384 -73.495916)
		(end 76.503784 -74.804016)
		(stroke
			(width 0)
			(type default)
		)
		(fill no)
		(layer "In1.Cu")
	)
	(gr_rect
		(start 74.446384 -70.296024)
		(end 76.503784 -71.604124)
		(stroke
			(width 0)
			(type default)
		)
		(fill no)
		(layer "In1.Cu")
	)
	(gr_rect
		(start 74.446384 -67.096132)
		(end 76.503784 -68.403978)
		(stroke
			(width 0)
			(type default)
		)
		(fill no)
		(layer "In1.Cu")
	)
	(gr_arc
		(start 76.902818 -93.800168)
		(mid 77.283818 -94.181168)
		(end 77.664818 -93.800168)
		(stroke
			(width 0.2)
			(type default)
		)
		(layer "In1.Cu")
	)
	(gr_line
		(start 76.902818 -92.911168)
		(end 76.902818 -93.800168)
		(stroke
			(width 0.2)
			(type default)
		)
		(layer "In1.Cu")
	)
	(gr_arc
		(start 76.902818 -87.399368)
		(mid 77.283818 -87.780368)
		(end 77.664818 -87.399368)
		(stroke
			(width 0.2)
			(type default)
		)
		(layer "In1.Cu")
	)
	(gr_line
		(start 76.902818 -86.510368)
		(end 76.902818 -87.399368)
		(stroke
			(width 0.2)
			(type default)
		)
		(layer "In1.Cu")
	)
	(gr_arc
		(start 76.902818 -80.998568)
		(mid 77.283818 -81.379568)
		(end 77.664818 -80.998568)
		(stroke
			(width 0.2)
			(type default)
		)
		(layer "In1.Cu")
	)
	(gr_line
		(start 76.902818 -80.109568)
		(end 76.902818 -80.998568)
		(stroke
			(width 0.2)
			(type default)
		)
		(layer "In1.Cu")
	)
	(gr_arc
		(start 76.902818 -74.597768)
		(mid 77.283818 -74.978768)
		(end 77.664818 -74.597768)
		(stroke
			(width 0.2)
			(type default)
		)
		(layer "In1.Cu")
	)
	(gr_line
		(start 76.902818 -73.708768)
		(end 76.902818 -74.597768)
		(stroke
			(width 0.2)
			(type default)
		)
		(layer "In1.Cu")
	)
	(gr_arc
		(start 76.974192 -68.201032)
		(mid 77.355192 -68.582032)
		(end 77.736192 -68.201032)
		(stroke
			(width 0.2)
			(type default)
		)
		(layer "In1.Cu")
	)
	(gr_line
		(start 76.974192 -67.312032)
		(end 76.974192 -68.201032)
		(stroke
			(width 0.2)
			(type default)
		)
		(layer "In1.Cu")
	)
	(gr_line
		(start 77.664818 -93.800168)
		(end 77.664818 -92.911422)
		(stroke
			(width 0.2)
			(type default)
		)
		(layer "In1.Cu")
	)
	(gr_arc
		(start 77.664818 -92.911422)
		(mid 77.283945 -92.530168)
		(end 76.902818 -92.911168)
		(stroke
			(width 0.2)
			(type default)
		)
		(layer "In1.Cu")
	)
	(gr_line
		(start 77.664818 -87.399368)
		(end 77.664818 -86.510622)
		(stroke
			(width 0.2)
			(type default)
		)
		(layer "In1.Cu")
	)
	(gr_arc
		(start 77.664818 -86.510622)
		(mid 77.283945 -86.129368)
		(end 76.902818 -86.510368)
		(stroke
			(width 0.2)
			(type default)
		)
		(layer "In1.Cu")
	)
	(gr_line
		(start 77.664818 -80.998568)
		(end 77.664818 -80.109822)
		(stroke
			(width 0.2)
			(type default)
		)
		(layer "In1.Cu")
	)
	(gr_arc
		(start 77.664818 -80.109822)
		(mid 77.283945 -79.728568)
		(end 76.902818 -80.109568)
		(stroke
			(width 0.2)
			(type default)
		)
		(layer "In1.Cu")
	)
	(gr_line
		(start 77.664818 -74.597768)
		(end 77.664818 -73.709022)
		(stroke
			(width 0.2)
			(type default)
		)
		(layer "In1.Cu")
	)
	(gr_arc
		(start 77.664818 -73.709022)
		(mid 77.283945 -73.327768)
		(end 76.902818 -73.708768)
		(stroke
			(width 0.2)
			(type default)
		)
		(layer "In1.Cu")
	)
	(gr_line
		(start 77.736192 -68.201032)
		(end 77.736192 -67.312286)
		(stroke
			(width 0.2)
			(type default)
		)
		(layer "In1.Cu")
	)
	(gr_arc
		(start 77.736192 -67.312286)
		(mid 77.355319 -66.931032)
		(end 76.974192 -67.312032)
		(stroke
			(width 0.2)
			(type default)
		)
		(layer "In1.Cu")
	)
	(gr_arc
		(start 77.741018 -90.599768)
		(mid 78.122018 -90.980768)
		(end 78.503018 -90.599768)
		(stroke
			(width 0.2)
			(type default)
		)
		(layer "In1.Cu")
	)
	(gr_line
		(start 77.741018 -89.710768)
		(end 77.741018 -90.599768)
		(stroke
			(width 0.2)
			(type default)
		)
		(layer "In1.Cu")
	)
	(gr_arc
		(start 77.741018 -84.198968)
		(mid 78.122018 -84.579968)
		(end 78.503018 -84.198968)
		(stroke
			(width 0.2)
			(type default)
		)
		(layer "In1.Cu")
	)
	(gr_line
		(start 77.741018 -83.309968)
		(end 77.741018 -84.198968)
		(stroke
			(width 0.2)
			(type default)
		)
		(layer "In1.Cu")
	)
	(gr_arc
		(start 77.741018 -77.798168)
		(mid 78.122018 -78.179168)
		(end 78.503018 -77.798168)
		(stroke
			(width 0.2)
			(type default)
		)
		(layer "In1.Cu")
	)
	(gr_line
		(start 77.741018 -76.909168)
		(end 77.741018 -77.798168)
		(stroke
			(width 0.2)
			(type default)
		)
		(layer "In1.Cu")
	)
	(gr_arc
		(start 77.741018 -71.397368)
		(mid 78.122018 -71.778368)
		(end 78.503018 -71.397368)
		(stroke
			(width 0.2)
			(type default)
		)
		(layer "In1.Cu")
	)
	(gr_line
		(start 77.741018 -70.508368)
		(end 77.741018 -71.397368)
		(stroke
			(width 0.2)
			(type default)
		)
		(layer "In1.Cu")
	)
	(gr_line
		(start 78.503018 -90.599768)
		(end 78.503018 -89.711022)
		(stroke
			(width 0.2)
			(type default)
		)
		(layer "In1.Cu")
	)
	(gr_arc
		(start 78.503018 -89.711022)
		(mid 78.122145 -89.329768)
		(end 77.741018 -89.710768)
		(stroke
			(width 0.2)
			(type default)
		)
		(layer "In1.Cu")
	)
	(gr_line
		(start 78.503018 -84.198968)
		(end 78.503018 -83.310222)
		(stroke
			(width 0.2)
			(type default)
		)
		(layer "In1.Cu")
	)
	(gr_arc
		(start 78.503018 -83.310222)
		(mid 78.122145 -82.928968)
		(end 77.741018 -83.309968)
		(stroke
			(width 0.2)
			(type default)
		)
		(layer "In1.Cu")
	)
	(gr_line
		(start 78.503018 -77.798168)
		(end 78.503018 -76.909422)
		(stroke
			(width 0.2)
			(type default)
		)
		(layer "In1.Cu")
	)
	(gr_arc
		(start 78.503018 -76.909422)
		(mid 78.122145 -76.528168)
		(end 77.741018 -76.909168)
		(stroke
			(width 0.2)
			(type default)
		)
		(layer "In1.Cu")
	)
	(gr_line
		(start 78.503018 -71.397368)
		(end 78.503018 -70.508622)
		(stroke
			(width 0.2)
			(type default)
		)
		(layer "In1.Cu")
	)
	(gr_arc
		(start 78.503018 -70.508622)
		(mid 78.122145 -70.127368)
		(end 77.741018 -70.508368)
		(stroke
			(width 0.2)
			(type default)
		)
		(layer "In1.Cu")
	)
	(gr_rect
		(start 78.896464 -94.295976)
		(end 80.953864 -95.604076)
		(stroke
			(width 0)
			(type default)
		)
		(fill no)
		(layer "In1.Cu")
	)
	(gr_rect
		(start 78.896464 -91.096084)
		(end 80.953864 -92.40393)
		(stroke
			(width 0)
			(type default)
		)
		(fill no)
		(layer "In1.Cu")
	)
	(gr_rect
		(start 78.896464 -87.895938)
		(end 80.953864 -89.204038)
		(stroke
			(width 0)
			(type default)
		)
		(fill no)
		(layer "In1.Cu")
	)
	(gr_rect
		(start 78.896464 -84.696046)
		(end 80.953864 -86.004146)
		(stroke
			(width 0)
			(type default)
		)
		(fill no)
		(layer "In1.Cu")
	)
	(gr_rect
		(start 78.896464 -81.4959)
		(end 80.953864 -82.804)
		(stroke
			(width 0)
			(type default)
		)
		(fill no)
		(layer "In1.Cu")
	)
	(gr_rect
		(start 78.896464 -78.296008)
		(end 80.953864 -79.604108)
		(stroke
			(width 0)
			(type default)
		)
		(fill no)
		(layer "In1.Cu")
	)
	(gr_rect
		(start 78.896464 -75.096116)
		(end 80.953864 -76.403962)
		(stroke
			(width 0)
			(type default)
		)
		(fill no)
		(layer "In1.Cu")
	)
	(gr_rect
		(start 78.896464 -71.89597)
		(end 80.953864 -73.20407)
		(stroke
			(width 0)
			(type default)
		)
		(fill no)
		(layer "In1.Cu")
	)
	(gr_arc
		(start 82.977228 -95.381572)
		(mid 83.358228 -95.762572)
		(end 83.739228 -95.381572)
		(stroke
			(width 0.2)
			(type default)
		)
		(layer "In1.Cu")
	)
	(gr_line
		(start 82.977228 -94.492572)
		(end 82.977228 -95.381572)
		(stroke
			(width 0.2)
			(type default)
		)
		(layer "In1.Cu")
	)
	(gr_arc
		(start 82.977228 -82.581496)
		(mid 83.358228 -82.962496)
		(end 83.739228 -82.581496)
		(stroke
			(width 0.2)
			(type default)
		)
		(layer "In1.Cu")
	)
	(gr_line
		(start 82.977228 -81.692496)
		(end 82.977228 -82.581496)
		(stroke
			(width 0.2)
			(type default)
		)
		(layer "In1.Cu")
	)
	(gr_arc
		(start 82.977228 -76.194158)
		(mid 83.358228 -76.575158)
		(end 83.739228 -76.194158)
		(stroke
			(width 0.2)
			(type default)
		)
		(layer "In1.Cu")
	)
	(gr_line
		(start 82.977228 -75.305158)
		(end 82.977228 -76.194158)
		(stroke
			(width 0.2)
			(type default)
		)
		(layer "In1.Cu")
	)
	(gr_arc
		(start 82.978498 -88.980264)
		(mid 83.359498 -89.361264)
		(end 83.740498 -88.980264)
		(stroke
			(width 0.2)
			(type default)
		)
		(layer "In1.Cu")
	)
	(gr_line
		(start 82.978498 -88.091264)
		(end 82.978498 -88.980264)
		(stroke
			(width 0.2)
			(type default)
		)
		(layer "In1.Cu")
	)
	(gr_line
		(start 83.739228 -95.381572)
		(end 83.739228 -94.492826)
		(stroke
			(width 0.2)
			(type default)
		)
		(layer "In1.Cu")
	)
	(gr_arc
		(start 83.739228 -94.492826)
		(mid 83.358355 -94.111572)
		(end 82.977228 -94.492572)
		(stroke
			(width 0.2)
			(type default)
		)
		(layer "In1.Cu")
	)
	(gr_line
		(start 83.739228 -82.581496)
		(end 83.739228 -81.69275)
		(stroke
			(width 0.2)
			(type default)
		)
		(layer "In1.Cu")
	)
	(gr_arc
		(start 83.739228 -81.69275)
		(mid 83.358355 -81.311496)
		(end 82.977228 -81.692496)
		(stroke
			(width 0.2)
			(type default)
		)
		(layer "In1.Cu")
	)
	(gr_line
		(start 83.739228 -76.194158)
		(end 83.739228 -75.305412)
		(stroke
			(width 0.2)
			(type default)
		)
		(layer "In1.Cu")
	)
	(gr_arc
		(start 83.739228 -75.305412)
		(mid 83.358355 -74.924158)
		(end 82.977228 -75.305158)
		(stroke
			(width 0.2)
			(type default)
		)
		(layer "In1.Cu")
	)
	(gr_line
		(start 83.740498 -88.980264)
		(end 83.740498 -88.091518)
		(stroke
			(width 0.2)
			(type default)
		)
		(layer "In1.Cu")
	)
	(gr_arc
		(start 83.740498 -88.091518)
		(mid 83.359625 -87.710264)
		(end 82.978498 -88.091264)
		(stroke
			(width 0.2)
			(type default)
		)
		(layer "In1.Cu")
	)
	(gr_arc
		(start 84.482178 -72.987916)
		(mid 84.863178 -73.368916)
		(end 85.244178 -72.987916)
		(stroke
			(width 0.2)
			(type default)
		)
		(layer "In1.Cu")
	)
	(gr_line
		(start 84.482178 -72.098916)
		(end 84.482178 -72.987916)
		(stroke
			(width 0.2)
			(type default)
		)
		(layer "In1.Cu")
	)
	(gr_arc
		(start 84.602828 -92.195396)
		(mid 84.983828 -92.576396)
		(end 85.364828 -92.195396)
		(stroke
			(width 0.2)
			(type default)
		)
		(layer "In1.Cu")
	)
	(gr_line
		(start 84.602828 -91.306396)
		(end 84.602828 -92.195396)
		(stroke
			(width 0.2)
			(type default)
		)
		(layer "In1.Cu")
	)
	(gr_arc
		(start 84.602828 -85.781134)
		(mid 84.983828 -86.162134)
		(end 85.364828 -85.781134)
		(stroke
			(width 0.2)
			(type default)
		)
		(layer "In1.Cu")
	)
	(gr_line
		(start 84.602828 -84.892134)
		(end 84.602828 -85.781134)
		(stroke
			(width 0.2)
			(type default)
		)
		(layer "In1.Cu")
	)
	(gr_arc
		(start 84.605622 -79.396336)
		(mid 84.986622 -79.777336)
		(end 85.367622 -79.396336)
		(stroke
			(width 0.2)
			(type default)
		)
		(layer "In1.Cu")
	)
	(gr_line
		(start 84.605622 -78.507336)
		(end 84.605622 -79.396336)
		(stroke
			(width 0.2)
			(type default)
		)
		(layer "In1.Cu")
	)
	(gr_line
		(start 85.244178 -72.987916)
		(end 85.244178 -72.09917)
		(stroke
			(width 0.2)
			(type default)
		)
		(layer "In1.Cu")
	)
	(gr_arc
		(start 85.244178 -72.09917)
		(mid 84.863305 -71.717916)
		(end 84.482178 -72.098916)
		(stroke
			(width 0.2)
			(type default)
		)
		(layer "In1.Cu")
	)
	(gr_line
		(start 85.364828 -92.195396)
		(end 85.364828 -91.30665)
		(stroke
			(width 0.2)
			(type default)
		)
		(layer "In1.Cu")
	)
	(gr_arc
		(start 85.364828 -91.30665)
		(mid 84.983955 -90.925396)
		(end 84.602828 -91.306396)
		(stroke
			(width 0.2)
			(type default)
		)
		(layer "In1.Cu")
	)
	(gr_line
		(start 85.364828 -85.781134)
		(end 85.364828 -84.892388)
		(stroke
			(width 0.2)
			(type default)
		)
		(layer "In1.Cu")
	)
	(gr_arc
		(start 85.364828 -84.892388)
		(mid 84.983955 -84.511134)
		(end 84.602828 -84.892134)
		(stroke
			(width 0.2)
			(type default)
		)
		(layer "In1.Cu")
	)
	(gr_line
		(start 85.367622 -79.396336)
		(end 85.367622 -78.50759)
		(stroke
			(width 0.2)
			(type default)
		)
		(layer "In1.Cu")
	)
	(gr_arc
		(start 85.367622 -78.50759)
		(mid 84.986749 -78.126336)
		(end 84.605622 -78.507336)
		(stroke
			(width 0.2)
			(type default)
		)
		(layer "In1.Cu")
	)
	(gr_line
		(start 98.081846 -194.00012)
		(end 5.617972 -194.00012)
		(stroke
			(width 1.524)
			(type default)
		)
		(layer "In1.Cu")
	)
	(gr_arc
		(start 98.081846 -194.00012)
		(mid 98.607706 -193.850755)
		(end 98.976434 -193.447162)
		(stroke
			(width 1.524)
			(type default)
		)
		(layer "In1.Cu")
	)
	(gr_line
		(start 103.594408 -184.211214)
		(end 98.976434 -193.447162)
		(stroke
			(width 1.524)
			(type default)
		)
		(layer "In1.Cu")
	)
	(gr_arc
		(start 103.594408 -184.211214)
		(mid 103.673311 -183.993725)
		(end 103.700072 -183.76392)
		(stroke
			(width 1.524)
			(type default)
		)
		(layer "In1.Cu")
	)
	(gr_line
		(start 103.700072 -47.999904)
		(end 103.700072 -183.76392)
		(stroke
			(width 1.524)
			(type default)
		)
		(layer "In1.Cu")
	)
	(gr_arc
		(start 104.70007 -47.999904)
		(mid 104.200198 -47.500032)
		(end 103.700072 -47.999904)
		(stroke
			(width 1.524)
			(type default)
		)
		(layer "In1.Cu")
	)
	(gr_arc
		(start 106.614722 -38.199822)
		(mid 107.099735 -38.685216)
		(end 107.585002 -38.200076)
		(stroke
			(width 0.2)
			(type default)
		)
		(layer "In1.Cu")
	)
	(gr_line
		(start 106.614722 -36.800028)
		(end 106.614722 -38.199822)
		(stroke
			(width 0.2)
			(type default)
		)
		(layer "In1.Cu")
	)
	(gr_arc
		(start 106.614722 -34.600134)
		(mid 107.099862 -35.085274)
		(end 107.585002 -34.600134)
		(stroke
			(width 0.2)
			(type default)
		)
		(layer "In1.Cu")
	)
	(gr_line
		(start 106.614722 -33.200086)
		(end 106.614722 -34.600134)
		(stroke
			(width 0.2)
			(type default)
		)
		(layer "In1.Cu")
	)
	(gr_line
		(start 107.585002 -38.200076)
		(end 107.585002 -36.800028)
		(stroke
			(width 0.2)
			(type default)
		)
		(layer "In1.Cu")
	)
	(gr_arc
		(start 107.585002 -36.800028)
		(mid 107.099862 -36.314888)
		(end 106.614722 -36.800028)
		(stroke
			(width 0.2)
			(type default)
		)
		(layer "In1.Cu")
	)
	(gr_line
		(start 107.585002 -34.600134)
		(end 107.585002 -33.20034)
		(stroke
			(width 0.2)
			(type default)
		)
		(layer "In1.Cu")
	)
	(gr_arc
		(start 107.585002 -33.20034)
		(mid 107.099989 -32.714946)
		(end 106.614722 -33.200086)
		(stroke
			(width 0.2)
			(type default)
		)
		(layer "In1.Cu")
	)
	(gr_arc
		(start 108.41482 -36.999926)
		(mid 108.899833 -37.48532)
		(end 109.3851 -37.00018)
		(stroke
			(width 0.2)
			(type default)
		)
		(layer "In1.Cu")
	)
	(gr_line
		(start 108.41482 -35.600132)
		(end 108.41482 -36.999926)
		(stroke
			(width 0.2)
			(type default)
		)
		(layer "In1.Cu")
	)
	(gr_arc
		(start 108.41482 -33.39973)
		(mid 108.899833 -33.885124)
		(end 109.3851 -33.399984)
		(stroke
			(width 0.2)
			(type default)
		)
		(layer "In1.Cu")
	)
	(gr_line
		(start 108.41482 -32.00019)
		(end 108.41482 -33.39973)
		(stroke
			(width 0.2)
			(type default)
		)
		(layer "In1.Cu")
	)
	(gr_line
		(start 109.0295 -14.362938)
		(end 109.3597 -14.693138)
		(stroke
			(width 0.381)
			(type default)
		)
		(layer "In1.Cu")
	)
	(gr_line
		(start 109.0295 -6.5913)
		(end 109.0295 -14.362938)
		(stroke
			(width 0.381)
			(type default)
		)
		(layer "In1.Cu")
	)
	(gr_line
		(start 109.3597 -14.693138)
		(end 116.191538 -14.693138)
		(stroke
			(width 0.381)
			(type default)
		)
		(layer "In1.Cu")
	)
	(gr_line
		(start 109.3851 -37.00018)
		(end 109.3851 -35.600132)
		(stroke
			(width 0.2)
			(type default)
		)
		(layer "In1.Cu")
	)
	(gr_arc
		(start 109.3851 -35.600132)
		(mid 108.89996 -35.114992)
		(end 108.41482 -35.600132)
		(stroke
			(width 0.2)
			(type default)
		)
		(layer "In1.Cu")
	)
	(gr_line
		(start 109.3851 -33.399984)
		(end 109.3851 -32.00019)
		(stroke
			(width 0.2)
			(type default)
		)
		(layer "In1.Cu")
	)
	(gr_arc
		(start 109.3851 -32.00019)
		(mid 108.89996 -31.51505)
		(end 108.41482 -32.00019)
		(stroke
			(width 0.2)
			(type default)
		)
		(layer "In1.Cu")
	)
	(gr_arc
		(start 110.214918 -38.199822)
		(mid 110.699931 -38.685216)
		(end 111.185198 -38.200076)
		(stroke
			(width 0.2)
			(type default)
		)
		(layer "In1.Cu")
	)
	(gr_line
		(start 110.214918 -36.800028)
		(end 110.214918 -38.199822)
		(stroke
			(width 0.2)
			(type default)
		)
		(layer "In1.Cu")
	)
	(gr_arc
		(start 110.214918 -34.600134)
		(mid 110.700058 -35.085274)
		(end 111.185198 -34.600134)
		(stroke
			(width 0.2)
			(type default)
		)
		(layer "In1.Cu")
	)
	(gr_line
		(start 110.214918 -33.200086)
		(end 110.214918 -34.600134)
		(stroke
			(width 0.2)
			(type default)
		)
		(layer "In1.Cu")
	)
	(gr_line
		(start 111.185198 -38.200076)
		(end 111.185198 -36.800028)
		(stroke
			(width 0.2)
			(type default)
		)
		(layer "In1.Cu")
	)
	(gr_arc
		(start 111.185198 -36.800028)
		(mid 110.700058 -36.314888)
		(end 110.214918 -36.800028)
		(stroke
			(width 0.2)
			(type default)
		)
		(layer "In1.Cu")
	)
	(gr_line
		(start 111.185198 -34.600134)
		(end 111.185198 -33.20034)
		(stroke
			(width 0.2)
			(type default)
		)
		(layer "In1.Cu")
	)
	(gr_arc
		(start 111.185198 -33.20034)
		(mid 110.700185 -32.714946)
		(end 110.214918 -33.200086)
		(stroke
			(width 0.2)
			(type default)
		)
		(layer "In1.Cu")
	)
	(gr_line
		(start 111.698278 -3.922522)
		(end 109.0295 -6.5913)
		(stroke
			(width 0.381)
			(type default)
		)
		(layer "In1.Cu")
	)
	(gr_arc
		(start 112.014762 -36.999926)
		(mid 112.499775 -37.48532)
		(end 112.985042 -37.00018)
		(stroke
			(width 0.2)
			(type default)
		)
		(layer "In1.Cu")
	)
	(gr_line
		(start 112.014762 -35.600132)
		(end 112.014762 -36.999926)
		(stroke
			(width 0.2)
			(type default)
		)
		(layer "In1.Cu")
	)
	(gr_arc
		(start 112.014762 -33.39973)
		(mid 112.499775 -33.885124)
		(end 112.985042 -33.399984)
		(stroke
			(width 0.2)
			(type default)
		)
		(layer "In1.Cu")
	)
	(gr_line
		(start 112.014762 -32.00019)
		(end 112.014762 -33.39973)
		(stroke
			(width 0.2)
			(type default)
		)
		(layer "In1.Cu")
	)
	(gr_line
		(start 112.985042 -37.00018)
		(end 112.985042 -35.600132)
		(stroke
			(width 0.2)
			(type default)
		)
		(layer "In1.Cu")
	)
	(gr_arc
		(start 112.985042 -35.600132)
		(mid 112.499902 -35.114992)
		(end 112.014762 -35.600132)
		(stroke
			(width 0.2)
			(type default)
		)
		(layer "In1.Cu")
	)
	(gr_line
		(start 112.985042 -33.399984)
		(end 112.985042 -32.00019)
		(stroke
			(width 0.2)
			(type default)
		)
		(layer "In1.Cu")
	)
	(gr_arc
		(start 112.985042 -32.00019)
		(mid 112.499902 -31.51505)
		(end 112.014762 -32.00019)
		(stroke
			(width 0.2)
			(type default)
		)
		(layer "In1.Cu")
	)
	(gr_arc
		(start 113.81486 -38.199822)
		(mid 114.299873 -38.685216)
		(end 114.78514 -38.200076)
		(stroke
			(width 0.2)
			(type default)
		)
		(layer "In1.Cu")
	)
	(gr_line
		(start 113.81486 -36.800028)
		(end 113.81486 -38.199822)
		(stroke
			(width 0.2)
			(type default)
		)
		(layer "In1.Cu")
	)
	(gr_arc
		(start 113.81486 -34.600134)
		(mid 114.3 -35.085274)
		(end 114.78514 -34.600134)
		(stroke
			(width 0.2)
			(type default)
		)
		(layer "In1.Cu")
	)
	(gr_line
		(start 113.81486 -33.200086)
		(end 113.81486 -34.600134)
		(stroke
			(width 0.2)
			(type default)
		)
		(layer "In1.Cu")
	)
	(gr_line
		(start 114.78514 -38.200076)
		(end 114.78514 -36.800028)
		(stroke
			(width 0.2)
			(type default)
		)
		(layer "In1.Cu")
	)
	(gr_arc
		(start 114.78514 -36.800028)
		(mid 114.3 -36.314888)
		(end 113.81486 -36.800028)
		(stroke
			(width 0.2)
			(type default)
		)
		(layer "In1.Cu")
	)
	(gr_line
		(start 114.78514 -34.600134)
		(end 114.78514 -33.20034)
		(stroke
			(width 0.2)
			(type default)
		)
		(layer "In1.Cu")
	)
	(gr_arc
		(start 114.78514 -33.20034)
		(mid 114.300127 -32.714946)
		(end 113.81486 -33.200086)
		(stroke
			(width 0.2)
			(type default)
		)
		(layer "In1.Cu")
	)
	(gr_arc
		(start 115.614704 -36.999926)
		(mid 116.099717 -37.48532)
		(end 116.584984 -37.00018)
		(stroke
			(width 0.2)
			(type default)
		)
		(layer "In1.Cu")
	)
	(gr_line
		(start 115.614704 -35.600132)
		(end 115.614704 -36.999926)
		(stroke
			(width 0.2)
			(type default)
		)
		(layer "In1.Cu")
	)
	(gr_arc
		(start 115.614704 -33.39973)
		(mid 116.099717 -33.885124)
		(end 116.584984 -33.399984)
		(stroke
			(width 0.2)
			(type default)
		)
		(layer "In1.Cu")
	)
	(gr_line
		(start 115.614704 -32.00019)
		(end 115.614704 -33.39973)
		(stroke
			(width 0.2)
			(type default)
		)
		(layer "In1.Cu")
	)
	(gr_line
		(start 116.191538 -14.693138)
		(end 116.6114 -15.113)
		(stroke
			(width 0.381)
			(type default)
		)
		(layer "In1.Cu")
	)
	(gr_line
		(start 116.584984 -37.00018)
		(end 116.584984 -35.600132)
		(stroke
			(width 0.2)
			(type default)
		)
		(layer "In1.Cu")
	)
	(gr_arc
		(start 116.584984 -35.600132)
		(mid 116.099844 -35.114992)
		(end 115.614704 -35.600132)
		(stroke
			(width 0.2)
			(type default)
		)
		(layer "In1.Cu")
	)
	(gr_line
		(start 116.584984 -33.399984)
		(end 116.584984 -32.00019)
		(stroke
			(width 0.2)
			(type default)
		)
		(layer "In1.Cu")
	)
	(gr_arc
		(start 116.584984 -32.00019)
		(mid 116.099844 -31.51505)
		(end 115.614704 -32.00019)
		(stroke
			(width 0.2)
			(type default)
		)
		(layer "In1.Cu")
	)
	(gr_line
		(start 116.6114 -15.113)
		(end 118.084092 -15.113)
		(stroke
			(width 0.381)
			(type default)
		)
		(layer "In1.Cu")
	)
	(gr_arc
		(start 117.414802 -38.199822)
		(mid 117.899815 -38.685216)
		(end 118.385082 -38.200076)
		(stroke
			(width 0.2)
			(type default)
		)
		(layer "In1.Cu")
	)
	(gr_line
		(start 117.414802 -36.800028)
		(end 117.414802 -38.199822)
		(stroke
			(width 0.2)
			(type default)
		)
		(layer "In1.Cu")
	)
	(gr_arc
		(start 117.414802 -34.600134)
		(mid 117.899942 -35.085274)
		(end 118.385082 -34.600134)
		(stroke
			(width 0.2)
			(type default)
		)
		(layer "In1.Cu")
	)
	(gr_line
		(start 117.414802 -33.200086)
		(end 117.414802 -34.600134)
		(stroke
			(width 0.2)
			(type default)
		)
		(layer "In1.Cu")
	)
	(gr_line
		(start 118.084092 -15.113)
		(end 118.426738 -15.455646)
		(stroke
			(width 0.381)
			(type default)
		)
		(layer "In1.Cu")
	)
	(gr_line
		(start 118.385082 -38.200076)
		(end 118.385082 -36.800028)
		(stroke
			(width 0.2)
			(type default)
		)
		(layer "In1.Cu")
	)
	(gr_arc
		(start 118.385082 -36.800028)
		(mid 117.899942 -36.314888)
		(end 117.414802 -36.800028)
		(stroke
			(width 0.2)
			(type default)
		)
		(layer "In1.Cu")
	)
	(gr_line
		(start 118.385082 -34.600134)
		(end 118.385082 -33.20034)
		(stroke
			(width 0.2)
			(type default)
		)
		(layer "In1.Cu")
	)
	(gr_arc
		(start 118.385082 -33.20034)
		(mid 117.900069 -32.714946)
		(end 117.414802 -33.200086)
		(stroke
			(width 0.2)
			(type default)
		)
		(layer "In1.Cu")
	)
	(gr_line
		(start 118.426738 -17.008856)
		(end 118.785386 -17.367504)
		(stroke
			(width 0.381)
			(type default)
		)
		(layer "In1.Cu")
	)
	(gr_line
		(start 118.426738 -15.455646)
		(end 118.426738 -17.008856)
		(stroke
			(width 0.381)
			(type default)
		)
		(layer "In1.Cu")
	)
	(gr_line
		(start 118.785386 -17.367504)
		(end 126.830836 -17.367504)
		(stroke
			(width 0.381)
			(type default)
		)
		(layer "In1.Cu")
	)
	(gr_arc
		(start 119.2149 -44.19981)
		(mid 119.699913 -44.685204)
		(end 120.18518 -44.200064)
		(stroke
			(width 0.2)
			(type default)
		)
		(layer "In1.Cu")
	)
	(gr_line
		(start 119.2149 -42.800016)
		(end 119.2149 -44.19981)
		(stroke
			(width 0.2)
			(type default)
		)
		(layer "In1.Cu")
	)
	(gr_arc
		(start 119.2149 -36.999926)
		(mid 119.699913 -37.48532)
		(end 120.18518 -37.00018)
		(stroke
			(width 0.2)
			(type default)
		)
		(layer "In1.Cu")
	)
	(gr_line
		(start 119.2149 -35.600132)
		(end 119.2149 -36.999926)
		(stroke
			(width 0.2)
			(type default)
		)
		(layer "In1.Cu")
	)
	(gr_arc
		(start 119.2149 -33.39973)
		(mid 119.699913 -33.885124)
		(end 120.18518 -33.399984)
		(stroke
			(width 0.2)
			(type default)
		)
		(layer "In1.Cu")
	)
	(gr_line
		(start 119.2149 -32.00019)
		(end 119.2149 -33.39973)
		(stroke
			(width 0.2)
			(type default)
		)
		(layer "In1.Cu")
	)
	(gr_line
		(start 120.18518 -44.200064)
		(end 120.18518 -42.800016)
		(stroke
			(width 0.2)
			(type default)
		)
		(layer "In1.Cu")
	)
	(gr_arc
		(start 120.18518 -42.800016)
		(mid 119.70004 -42.314876)
		(end 119.2149 -42.800016)
		(stroke
			(width 0.2)
			(type default)
		)
		(layer "In1.Cu")
	)
	(gr_line
		(start 120.18518 -37.00018)
		(end 120.18518 -35.600132)
		(stroke
			(width 0.2)
			(type default)
		)
		(layer "In1.Cu")
	)
	(gr_arc
		(start 120.18518 -35.600132)
		(mid 119.70004 -35.114992)
		(end 119.2149 -35.600132)
		(stroke
			(width 0.2)
			(type default)
		)
		(layer "In1.Cu")
	)
	(gr_line
		(start 120.18518 -33.399984)
		(end 120.18518 -32.00019)
		(stroke
			(width 0.2)
			(type default)
		)
		(layer "In1.Cu")
	)
	(gr_arc
		(start 120.18518 -32.00019)
		(mid 119.70004 -31.51505)
		(end 119.2149 -32.00019)
		(stroke
			(width 0.2)
			(type default)
		)
		(layer "In1.Cu")
	)
	(gr_line
		(start 125.648974 -3.922522)
		(end 111.698278 -3.922522)
		(stroke
			(width 0.381)
			(type default)
		)
		(layer "In1.Cu")
	)
	(gr_line
		(start 126.830836 -17.367504)
		(end 128.12268 -16.07566)
		(stroke
			(width 0.381)
			(type default)
		)
		(layer "In1.Cu")
	)
	(gr_line
		(start 126.886462 -10.976864)
		(end 126.886462 -5.16001)
		(stroke
			(width 0.381)
			(type default)
		)
		(layer "In1.Cu")
	)
	(gr_line
		(start 126.886462 -5.16001)
		(end 125.648974 -3.922522)
		(stroke
			(width 0.381)
			(type default)
		)
		(layer "In1.Cu")
	)
	(gr_line
		(start 128.12268 -16.07566)
		(end 128.12268 -12.213082)
		(stroke
			(width 0.381)
			(type default)
		)
		(layer "In1.Cu")
	)
	(gr_line
		(start 128.12268 -12.213082)
		(end 126.886462 -10.976864)
		(stroke
			(width 0.381)
			(type default)
		)
		(layer "In1.Cu")
	)
	(gr_arc
		(start 128.214882 -38.199822)
		(mid 128.699895 -38.685216)
		(end 129.185162 -38.200076)
		(stroke
			(width 0.2)
			(type default)
		)
		(layer "In1.Cu")
	)
	(gr_line
		(start 128.214882 -36.800028)
		(end 128.214882 -38.199822)
		(stroke
			(width 0.2)
			(type default)
		)
		(layer "In1.Cu")
	)
	(gr_arc
		(start 128.214882 -34.600134)
		(mid 128.700022 -35.085274)
		(end 129.185162 -34.600134)
		(stroke
			(width 0.2)
			(type default)
		)
		(layer "In1.Cu")
	)
	(gr_line
		(start 128.214882 -33.200086)
		(end 128.214882 -34.600134)
		(stroke
			(width 0.2)
			(type default)
		)
		(layer "In1.Cu")
	)
	(gr_line
		(start 128.467866 -26.592276)
		(end 129.53492 -26.592276)
		(stroke
			(width 0.2)
			(type default)
		)
		(layer "In1.Cu")
	)
	(gr_arc
		(start 128.467866 -25.830276)
		(mid 128.086866 -26.211276)
		(end 128.467866 -26.592276)
		(stroke
			(width 0.2)
			(type default)
		)
		(layer "In1.Cu")
	)
	(gr_line
		(start 129.185162 -38.200076)
		(end 129.185162 -36.800028)
		(stroke
			(width 0.2)
			(type default)
		)
		(layer "In1.Cu")
	)
	(gr_arc
		(start 129.185162 -36.800028)
		(mid 128.700022 -36.314888)
		(end 128.214882 -36.800028)
		(stroke
			(width 0.2)
			(type default)
		)
		(layer "In1.Cu")
	)
	(gr_line
		(start 129.185162 -34.600134)
		(end 129.185162 -33.20034)
		(stroke
			(width 0.2)
			(type default)
		)
		(layer "In1.Cu")
	)
	(gr_arc
		(start 129.185162 -33.20034)
		(mid 128.700149 -32.714946)
		(end 128.214882 -33.200086)
		(stroke
			(width 0.2)
			(type default)
		)
		(layer "In1.Cu")
	)
	(gr_arc
		(start 129.53492 -26.592276)
		(mid 129.916174 -26.211403)
		(end 129.535174 -25.830276)
		(stroke
			(width 0.2)
			(type default)
		)
		(layer "In1.Cu")
	)
	(gr_line
		(start 129.535174 -25.830276)
		(end 128.467866 -25.830276)
		(stroke
			(width 0.2)
			(type default)
		)
		(layer "In1.Cu")
	)
	(gr_arc
		(start 130.014726 -36.999926)
		(mid 130.499739 -37.48532)
		(end 130.985006 -37.00018)
		(stroke
			(width 0.2)
			(type default)
		)
		(layer "In1.Cu")
	)
	(gr_line
		(start 130.014726 -35.600132)
		(end 130.014726 -36.999926)
		(stroke
			(width 0.2)
			(type default)
		)
		(layer "In1.Cu")
	)
	(gr_arc
		(start 130.014726 -33.39973)
		(mid 130.499739 -33.885124)
		(end 130.985006 -33.399984)
		(stroke
			(width 0.2)
			(type default)
		)
		(layer "In1.Cu")
	)
	(gr_line
		(start 130.014726 -32.00019)
		(end 130.014726 -33.39973)
		(stroke
			(width 0.2)
			(type default)
		)
		(layer "In1.Cu")
	)
	(gr_line
		(start 130.985006 -37.00018)
		(end 130.985006 -35.600132)
		(stroke
			(width 0.2)
			(type default)
		)
		(layer "In1.Cu")
	)
	(gr_arc
		(start 130.985006 -35.600132)
		(mid 130.499866 -35.114992)
		(end 130.014726 -35.600132)
		(stroke
			(width 0.2)
			(type default)
		)
		(layer "In1.Cu")
	)
	(gr_line
		(start 130.985006 -33.399984)
		(end 130.985006 -32.00019)
		(stroke
			(width 0.2)
			(type default)
		)
		(layer "In1.Cu")
	)
	(gr_arc
		(start 130.985006 -32.00019)
		(mid 130.499866 -31.51505)
		(end 130.014726 -32.00019)
		(stroke
			(width 0.2)
			(type default)
		)
		(layer "In1.Cu")
	)
	(gr_arc
		(start 131.814824 -38.199822)
		(mid 132.299837 -38.685216)
		(end 132.785104 -38.200076)
		(stroke
			(width 0.2)
			(type default)
		)
		(layer "In1.Cu")
	)
	(gr_line
		(start 131.814824 -36.800028)
		(end 131.814824 -38.199822)
		(stroke
			(width 0.2)
			(type default)
		)
		(layer "In1.Cu")
	)
	(gr_arc
		(start 131.814824 -34.600134)
		(mid 132.299964 -35.085274)
		(end 132.785104 -34.600134)
		(stroke
			(width 0.2)
			(type default)
		)
		(layer "In1.Cu")
	)
	(gr_line
		(start 131.814824 -33.200086)
		(end 131.814824 -34.600134)
		(stroke
			(width 0.2)
			(type default)
		)
		(layer "In1.Cu")
	)
	(gr_line
		(start 132.785104 -38.200076)
		(end 132.785104 -36.800028)
		(stroke
			(width 0.2)
			(type default)
		)
		(layer "In1.Cu")
	)
	(gr_arc
		(start 132.785104 -36.800028)
		(mid 132.299964 -36.314888)
		(end 131.814824 -36.800028)
		(stroke
			(width 0.2)
			(type default)
		)
		(layer "In1.Cu")
	)
	(gr_line
		(start 132.785104 -34.600134)
		(end 132.785104 -33.20034)
		(stroke
			(width 0.2)
			(type default)
		)
		(layer "In1.Cu")
	)
	(gr_arc
		(start 132.785104 -33.20034)
		(mid 132.300091 -32.714946)
		(end 131.814824 -33.200086)
		(stroke
			(width 0.2)
			(type default)
		)
		(layer "In1.Cu")
	)
	(gr_arc
		(start 133.614922 -44.19981)
		(mid 134.099935 -44.685204)
		(end 134.585202 -44.200064)
		(stroke
			(width 0.2)
			(type default)
		)
		(layer "In1.Cu")
	)
	(gr_line
		(start 133.614922 -42.800016)
		(end 133.614922 -44.19981)
		(stroke
			(width 0.2)
			(type default)
		)
		(layer "In1.Cu")
	)
	(gr_arc
		(start 133.614922 -36.999926)
		(mid 134.099935 -37.48532)
		(end 134.585202 -37.00018)
		(stroke
			(width 0.2)
			(type default)
		)
		(layer "In1.Cu")
	)
	(gr_line
		(start 133.614922 -35.600132)
		(end 133.614922 -36.999926)
		(stroke
			(width 0.2)
			(type default)
		)
		(layer "In1.Cu")
	)
	(gr_arc
		(start 133.614922 -33.39973)
		(mid 134.099935 -33.885124)
		(end 134.585202 -33.399984)
		(stroke
			(width 0.2)
			(type default)
		)
		(layer "In1.Cu")
	)
	(gr_line
		(start 133.614922 -32.00019)
		(end 133.614922 -33.39973)
		(stroke
			(width 0.2)
			(type default)
		)
		(layer "In1.Cu")
	)
	(gr_line
		(start 134.585202 -44.200064)
		(end 134.585202 -42.800016)
		(stroke
			(width 0.2)
			(type default)
		)
		(layer "In1.Cu")
	)
	(gr_arc
		(start 134.585202 -42.800016)
		(mid 134.100062 -42.314876)
		(end 133.614922 -42.800016)
		(stroke
			(width 0.2)
			(type default)
		)
		(layer "In1.Cu")
	)
	(gr_line
		(start 134.585202 -37.00018)
		(end 134.585202 -35.600132)
		(stroke
			(width 0.2)
			(type default)
		)
		(layer "In1.Cu")
	)
	(gr_arc
		(start 134.585202 -35.600132)
		(mid 134.100062 -35.114992)
		(end 133.614922 -35.600132)
		(stroke
			(width 0.2)
			(type default)
		)
		(layer "In1.Cu")
	)
	(gr_line
		(start 134.585202 -33.399984)
		(end 134.585202 -32.00019)
		(stroke
			(width 0.2)
			(type default)
		)
		(layer "In1.Cu")
	)
	(gr_arc
		(start 134.585202 -32.00019)
		(mid 134.100062 -31.51505)
		(end 133.614922 -32.00019)
		(stroke
			(width 0.2)
			(type default)
		)
		(layer "In1.Cu")
	)
	(gr_arc
		(start 135.414766 -38.199822)
		(mid 135.899779 -38.685216)
		(end 136.385046 -38.200076)
		(stroke
			(width 0.2)
			(type default)
		)
		(layer "In1.Cu")
	)
	(gr_line
		(start 135.414766 -36.800028)
		(end 135.414766 -38.199822)
		(stroke
			(width 0.2)
			(type default)
		)
		(layer "In1.Cu")
	)
	(gr_arc
		(start 135.414766 -34.600134)
		(mid 135.899906 -35.085274)
		(end 136.385046 -34.600134)
		(stroke
			(width 0.2)
			(type default)
		)
		(layer "In1.Cu")
	)
	(gr_line
		(start 135.414766 -33.200086)
		(end 135.414766 -34.600134)
		(stroke
			(width 0.2)
			(type default)
		)
		(layer "In1.Cu")
	)
	(gr_line
		(start 136.385046 -38.200076)
		(end 136.385046 -36.800028)
		(stroke
			(width 0.2)
			(type default)
		)
		(layer "In1.Cu")
	)
	(gr_arc
		(start 136.385046 -36.800028)
		(mid 135.899906 -36.314888)
		(end 135.414766 -36.800028)
		(stroke
			(width 0.2)
			(type default)
		)
		(layer "In1.Cu")
	)
	(gr_line
		(start 136.385046 -34.600134)
		(end 136.385046 -33.20034)
		(stroke
			(width 0.2)
			(type default)
		)
		(layer "In1.Cu")
	)
	(gr_arc
		(start 136.385046 -33.20034)
		(mid 135.900033 -32.714946)
		(end 135.414766 -33.200086)
		(stroke
			(width 0.2)
			(type default)
		)
		(layer "In1.Cu")
	)
	(gr_arc
		(start 137.214864 -36.999926)
		(mid 137.699877 -37.48532)
		(end 138.185144 -37.00018)
		(stroke
			(width 0.2)
			(type default)
		)
		(layer "In1.Cu")
	)
	(gr_line
		(start 137.214864 -35.600132)
		(end 137.214864 -36.999926)
		(stroke
			(width 0.2)
			(type default)
		)
		(layer "In1.Cu")
	)
	(gr_arc
		(start 137.214864 -33.39973)
		(mid 137.699877 -33.885124)
		(end 138.185144 -33.399984)
		(stroke
			(width 0.2)
			(type default)
		)
		(layer "In1.Cu")
	)
	(gr_line
		(start 137.214864 -32.00019)
		(end 137.214864 -33.39973)
		(stroke
			(width 0.2)
			(type default)
		)
		(layer "In1.Cu")
	)
	(gr_line
		(start 138.185144 -37.00018)
		(end 138.185144 -35.600132)
		(stroke
			(width 0.2)
			(type default)
		)
		(layer "In1.Cu")
	)
	(gr_arc
		(start 138.185144 -35.600132)
		(mid 137.700004 -35.114992)
		(end 137.214864 -35.600132)
		(stroke
			(width 0.2)
			(type default)
		)
		(layer "In1.Cu")
	)
	(gr_line
		(start 138.185144 -33.399984)
		(end 138.185144 -32.00019)
		(stroke
			(width 0.2)
			(type default)
		)
		(layer "In1.Cu")
	)
	(gr_arc
		(start 138.185144 -32.00019)
		(mid 137.700004 -31.51505)
		(end 137.214864 -32.00019)
		(stroke
			(width 0.2)
			(type default)
		)
		(layer "In1.Cu")
	)
	(gr_arc
		(start 139.014708 -38.199822)
		(mid 139.499721 -38.685216)
		(end 139.984988 -38.200076)
		(stroke
			(width 0.2)
			(type default)
		)
		(layer "In1.Cu")
	)
	(gr_line
		(start 139.014708 -36.800028)
		(end 139.014708 -38.199822)
		(stroke
			(width 0.2)
			(type default)
		)
		(layer "In1.Cu")
	)
	(gr_arc
		(start 139.014708 -34.600134)
		(mid 139.499848 -35.085274)
		(end 139.984988 -34.600134)
		(stroke
			(width 0.2)
			(type default)
		)
		(layer "In1.Cu")
	)
	(gr_line
		(start 139.014708 -33.200086)
		(end 139.014708 -34.600134)
		(stroke
			(width 0.2)
			(type default)
		)
		(layer "In1.Cu")
	)
	(gr_line
		(start 139.984988 -38.200076)
		(end 139.984988 -36.800028)
		(stroke
			(width 0.2)
			(type default)
		)
		(layer "In1.Cu")
	)
	(gr_arc
		(start 139.984988 -36.800028)
		(mid 139.499848 -36.314888)
		(end 139.014708 -36.800028)
		(stroke
			(width 0.2)
			(type default)
		)
		(layer "In1.Cu")
	)
	(gr_line
		(start 139.984988 -34.600134)
		(end 139.984988 -33.20034)
		(stroke
			(width 0.2)
			(type default)
		)
		(layer "In1.Cu")
	)
	(gr_arc
		(start 139.984988 -33.20034)
		(mid 139.499975 -32.714946)
		(end 139.014708 -33.200086)
		(stroke
			(width 0.2)
			(type default)
		)
		(layer "In1.Cu")
	)
	(gr_arc
		(start 140.814806 -44.19981)
		(mid 141.299819 -44.685204)
		(end 141.785086 -44.200064)
		(stroke
			(width 0.2)
			(type default)
		)
		(layer "In1.Cu")
	)
	(gr_line
		(start 140.814806 -42.800016)
		(end 140.814806 -44.19981)
		(stroke
			(width 0.2)
			(type default)
		)
		(layer "In1.Cu")
	)
	(gr_arc
		(start 140.814806 -36.999926)
		(mid 141.299819 -37.48532)
		(end 141.785086 -37.00018)
		(stroke
			(width 0.2)
			(type default)
		)
		(layer "In1.Cu")
	)
	(gr_line
		(start 140.814806 -35.600132)
		(end 140.814806 -36.999926)
		(stroke
			(width 0.2)
			(type default)
		)
		(layer "In1.Cu")
	)
	(gr_arc
		(start 140.814806 -33.39973)
		(mid 141.299819 -33.885124)
		(end 141.785086 -33.399984)
		(stroke
			(width 0.2)
			(type default)
		)
		(layer "In1.Cu")
	)
	(gr_line
		(start 140.814806 -32.00019)
		(end 140.814806 -33.39973)
		(stroke
			(width 0.2)
			(type default)
		)
		(layer "In1.Cu")
	)
	(gr_line
		(start 141.785086 -44.200064)
		(end 141.785086 -42.800016)
		(stroke
			(width 0.2)
			(type default)
		)
		(layer "In1.Cu")
	)
	(gr_arc
		(start 141.785086 -42.800016)
		(mid 141.299946 -42.314876)
		(end 140.814806 -42.800016)
		(stroke
			(width 0.2)
			(type default)
		)
		(layer "In1.Cu")
	)
	(gr_line
		(start 141.785086 -37.00018)
		(end 141.785086 -35.600132)
		(stroke
			(width 0.2)
			(type default)
		)
		(layer "In1.Cu")
	)
	(gr_arc
		(start 141.785086 -35.600132)
		(mid 141.299946 -35.114992)
		(end 140.814806 -35.600132)
		(stroke
			(width 0.2)
			(type default)
		)
		(layer "In1.Cu")
	)
	(gr_line
		(start 141.785086 -33.399984)
		(end 141.785086 -32.00019)
		(stroke
			(width 0.2)
			(type default)
		)
		(layer "In1.Cu")
	)
	(gr_arc
		(start 141.785086 -32.00019)
		(mid 141.299946 -31.51505)
		(end 140.814806 -32.00019)
		(stroke
			(width 0.2)
			(type default)
		)
		(layer "In1.Cu")
	)
	(gr_line
		(start 143.299942 -47.999904)
		(end 104.70007 -47.999904)
		(stroke
			(width 1.524)
			(type default)
		)
		(layer "In1.Cu")
	)
	(gr_line
		(start 144.29994 -149.763988)
		(end 144.29994 -47.999904)
		(stroke
			(width 1.524)
			(type default)
		)
		(layer "In1.Cu")
	)
	(gr_arc
		(start 144.29994 -149.763988)
		(mid 144.326787 -149.993649)
		(end 144.405604 -150.211028)
		(stroke
			(width 1.524)
			(type default)
		)
		(layer "In1.Cu")
	)
	(gr_arc
		(start 144.29994 -47.999904)
		(mid 143.800068 -47.500032)
		(end 143.299942 -47.999904)
		(stroke
			(width 1.524)
			(type default)
		)
		(layer "In1.Cu")
	)
	(gr_line
		(start 149.023578 -159.44723)
		(end 144.405604 -150.211028)
		(stroke
			(width 1.524)
			(type default)
		)
		(layer "In1.Cu")
	)
	(gr_arc
		(start 149.023578 -159.44723)
		(mid 149.392231 -159.850635)
		(end 149.917912 -159.999934)
		(stroke
			(width 1.524)
			(type default)
		)
		(layer "In1.Cu")
	)
	(gr_line
		(start 166.84244 -137.175494)
		(end 167.47109 -137.80389)
		(stroke
			(width 0.2)
			(type default)
		)
		(layer "In1.Cu")
	)
	(gr_arc
		(start 167.381428 -136.636506)
		(mid 166.84244 -136.636506)
		(end 166.84244 -137.175494)
		(stroke
			(width 0.2)
			(type default)
		)
		(layer "In1.Cu")
	)
	(gr_arc
		(start 167.47109 -137.80389)
		(mid 168.009888 -137.804081)
		(end 168.010078 -137.265156)
		(stroke
			(width 0.2)
			(type default)
		)
		(layer "In1.Cu")
	)
	(gr_line
		(start 168.010078 -137.265156)
		(end 167.381428 -136.636506)
		(stroke
			(width 0.2)
			(type default)
		)
		(layer "In1.Cu")
	)
	(gr_line
		(start 170.170602 -138.590528)
		(end 170.799252 -139.218924)
		(stroke
			(width 0.2)
			(type default)
		)
		(layer "In1.Cu")
	)
	(gr_arc
		(start 170.70959 -138.05154)
		(mid 170.170602 -138.05154)
		(end 170.170602 -138.590528)
		(stroke
			(width 0.2)
			(type default)
		)
		(layer "In1.Cu")
	)
	(gr_arc
		(start 170.799252 -139.218924)
		(mid 171.33805 -139.219115)
		(end 171.33824 -138.68019)
		(stroke
			(width 0.2)
			(type default)
		)
		(layer "In1.Cu")
	)
	(gr_rect
		(start 170.997626 -134.100316)
		(end 171.802298 -135.649716)
		(stroke
			(width 0)
			(type default)
		)
		(fill no)
		(layer "In1.Cu")
	)
	(gr_line
		(start 171.33824 -138.68019)
		(end 170.70959 -138.05154)
		(stroke
			(width 0.2)
			(type default)
		)
		(layer "In1.Cu")
	)
	(gr_rect
		(start 172.497496 -134.100316)
		(end 173.302422 -135.649716)
		(stroke
			(width 0)
			(type default)
		)
		(fill no)
		(layer "In1.Cu")
	)
	(gr_line
		(start 173.674278 -138.194542)
		(end 174.302928 -138.822938)
		(stroke
			(width 0.2)
			(type default)
		)
		(layer "In1.Cu")
	)
	(gr_rect
		(start 173.99762 -134.100316)
		(end 174.802292 -135.649716)
		(stroke
			(width 0)
			(type default)
		)
		(fill no)
		(layer "In1.Cu")
	)
	(gr_line
		(start 174.024798 -140.502386)
		(end 174.653448 -141.130782)
		(stroke
			(width 0.2)
			(type default)
		)
		(layer "In1.Cu")
	)
	(gr_arc
		(start 174.213266 -137.655554)
		(mid 173.674278 -137.655554)
		(end 173.674278 -138.194542)
		(stroke
			(width 0.2)
			(type default)
		)
		(layer "In1.Cu")
	)
	(gr_arc
		(start 174.302928 -138.822938)
		(mid 174.841726 -138.823129)
		(end 174.841916 -138.284204)
		(stroke
			(width 0.2)
			(type default)
		)
		(layer "In1.Cu")
	)
	(gr_arc
		(start 174.563786 -139.963398)
		(mid 174.024798 -139.963398)
		(end 174.024798 -140.502386)
		(stroke
			(width 0.2)
			(type default)
		)
		(layer "In1.Cu")
	)
	(gr_arc
		(start 174.653448 -141.130782)
		(mid 175.192246 -141.130973)
		(end 175.192436 -140.592048)
		(stroke
			(width 0.2)
			(type default)
		)
		(layer "In1.Cu")
	)
	(gr_line
		(start 174.841916 -138.284204)
		(end 174.213266 -137.655554)
		(stroke
			(width 0.2)
			(type default)
		)
		(layer "In1.Cu")
	)
	(gr_line
		(start 175.192436 -140.592048)
		(end 174.563786 -139.963398)
		(stroke
			(width 0.2)
			(type default)
		)
		(layer "In1.Cu")
	)
	(gr_rect
		(start 175.49749 -134.100316)
		(end 176.302416 -135.649716)
		(stroke
			(width 0)
			(type default)
		)
		(fill no)
		(layer "In1.Cu")
	)
	(gr_rect
		(start 176.997614 -134.100316)
		(end 177.802286 -135.649716)
		(stroke
			(width 0)
			(type default)
		)
		(fill no)
		(layer "In1.Cu")
	)
	(gr_line
		(start 177.391568 -140.243306)
		(end 178.020218 -140.871702)
		(stroke
			(width 0.2)
			(type default)
		)
		(layer "In1.Cu")
	)
	(gr_arc
		(start 177.930556 -139.704318)
		(mid 177.391568 -139.704318)
		(end 177.391568 -140.243306)
		(stroke
			(width 0.2)
			(type default)
		)
		(layer "In1.Cu")
	)
	(gr_arc
		(start 178.020218 -140.871702)
		(mid 178.559016 -140.871893)
		(end 178.559206 -140.332968)
		(stroke
			(width 0.2)
			(type default)
		)
		(layer "In1.Cu")
	)
	(gr_rect
		(start 178.497484 -134.100316)
		(end 179.30241 -135.649716)
		(stroke
			(width 0)
			(type default)
		)
		(fill no)
		(layer "In1.Cu")
	)
	(gr_line
		(start 178.559206 -140.332968)
		(end 177.930556 -139.704318)
		(stroke
			(width 0.2)
			(type default)
		)
		(layer "In1.Cu")
	)
	(gr_line
		(start 179.735734 -140.438378)
		(end 180.364384 -141.066774)
		(stroke
			(width 0.2)
			(type default)
		)
		(layer "In1.Cu")
	)
	(gr_rect
		(start 179.997608 -134.100316)
		(end 180.80228 -135.649716)
		(stroke
			(width 0)
			(type default)
		)
		(fill no)
		(layer "In1.Cu")
	)
	(gr_arc
		(start 180.274722 -139.89939)
		(mid 179.735734 -139.89939)
		(end 179.735734 -140.438378)
		(stroke
			(width 0.2)
			(type default)
		)
		(layer "In1.Cu")
	)
	(gr_arc
		(start 180.364384 -141.066774)
		(mid 180.903182 -141.066965)
		(end 180.903372 -140.52804)
		(stroke
			(width 0.2)
			(type default)
		)
		(layer "In1.Cu")
	)
	(gr_line
		(start 180.903372 -140.52804)
		(end 180.274722 -139.89939)
		(stroke
			(width 0.2)
			(type default)
		)
		(layer "In1.Cu")
	)
	(gr_rect
		(start 181.497478 -134.100316)
		(end 182.302404 -135.649716)
		(stroke
			(width 0)
			(type default)
		)
		(fill no)
		(layer "In1.Cu")
	)
	(gr_line
		(start 182.059072 -139.932918)
		(end 182.687722 -140.561314)
		(stroke
			(width 0.2)
			(type default)
		)
		(layer "In1.Cu")
	)
	(gr_arc
		(start 182.59806 -139.39393)
		(mid 182.059072 -139.39393)
		(end 182.059072 -139.932918)
		(stroke
			(width 0.2)
			(type default)
		)
		(layer "In1.Cu")
	)
	(gr_arc
		(start 182.687722 -140.561314)
		(mid 183.22652 -140.561505)
		(end 183.22671 -140.02258)
		(stroke
			(width 0.2)
			(type default)
		)
		(layer "In1.Cu")
	)
	(gr_rect
		(start 182.997602 -134.100316)
		(end 183.802528 -135.649716)
		(stroke
			(width 0)
			(type default)
		)
		(fill no)
		(layer "In1.Cu")
	)
	(gr_line
		(start 183.016144 -133.354826)
		(end 183.90489 -133.354826)
		(stroke
			(width 0.2)
			(type default)
		)
		(layer "In1.Cu")
	)
	(gr_arc
		(start 183.016144 -132.592826)
		(mid 182.635144 -132.973826)
		(end 183.016144 -133.354826)
		(stroke
			(width 0.2)
			(type default)
		)
		(layer "In1.Cu")
	)
	(gr_line
		(start 183.22671 -140.02258)
		(end 182.59806 -139.39393)
		(stroke
			(width 0.2)
			(type default)
		)
		(layer "In1.Cu")
	)
	(gr_arc
		(start 183.90489 -133.354826)
		(mid 184.286144 -132.973953)
		(end 183.905144 -132.592826)
		(stroke
			(width 0.2)
			(type default)
		)
		(layer "In1.Cu")
	)
	(gr_line
		(start 183.905144 -132.592826)
		(end 183.016144 -132.592826)
		(stroke
			(width 0.2)
			(type default)
		)
		(layer "In1.Cu")
	)
	(gr_line
		(start 184.815734 -139.955778)
		(end 185.444384 -140.584174)
		(stroke
			(width 0.2)
			(type default)
		)
		(layer "In1.Cu")
	)
	(gr_arc
		(start 185.354722 -139.41679)
		(mid 184.815734 -139.41679)
		(end 184.815734 -139.955778)
		(stroke
			(width 0.2)
			(type default)
		)
		(layer "In1.Cu")
	)
	(gr_arc
		(start 185.444384 -140.584174)
		(mid 185.983182 -140.584365)
		(end 185.983372 -140.04544)
		(stroke
			(width 0.2)
			(type default)
		)
		(layer "In1.Cu")
	)
	(gr_line
		(start 185.983372 -140.04544)
		(end 185.354722 -139.41679)
		(stroke
			(width 0.2)
			(type default)
		)
		(layer "In1.Cu")
	)
	(gr_line
		(start 191.821308 -139.528296)
		(end 192.449958 -140.156692)
		(stroke
			(width 0.2)
			(type default)
		)
		(layer "In1.Cu")
	)
	(gr_arc
		(start 192.360296 -138.989308)
		(mid 191.821308 -138.989308)
		(end 191.821308 -139.528296)
		(stroke
			(width 0.2)
			(type default)
		)
		(layer "In1.Cu")
	)
	(gr_arc
		(start 192.449958 -140.156692)
		(mid 192.988756 -140.156883)
		(end 192.988946 -139.617958)
		(stroke
			(width 0.2)
			(type default)
		)
		(layer "In1.Cu")
	)
	(gr_line
		(start 192.988946 -139.617958)
		(end 192.360296 -138.989308)
		(stroke
			(width 0.2)
			(type default)
		)
		(layer "In1.Cu")
	)
	(gr_line
		(start 194.869308 -140.671296)
		(end 195.497958 -141.299692)
		(stroke
			(width 0.2)
			(type default)
		)
		(layer "In1.Cu")
	)
	(gr_arc
		(start 195.408296 -140.132308)
		(mid 194.869308 -140.132308)
		(end 194.869308 -140.671296)
		(stroke
			(width 0.2)
			(type default)
		)
		(layer "In1.Cu")
	)
	(gr_arc
		(start 195.497958 -141.299692)
		(mid 196.036756 -141.299883)
		(end 196.036946 -140.760958)
		(stroke
			(width 0.2)
			(type default)
		)
		(layer "In1.Cu")
	)
	(gr_rect
		(start 195.997576 -134.100316)
		(end 196.802248 -135.649716)
		(stroke
			(width 0)
			(type default)
		)
		(fill no)
		(layer "In1.Cu")
	)
	(gr_line
		(start 196.036946 -140.760958)
		(end 195.408296 -140.132308)
		(stroke
			(width 0.2)
			(type default)
		)
		(layer "In1.Cu")
	)
	(gr_rect
		(start 197.497446 -134.100316)
		(end 198.302372 -135.649716)
		(stroke
			(width 0)
			(type default)
		)
		(fill no)
		(layer "In1.Cu")
	)
	(gr_line
		(start 197.536308 -140.925296)
		(end 198.164958 -141.553692)
		(stroke
			(width 0.2)
			(type default)
		)
		(layer "In1.Cu")
	)
	(gr_arc
		(start 198.075296 -140.386308)
		(mid 197.536308 -140.386308)
		(end 197.536308 -140.925296)
		(stroke
			(width 0.2)
			(type default)
		)
		(layer "In1.Cu")
	)
	(gr_arc
		(start 198.164958 -141.553692)
		(mid 198.703756 -141.553883)
		(end 198.703946 -141.014958)
		(stroke
			(width 0.2)
			(type default)
		)
		(layer "In1.Cu")
	)
	(gr_line
		(start 198.703946 -141.014958)
		(end 198.075296 -140.386308)
		(stroke
			(width 0.2)
			(type default)
		)
		(layer "In1.Cu")
	)
	(gr_rect
		(start 198.99757 -134.100316)
		(end 199.802242 -135.649716)
		(stroke
			(width 0)
			(type default)
		)
		(fill no)
		(layer "In1.Cu")
	)
	(gr_line
		(start 199.949308 -141.179296)
		(end 200.577958 -141.807692)
		(stroke
			(width 0.2)
			(type default)
		)
		(layer "In1.Cu")
	)
	(gr_arc
		(start 200.488296 -140.640308)
		(mid 199.949308 -140.640308)
		(end 199.949308 -141.179296)
		(stroke
			(width 0.2)
			(type default)
		)
		(layer "In1.Cu")
	)
	(gr_rect
		(start 200.49744 -134.100316)
		(end 201.302366 -135.649716)
		(stroke
			(width 0)
			(type default)
		)
		(fill no)
		(layer "In1.Cu")
	)
	(gr_arc
		(start 200.577958 -141.807692)
		(mid 201.116756 -141.807883)
		(end 201.116946 -141.268958)
		(stroke
			(width 0.2)
			(type default)
		)
		(layer "In1.Cu")
	)
	(gr_line
		(start 201.116946 -141.268958)
		(end 200.488296 -140.640308)
		(stroke
			(width 0.2)
			(type default)
		)
		(layer "In1.Cu")
	)
	(gr_rect
		(start 201.997564 -134.100316)
		(end 202.802236 -135.649716)
		(stroke
			(width 0)
			(type default)
		)
		(fill no)
		(layer "In1.Cu")
	)
	(gr_line
		(start 202.362308 -141.052296)
		(end 202.990958 -141.680692)
		(stroke
			(width 0.2)
			(type default)
		)
		(layer "In1.Cu")
	)
	(gr_arc
		(start 202.901296 -140.513308)
		(mid 202.362308 -140.513308)
		(end 202.362308 -141.052296)
		(stroke
			(width 0.2)
			(type default)
		)
		(layer "In1.Cu")
	)
	(gr_arc
		(start 202.990958 -141.680692)
		(mid 203.529756 -141.680883)
		(end 203.529946 -141.141958)
		(stroke
			(width 0.2)
			(type default)
		)
		(layer "In1.Cu")
	)
	(gr_rect
		(start 203.497434 -134.100316)
		(end 204.30236 -135.649716)
		(stroke
			(width 0)
			(type default)
		)
		(fill no)
		(layer "In1.Cu")
	)
	(gr_line
		(start 203.529946 -141.141958)
		(end 202.901296 -140.513308)
		(stroke
			(width 0.2)
			(type default)
		)
		(layer "In1.Cu")
	)
	(gr_line
		(start 204.648308 -141.179296)
		(end 205.276958 -141.807692)
		(stroke
			(width 0.2)
			(type default)
		)
		(layer "In1.Cu")
	)
	(gr_rect
		(start 204.997558 -134.100316)
		(end 205.80223 -135.649716)
		(stroke
			(width 0)
			(type default)
		)
		(fill no)
		(layer "In1.Cu")
	)
	(gr_arc
		(start 205.187296 -140.640308)
		(mid 204.648308 -140.640308)
		(end 204.648308 -141.179296)
		(stroke
			(width 0.2)
			(type default)
		)
		(layer "In1.Cu")
	)
	(gr_arc
		(start 205.276958 -141.807692)
		(mid 205.815756 -141.807883)
		(end 205.815946 -141.268958)
		(stroke
			(width 0.2)
			(type default)
		)
		(layer "In1.Cu")
	)
	(gr_line
		(start 205.815946 -141.268958)
		(end 205.187296 -140.640308)
		(stroke
			(width 0.2)
			(type default)
		)
		(layer "In1.Cu")
	)
	(gr_line
		(start 206.172308 -139.528296)
		(end 206.800958 -140.156692)
		(stroke
			(width 0.2)
			(type default)
		)
		(layer "In1.Cu")
	)
	(gr_rect
		(start 206.497428 -134.100316)
		(end 207.302354 -135.649716)
		(stroke
			(width 0)
			(type default)
		)
		(fill no)
		(layer "In1.Cu")
	)
	(gr_arc
		(start 206.711296 -138.989308)
		(mid 206.172308 -138.989308)
		(end 206.172308 -139.528296)
		(stroke
			(width 0.2)
			(type default)
		)
		(layer "In1.Cu")
	)
	(gr_arc
		(start 206.800958 -140.156692)
		(mid 207.339756 -140.156883)
		(end 207.339946 -139.617958)
		(stroke
			(width 0.2)
			(type default)
		)
		(layer "In1.Cu")
	)
	(gr_line
		(start 207.339946 -139.617958)
		(end 206.711296 -138.989308)
		(stroke
			(width 0.2)
			(type default)
		)
		(layer "In1.Cu")
	)
	(gr_rect
		(start 207.997552 -134.100316)
		(end 208.802224 -135.649716)
		(stroke
			(width 0)
			(type default)
		)
		(fill no)
		(layer "In1.Cu")
	)
	(gr_line
		(start 209.347308 -140.798296)
		(end 209.975958 -141.426692)
		(stroke
			(width 0.2)
			(type default)
		)
		(layer "In1.Cu")
	)
	(gr_arc
		(start 209.886296 -140.259308)
		(mid 209.347308 -140.259308)
		(end 209.347308 -140.798296)
		(stroke
			(width 0.2)
			(type default)
		)
		(layer "In1.Cu")
	)
	(gr_arc
		(start 209.975958 -141.426692)
		(mid 210.514756 -141.426883)
		(end 210.514946 -140.887958)
		(stroke
			(width 0.2)
			(type default)
		)
		(layer "In1.Cu")
	)
	(gr_line
		(start 210.514946 -140.887958)
		(end 209.886296 -140.259308)
		(stroke
			(width 0.2)
			(type default)
		)
		(layer "In1.Cu")
	)
	(gr_line
		(start 213.063836 -139.146534)
		(end 213.692486 -139.77493)
		(stroke
			(width 0.2)
			(type default)
		)
		(layer "In1.Cu")
	)
	(gr_arc
		(start 213.602824 -138.607546)
		(mid 213.063836 -138.607546)
		(end 213.063836 -139.146534)
		(stroke
			(width 0.2)
			(type default)
		)
		(layer "In1.Cu")
	)
	(gr_arc
		(start 213.692486 -139.77493)
		(mid 214.231284 -139.775121)
		(end 214.231474 -139.236196)
		(stroke
			(width 0.2)
			(type default)
		)
		(layer "In1.Cu")
	)
	(gr_line
		(start 214.00008 -159.999934)
		(end 149.917912 -159.999934)
		(stroke
			(width 1.524)
			(type default)
		)
		(layer "In1.Cu")
	)
	(gr_line
		(start 214.231474 -139.236196)
		(end 213.602824 -138.607546)
		(stroke
			(width 0.2)
			(type default)
		)
		(layer "In1.Cu")
	)
	(gr_line
		(start 215.000078 -193.000122)
		(end 215.000078 -160.999932)
		(stroke
			(width 1.524)
			(type default)
		)
		(layer "In1.Cu")
	)
	(gr_arc
		(start 215.000078 -193.000122)
		(mid 215.292977 -193.707222)
		(end 216.000076 -194.00012)
		(stroke
			(width 1.524)
			(type default)
		)
		(layer "In1.Cu")
	)
	(gr_arc
		(start 215.000078 -160.999932)
		(mid 214.707185 -160.292827)
		(end 214.00008 -159.999934)
		(stroke
			(width 1.524)
			(type default)
		)
		(layer "In1.Cu")
	)
	(gr_line
		(start 229.382066 -194.00012)
		(end 216.000076 -194.00012)
		(stroke
			(width 1.524)
			(type default)
		)
		(layer "In1.Cu")
	)
	(gr_arc
		(start 229.382066 -194.00012)
		(mid 229.907793 -193.850701)
		(end 230.2764 -193.447162)
		(stroke
			(width 1.524)
			(type default)
		)
		(layer "In1.Cu")
	)
	(gr_line
		(start 234.894374 -184.211214)
		(end 230.2764 -193.447162)
		(stroke
			(width 1.524)
			(type default)
		)
		(layer "In1.Cu")
	)
	(gr_arc
		(start 234.894374 -184.211214)
		(mid 234.97328 -183.993726)
		(end 235.000038 -183.76392)
		(stroke
			(width 1.524)
			(type default)
		)
		(layer "In1.Cu")
	)
	(gr_arc
		(start 235.000038 -0.999998)
		(mid 234.707147 -0.29288)
		(end 234.00004 0)
		(stroke
			(width 1.524)
			(type default)
		)
		(layer "In1.Cu")
	)
	(gr_line
		(start 235.000038 -0.999998)
		(end 235.000038 -183.76392)
		(stroke
			(width 1.524)
			(type default)
		)
		(layer "In1.Cu")
	)
	(gr_arc
		(start 18.174716 -144.500092)
		(mid 18.13829 -144.316857)
		(end 18.034508 -144.16151)
		(stroke
			(width 0.0508)
			(type default)
		)
		(layer "In2.Cu")
	)
	(gr_arc
		(start 18.734532 -144.16151)
		(mid 18.554197 -144.236193)
		(end 18.479516 -144.416526)
		(stroke
			(width 0.0508)
			(type default)
		)
		(layer "In2.Cu")
	)
	(gr_line
		(start 18.734532 -144.16151)
		(end 18.834608 -144.16151)
		(stroke
			(width 0.0508)
			(type default)
		)
		(layer "In2.Cu")
	)
	(gr_line
		(start 19.414998 -145.711672)
		(end 19.414998 -145.711926)
		(stroke
			(width 0.0508)
			(type default)
		)
		(layer "In2.Cu")
	)
	(gr_arc
		(start 21.117814 -144.823434)
		(mid 21.229941 -144.796865)
		(end 21.318474 -144.723104)
		(stroke
			(width 0.0508)
			(type default)
		)
		(layer "In2.Cu")
	)
	(gr_line
		(start 21.425154 -145.128234)
		(end 21.917914 -145.128234)
		(stroke
			(width 0.0508)
			(type default)
		)
		(layer "In2.Cu")
	)
	(gr_arc
		(start 21.519134 -144.622774)
		(mid 21.406977 -144.649298)
		(end 21.318474 -144.723104)
		(stroke
			(width 0.0508)
			(type default)
		)
		(layer "In2.Cu")
	)
	(gr_line
		(start 21.519134 -144.622774)
		(end 21.823934 -144.622774)
		(stroke
			(width 0.0508)
			(type default)
		)
		(layer "In2.Cu")
	)
	(gr_arc
		(start 22.024594 -144.723104)
		(mid 21.936068 -144.649344)
		(end 21.823934 -144.622774)
		(stroke
			(width 0.0508)
			(type default)
		)
		(layer "In2.Cu")
	)
	(gr_arc
		(start 22.024594 -144.723104)
		(mid 22.113107 -144.79689)
		(end 22.225254 -144.823434)
		(stroke
			(width 0.0508)
			(type default)
		)
		(layer "In2.Cu")
	)
	(gr_line
		(start 22.0345 -148.961602)
		(end 22.22246 -148.773642)
		(stroke
			(width 0.0508)
			(type default)
		)
		(layer "In2.Cu")
	)
	(gr_line
		(start 22.0345 -148.161502)
		(end 22.095968 -148.222716)
		(stroke
			(width 0.0508)
			(type default)
		)
		(layer "In2.Cu")
	)
	(gr_line
		(start 22.0345 -141.76121)
		(end 22.253194 -141.542516)
		(stroke
			(width 0.0508)
			(type default)
		)
		(layer "In2.Cu")
	)
	(gr_line
		(start 22.0345 -140.96111)
		(end 22.217126 -141.143736)
		(stroke
			(width 0.0508)
			(type default)
		)
		(layer "In2.Cu")
	)
	(gr_arc
		(start 22.095968 -148.222716)
		(mid 22.261209 -148.333186)
		(end 22.45614 -148.372068)
		(stroke
			(width 0.0508)
			(type default)
		)
		(layer "In2.Cu")
	)
	(gr_arc
		(start 22.45614 -148.676868)
		(mid 22.329679 -148.702016)
		(end 22.22246 -148.773642)
		(stroke
			(width 0.0508)
			(type default)
		)
		(layer "In2.Cu")
	)
	(gr_arc
		(start 22.530054 -144.823434)
		(mid 22.64217 -144.796851)
		(end 22.730714 -144.723104)
		(stroke
			(width 0.0508)
			(type default)
		)
		(layer "In2.Cu")
	)
	(gr_line
		(start 22.837394 -145.128234)
		(end 23.330154 -145.128234)
		(stroke
			(width 0.0508)
			(type default)
		)
		(layer "In2.Cu")
	)
	(gr_arc
		(start 22.931374 -144.622774)
		(mid 22.819217 -144.649298)
		(end 22.730714 -144.723104)
		(stroke
			(width 0.0508)
			(type default)
		)
		(layer "In2.Cu")
	)
	(gr_line
		(start 22.931374 -144.622774)
		(end 23.236174 -144.622774)
		(stroke
			(width 0.0508)
			(type default)
		)
		(layer "In2.Cu")
	)
	(gr_arc
		(start 23.436834 -144.723104)
		(mid 23.348308 -144.649344)
		(end 23.236174 -144.622774)
		(stroke
			(width 0.0508)
			(type default)
		)
		(layer "In2.Cu")
	)
	(gr_arc
		(start 23.436834 -144.723104)
		(mid 23.525343 -144.796911)
		(end 23.637494 -144.823434)
		(stroke
			(width 0.0508)
			(type default)
		)
		(layer "In2.Cu")
	)
	(gr_line
		(start 25.769316 -150.793958)
		(end 25.76957 -150.794212)
		(stroke
			(width 0.0508)
			(type default)
		)
		(layer "In2.Cu")
	)
	(gr_arc
		(start 25.769316 -150.793958)
		(mid 25.785413 -150.758016)
		(end 25.796748 -150.720298)
		(stroke
			(width 0.0508)
			(type default)
		)
		(layer "In2.Cu")
	)
	(gr_line
		(start 26.51506 -150.6093)
		(end 26.515314 -150.6093)
		(stroke
			(width 0.0508)
			(type default)
		)
		(layer "In2.Cu")
	)
	(gr_arc
		(start 27.862784 -150.67661)
		(mid 27.872741 -150.656732)
		(end 27.881326 -150.636224)
		(stroke
			(width 0.0508)
			(type default)
		)
		(layer "In2.Cu")
	)
	(gr_line
		(start 28.607512 -150.682198)
		(end 28.607766 -150.682198)
		(stroke
			(width 0.0508)
			(type default)
		)
		(layer "In2.Cu")
	)
	(gr_arc
		(start 32.092138 -144.667224)
		(mid 32.348973 -144.560839)
		(end 32.455358 -144.304004)
		(stroke
			(width 0.0508)
			(type default)
		)
		(layer "In2.Cu")
	)
	(gr_arc
		(start 32.760158 -144.273524)
		(mid 32.881429 -144.566273)
		(end 33.174178 -144.687544)
		(stroke
			(width 0.0508)
			(type default)
		)
		(layer "In2.Cu")
	)
	(gr_arc
		(start 36.44138 -149.456902)
		(mid 36.679463 -149.366917)
		(end 36.798504 -149.141942)
		(stroke
			(width 0.0508)
			(type default)
		)
		(layer "In2.Cu")
	)
	(gr_arc
		(start 36.798504 -150.076916)
		(mid 36.679392 -149.851755)
		(end 36.441126 -149.761702)
		(stroke
			(width 0.0508)
			(type default)
		)
		(layer "In2.Cu")
	)
	(gr_arc
		(start 37.221668 -146.559524)
		(mid 37.513144 -146.466179)
		(end 37.695886 -146.220688)
		(stroke
			(width 0.0508)
			(type default)
		)
		(layer "In2.Cu")
	)
	(gr_arc
		(start 37.695886 -147.155662)
		(mid 37.499952 -146.942973)
		(end 37.221668 -146.864324)
		(stroke
			(width 0.0508)
			(type default)
		)
		(layer "In2.Cu")
	)
	(gr_line
		(start 86.590378 -159.101282)
		(end 86.80577 -159.316674)
		(stroke
			(width 0.06985)
			(type default)
		)
		(layer "In2.Cu")
	)
	(gr_line
		(start 86.590378 -158.63062)
		(end 86.80577 -158.415228)
		(stroke
			(width 0.06985)
			(type default)
		)
		(layer "In2.Cu")
	)
	(gr_line
		(start 87.16645 -134.334758)
		(end 87.16645 -134.418324)
		(stroke
			(width 0.06985)
			(type default)
		)
		(layer "In2.Cu")
	)
	(gr_line
		(start 87.386922 -134.004558)
		(end 87.386922 -134.088124)
		(stroke
			(width 0.06985)
			(type default)
		)
		(layer "In2.Cu")
	)
	(gr_line
		(start 88.297004 -114.757962)
		(end 88.297004 -114.862102)
		(stroke
			(width 0.06985)
			(type default)
		)
		(layer "In2.Cu")
	)
	(gr_line
		(start 88.53805 -115.088162)
		(end 88.53805 -115.192302)
		(stroke
			(width 0.06985)
			(type default)
		)
		(layer "In2.Cu")
	)
	(gr_line
		(start 89.41435 -42.549572)
		(end 89.41435 -42.658792)
		(stroke
			(width 0.06985)
			(type default)
		)
		(layer "In2.Cu")
	)
	(gr_line
		(start 89.41435 -41.355772)
		(end 89.41435 -41.464992)
		(stroke
			(width 0.06985)
			(type default)
		)
		(layer "In2.Cu")
	)
	(gr_line
		(start 89.41435 -40.161972)
		(end 89.41435 -40.271192)
		(stroke
			(width 0.06985)
			(type default)
		)
		(layer "In2.Cu")
	)
	(gr_line
		(start 89.74709 -42.988992)
		(end 89.92235 -42.813732)
		(stroke
			(width 0.06985)
			(type default)
		)
		(layer "In2.Cu")
	)
	(gr_line
		(start 89.74709 -42.219372)
		(end 89.92235 -42.394632)
		(stroke
			(width 0.06985)
			(type default)
		)
		(layer "In2.Cu")
	)
	(gr_line
		(start 89.74709 -41.795192)
		(end 89.92235 -41.619932)
		(stroke
			(width 0.06985)
			(type default)
		)
		(layer "In2.Cu")
	)
	(gr_line
		(start 89.74709 -41.025572)
		(end 89.92235 -41.200832)
		(stroke
			(width 0.06985)
			(type default)
		)
		(layer "In2.Cu")
	)
	(gr_line
		(start 89.74709 -40.601392)
		(end 89.92235 -40.426132)
		(stroke
			(width 0.06985)
			(type default)
		)
		(layer "In2.Cu")
	)
	(gr_line
		(start 89.74709 -39.831772)
		(end 89.92235 -40.007032)
		(stroke
			(width 0.06985)
			(type default)
		)
		(layer "In2.Cu")
	)
	(gr_line
		(start 89.89695 -93.726)
		(end 89.89695 -93.766894)
		(stroke
			(width 0.06985)
			(type default)
		)
		(layer "In2.Cu")
	)
	(gr_line
		(start 89.92235 -42.394632)
		(end 89.92235 -42.813732)
		(stroke
			(width 0.06985)
			(type default)
		)
		(layer "In2.Cu")
	)
	(gr_line
		(start 89.92235 -41.200832)
		(end 89.92235 -41.619932)
		(stroke
			(width 0.06985)
			(type default)
		)
		(layer "In2.Cu")
	)
	(gr_line
		(start 89.92235 -40.007032)
		(end 89.92235 -40.426132)
		(stroke
			(width 0.06985)
			(type default)
		)
		(layer "In2.Cu")
	)
	(gr_line
		(start 90.07475 -94.0562)
		(end 90.07475 -94.097094)
		(stroke
			(width 0.06985)
			(type default)
		)
		(layer "In2.Cu")
	)
	(gr_line
		(start 98.509582 -21.06422)
		(end 98.717354 -21.271992)
		(stroke
			(width 0.06985)
			(type default)
		)
		(layer "In2.Cu")
	)
	(gr_line
		(start 99.050094 -21.425154)
		(end 99.411028 -21.06422)
		(stroke
			(width 0.06985)
			(type default)
		)
		(layer "In2.Cu")
	)
	(gr_line
		(start 0 -183.76392)
		(end 0 -0.999998)
		(stroke
			(width 2.54)
			(type default)
		)
		(layer "In3.Cu")
	)
	(gr_arc
		(start 0 -183.76392)
		(mid 0.026807 -183.993715)
		(end 0.105664 -184.211214)
		(stroke
			(width 2.54)
			(type default)
		)
		(layer "In3.Cu")
	)
	(gr_arc
		(start 0.999998 0)
		(mid 0.292893 -0.292893)
		(end 0 -0.999998)
		(stroke
			(width 2.54)
			(type default)
		)
		(layer "In3.Cu")
	)
	(gr_line
		(start 0.999998 0)
		(end 29.53004 0)
		(stroke
			(width 2.54)
			(type default)
		)
		(layer "In3.Cu")
	)
	(gr_line
		(start 2.6416 -172.0596)
		(end 16.002 -185.42)
		(stroke
			(width 0.381)
			(type default)
		)
		(layer "In3.Cu")
	)
	(gr_line
		(start 2.6416 -118.595902)
		(end 2.6416 -172.0596)
		(stroke
			(width 0.381)
			(type default)
		)
		(layer "In3.Cu")
	)
	(gr_circle
		(center 2.641854 -118.595902)
		(end 2.642108 -118.595902)
		(stroke
			(width 0.381)
			(type default)
		)
		(fill no)
		(layer "In3.Cu")
	)
	(gr_line
		(start 4.723638 -193.447162)
		(end 0.105664 -184.211214)
		(stroke
			(width 2.54)
			(type default)
		)
		(layer "In3.Cu")
	)
	(gr_arc
		(start 4.723638 -193.447162)
		(mid 5.092281 -193.850645)
		(end 5.617972 -194.00012)
		(stroke
			(width 2.54)
			(type default)
		)
		(layer "In3.Cu")
	)
	(gr_line
		(start 11.557 -169.799)
		(end 11.557 -154.037538)
		(stroke
			(width 0.381)
			(type default)
		)
		(layer "In3.Cu")
	)
	(gr_line
		(start 11.557 -161.651442)
		(end 12.156186 -161.052256)
		(stroke
			(width 0.381)
			(type default)
		)
		(layer "In3.Cu")
	)
	(gr_line
		(start 11.557 -154.037538)
		(end 11.557254 -154.037284)
		(stroke
			(width 0.381)
			(type default)
		)
		(layer "In3.Cu")
	)
	(gr_line
		(start 11.557 -154.03703)
		(end 11.557 -133.026658)
		(stroke
			(width 0.381)
			(type default)
		)
		(layer "In3.Cu")
	)
	(gr_line
		(start 11.557 -133.026658)
		(end 11.557 -131.999482)
		(stroke
			(width 0.381)
			(type default)
		)
		(layer "In3.Cu")
	)
	(gr_line
		(start 11.557 -131.999482)
		(end 11.557 -119.507)
		(stroke
			(width 0.381)
			(type default)
		)
		(layer "In3.Cu")
	)
	(gr_line
		(start 11.557 -131.999482)
		(end 11.947652 -131.60883)
		(stroke
			(width 0.381)
			(type default)
		)
		(layer "In3.Cu")
	)
	(gr_line
		(start 11.557 -119.507)
		(end 16.002 -115.062)
		(stroke
			(width 0.381)
			(type default)
		)
		(layer "In3.Cu")
	)
	(gr_circle
		(center 11.557254 -161.651442)
		(end 11.557508 -161.651442)
		(stroke
			(width 0.381)
			(type default)
		)
		(fill no)
		(layer "In3.Cu")
	)
	(gr_circle
		(center 11.557254 -160.452562)
		(end 11.557508 -160.452562)
		(stroke
			(width 0.381)
			(type default)
		)
		(fill no)
		(layer "In3.Cu")
	)
	(gr_line
		(start 11.557254 -154.037284)
		(end 11.557 -154.03703)
		(stroke
			(width 0.381)
			(type default)
		)
		(layer "In3.Cu")
	)
	(gr_circle
		(center 11.557254 -133.026658)
		(end 11.557508 -133.026658)
		(stroke
			(width 0.381)
			(type default)
		)
		(fill no)
		(layer "In3.Cu")
	)
	(gr_line
		(start 11.827764 -131.60883)
		(end 11.601958 -131.383024)
		(stroke
			(width 0.381)
			(type default)
		)
		(layer "In3.Cu")
	)
	(gr_line
		(start 11.947652 -131.60883)
		(end 11.827764 -131.60883)
		(stroke
			(width 0.381)
			(type default)
		)
		(layer "In3.Cu")
	)
	(gr_line
		(start 11.947652 -131.60883)
		(end 25.14473 -131.60883)
		(stroke
			(width 0.381)
			(type default)
		)
		(layer "In3.Cu")
	)
	(gr_circle
		(center 12.119102 -109.118654)
		(end 12.119356 -109.118654)
		(stroke
			(width 0.381)
			(type default)
		)
		(fill no)
		(layer "In3.Cu")
	)
	(gr_line
		(start 12.119102 -109.1184)
		(end 2.6416 -118.595902)
		(stroke
			(width 0.381)
			(type default)
		)
		(layer "In3.Cu")
	)
	(gr_arc
		(start 12.156186 -161.052256)
		(mid 12.15644 -161.052002)
		(end 12.156186 -161.051748)
		(stroke
			(width 0.381)
			(type default)
		)
		(layer "In3.Cu")
	)
	(gr_line
		(start 12.156186 -161.051748)
		(end 11.557 -160.452562)
		(stroke
			(width 0.381)
			(type default)
		)
		(layer "In3.Cu")
	)
	(gr_circle
		(center 14.249908 -6.249924)
		(end 15.141448 -6.249924)
		(stroke
			(width 0.2)
			(type default)
		)
		(fill no)
		(layer "In3.Cu")
	)
	(gr_line
		(start 15.875 -174.117)
		(end 16.129 -174.371)
		(stroke
			(width 0.381)
			(type default)
		)
		(layer "In3.Cu")
	)
	(gr_line
		(start 15.875 -171.958)
		(end 15.875 -174.117)
		(stroke
			(width 0.381)
			(type default)
		)
		(layer "In3.Cu")
	)
	(gr_line
		(start 16.002 -185.42)
		(end 24.257 -185.42)
		(stroke
			(width 0.381)
			(type default)
		)
		(layer "In3.Cu")
	)
	(gr_line
		(start 16.002 -115.062)
		(end 19.979386 -115.062)
		(stroke
			(width 0.381)
			(type default)
		)
		(layer "In3.Cu")
	)
	(gr_line
		(start 16.637 -171.196)
		(end 15.875 -171.958)
		(stroke
			(width 0.381)
			(type default)
		)
		(layer "In3.Cu")
	)
	(gr_line
		(start 18.065242 -176.307242)
		(end 11.557 -169.799)
		(stroke
			(width 0.381)
			(type default)
		)
		(layer "In3.Cu")
	)
	(gr_circle
		(center 18.065242 -176.306988)
		(end 18.065496 -176.306988)
		(stroke
			(width 0.381)
			(type default)
		)
		(fill no)
		(layer "In3.Cu")
	)
	(gr_arc
		(start 19.997166 -115.069366)
		(mid 19.989016 -115.0639)
		(end 19.979386 -115.062)
		(stroke
			(width 0.381)
			(type default)
		)
		(layer "In3.Cu")
	)
	(gr_line
		(start 19.997166 -115.069366)
		(end 22.1234 -117.1956)
		(stroke
			(width 0.381)
			(type default)
		)
		(layer "In3.Cu")
	)
	(gr_line
		(start 21.440648 -161.071306)
		(end 11.686794 -161.071306)
		(stroke
			(width 0.381)
			(type default)
		)
		(layer "In3.Cu")
	)
	(gr_line
		(start 22.1234 -117.1956)
		(end 75.819 -117.1956)
		(stroke
			(width 0.381)
			(type default)
		)
		(layer "In3.Cu")
	)
	(gr_line
		(start 22.86 -171.196)
		(end 16.637 -171.196)
		(stroke
			(width 0.381)
			(type default)
		)
		(layer "In3.Cu")
	)
	(gr_circle
		(center 23.145242 -176.307496)
		(end 23.145496 -176.307496)
		(stroke
			(width 0.381)
			(type default)
		)
		(fill no)
		(layer "In3.Cu")
	)
	(gr_line
		(start 23.145242 -176.307242)
		(end 18.065242 -176.307242)
		(stroke
			(width 0.381)
			(type default)
		)
		(layer "In3.Cu")
	)
	(gr_line
		(start 24.257 -188.3664)
		(end 24.257 -185.42)
		(stroke
			(width 0.381)
			(type default)
		)
		(layer "In3.Cu")
	)
	(gr_line
		(start 24.257 -185.42)
		(end 24.892 -184.785)
		(stroke
			(width 0.381)
			(type default)
		)
		(layer "In3.Cu")
	)
	(gr_line
		(start 24.798528 -173.134528)
		(end 22.86 -171.196)
		(stroke
			(width 0.381)
			(type default)
		)
		(layer "In3.Cu")
	)
	(gr_line
		(start 24.892 -184.785)
		(end 24.892 -178.054)
		(stroke
			(width 0.381)
			(type default)
		)
		(layer "In3.Cu")
	)
	(gr_line
		(start 24.892 -178.054)
		(end 23.145242 -176.307242)
		(stroke
			(width 0.381)
			(type default)
		)
		(layer "In3.Cu")
	)
	(gr_line
		(start 25.14473 -131.60883)
		(end 25.721818 -132.185918)
		(stroke
			(width 0.381)
			(type default)
		)
		(layer "In3.Cu")
	)
	(gr_line
		(start 25.261062 -157.250892)
		(end 21.440648 -161.071306)
		(stroke
			(width 0.381)
			(type default)
		)
		(layer "In3.Cu")
	)
	(gr_line
		(start 25.261062 -154.516582)
		(end 25.261062 -157.250892)
		(stroke
			(width 0.381)
			(type default)
		)
		(layer "In3.Cu")
	)
	(gr_line
		(start 25.721818 -133.514592)
		(end 27.533092 -135.325866)
		(stroke
			(width 0.381)
			(type default)
		)
		(layer "In3.Cu")
	)
	(gr_line
		(start 25.721818 -132.185918)
		(end 25.721818 -133.514592)
		(stroke
			(width 0.381)
			(type default)
		)
		(layer "In3.Cu")
	)
	(gr_line
		(start 25.74036 -154.037284)
		(end 25.261062 -154.516582)
		(stroke
			(width 0.381)
			(type default)
		)
		(layer "In3.Cu")
	)
	(gr_circle
		(center 26.249884 -8.750046)
		(end 27.141424 -8.750046)
		(stroke
			(width 0.2)
			(type default)
		)
		(fill no)
		(layer "In3.Cu")
	)
	(gr_line
		(start 27.533092 -135.325866)
		(end 35.219386 -135.325866)
		(stroke
			(width 0.381)
			(type default)
		)
		(layer "In3.Cu")
	)
	(gr_line
		(start 27.5844 -191.6938)
		(end 24.257 -188.3664)
		(stroke
			(width 0.381)
			(type default)
		)
		(layer "In3.Cu")
	)
	(gr_arc
		(start 30.530038 -109.050074)
		(mid 30.822931 -109.757179)
		(end 31.530036 -110.050072)
		(stroke
			(width 2.54)
			(type default)
		)
		(layer "In3.Cu")
	)
	(gr_arc
		(start 30.530038 -0.999998)
		(mid 30.237147 -0.29288)
		(end 29.53004 0)
		(stroke
			(width 2.54)
			(type default)
		)
		(layer "In3.Cu")
	)
	(gr_line
		(start 30.530038 -0.999998)
		(end 30.530038 -109.050074)
		(stroke
			(width 2.54)
			(type default)
		)
		(layer "In3.Cu")
	)
	(gr_line
		(start 31.148528 -173.134528)
		(end 24.798528 -173.134528)
		(stroke
			(width 0.381)
			(type default)
		)
		(layer "In3.Cu")
	)
	(gr_line
		(start 31.530036 -110.050072)
		(end 72.030082 -110.050072)
		(stroke
			(width 2.54)
			(type default)
		)
		(layer "In3.Cu")
	)
	(gr_circle
		(center 31.697676 -154.037538)
		(end 31.69793 -154.037538)
		(stroke
			(width 0.381)
			(type default)
		)
		(fill no)
		(layer "In3.Cu")
	)
	(gr_line
		(start 31.697676 -154.037284)
		(end 25.74036 -154.037284)
		(stroke
			(width 0.381)
			(type default)
		)
		(layer "In3.Cu")
	)
	(gr_line
		(start 32.16783 -154.507438)
		(end 31.697676 -154.037284)
		(stroke
			(width 0.381)
			(type default)
		)
		(layer "In3.Cu")
	)
	(gr_circle
		(center 32.16783 -154.507184)
		(end 32.168084 -154.507184)
		(stroke
			(width 0.381)
			(type default)
		)
		(fill no)
		(layer "In3.Cu")
	)
	(gr_line
		(start 35.219386 -135.325866)
		(end 40.454072 -140.560552)
		(stroke
			(width 0.381)
			(type default)
		)
		(layer "In3.Cu")
	)
	(gr_line
		(start 36.576762 -154.507438)
		(end 32.16783 -154.507438)
		(stroke
			(width 0.381)
			(type default)
		)
		(layer "In3.Cu")
	)
	(gr_circle
		(center 36.576762 -154.507184)
		(end 36.577016 -154.507184)
		(stroke
			(width 0.381)
			(type default)
		)
		(fill no)
		(layer "In3.Cu")
	)
	(gr_line
		(start 37.4396 -109.1184)
		(end 12.119102 -109.1184)
		(stroke
			(width 0.381)
			(type default)
		)
		(layer "In3.Cu")
	)
	(gr_line
		(start 37.53358 -179.51958)
		(end 31.148528 -173.134528)
		(stroke
			(width 0.381)
			(type default)
		)
		(layer "In3.Cu")
	)
	(gr_line
		(start 38.827202 -179.51958)
		(end 37.53358 -179.51958)
		(stroke
			(width 0.381)
			(type default)
		)
		(layer "In3.Cu")
	)
	(gr_line
		(start 39.398194 -151.686006)
		(end 36.576762 -154.507438)
		(stroke
			(width 0.381)
			(type default)
		)
		(layer "In3.Cu")
	)
	(gr_line
		(start 39.398194 -151.032972)
		(end 39.398194 -151.686006)
		(stroke
			(width 0.381)
			(type default)
		)
		(layer "In3.Cu")
	)
	(gr_line
		(start 39.838122 -181.824122)
		(end 39.838122 -180.5305)
		(stroke
			(width 0.381)
			(type default)
		)
		(layer "In3.Cu")
	)
	(gr_line
		(start 39.838122 -180.5305)
		(end 38.827202 -179.51958)
		(stroke
			(width 0.381)
			(type default)
		)
		(layer "In3.Cu")
	)
	(gr_line
		(start 40.198548 -150.232618)
		(end 39.398194 -151.032972)
		(stroke
			(width 0.381)
			(type default)
		)
		(layer "In3.Cu")
	)
	(gr_line
		(start 40.454072 -140.560552)
		(end 42.978324 -140.560552)
		(stroke
			(width 0.381)
			(type default)
		)
		(layer "In3.Cu")
	)
	(gr_line
		(start 40.568626 -150.232618)
		(end 40.198548 -150.232618)
		(stroke
			(width 0.381)
			(type default)
		)
		(layer "In3.Cu")
	)
	(gr_line
		(start 40.84066 -149.960584)
		(end 40.568626 -150.232618)
		(stroke
			(width 0.381)
			(type default)
		)
		(layer "In3.Cu")
	)
	(gr_line
		(start 40.84066 -149.715728)
		(end 40.84066 -149.960584)
		(stroke
			(width 0.381)
			(type default)
		)
		(layer "In3.Cu")
	)
	(gr_line
		(start 41.053004 -149.503384)
		(end 40.84066 -149.715728)
		(stroke
			(width 0.381)
			(type default)
		)
		(layer "In3.Cu")
	)
	(gr_line
		(start 42.10304 -149.503384)
		(end 41.053004 -149.503384)
		(stroke
			(width 0.381)
			(type default)
		)
		(layer "In3.Cu")
	)
	(gr_line
		(start 42.495216 -149.111208)
		(end 42.10304 -149.503384)
		(stroke
			(width 0.381)
			(type default)
		)
		(layer "In3.Cu")
	)
	(gr_line
		(start 42.495216 -148.099018)
		(end 42.495216 -149.111208)
		(stroke
			(width 0.381)
			(type default)
		)
		(layer "In3.Cu")
	)
	(gr_circle
		(center 42.49547 -148.099018)
		(end 42.495724 -148.099018)
		(stroke
			(width 0.381)
			(type default)
		)
		(fill no)
		(layer "In3.Cu")
	)
	(gr_circle
		(center 42.766234 -147.828254)
		(end 42.766488 -147.828254)
		(stroke
			(width 0.381)
			(type default)
		)
		(fill no)
		(layer "In3.Cu")
	)
	(gr_line
		(start 42.766234 -147.828)
		(end 42.495216 -148.099018)
		(stroke
			(width 0.381)
			(type default)
		)
		(layer "In3.Cu")
	)
	(gr_circle
		(center 42.978324 -140.560806)
		(end 42.978578 -140.560806)
		(stroke
			(width 0.381)
			(type default)
		)
		(fill no)
		(layer "In3.Cu")
	)
	(gr_line
		(start 42.978324 -140.560552)
		(end 43.26255 -140.844778)
		(stroke
			(width 0.381)
			(type default)
		)
		(layer "In3.Cu")
	)
	(gr_circle
		(center 43.262296 -140.844778)
		(end 43.26255 -140.844778)
		(stroke
			(width 0.381)
			(type default)
		)
		(fill no)
		(layer "In3.Cu")
	)
	(gr_line
		(start 43.26255 -141.17955)
		(end 44.45 -142.367)
		(stroke
			(width 0.381)
			(type default)
		)
		(layer "In3.Cu")
	)
	(gr_line
		(start 43.26255 -140.844778)
		(end 43.26255 -141.17955)
		(stroke
			(width 0.381)
			(type default)
		)
		(layer "In3.Cu")
	)
	(gr_circle
		(center 43.262804 -141.17955)
		(end 43.263058 -141.17955)
		(stroke
			(width 0.381)
			(type default)
		)
		(fill no)
		(layer "In3.Cu")
	)
	(gr_line
		(start 44.45 -147.828)
		(end 42.766234 -147.828)
		(stroke
			(width 0.381)
			(type default)
		)
		(layer "In3.Cu")
	)
	(gr_circle
		(center 44.45 -147.827746)
		(end 44.450254 -147.827746)
		(stroke
			(width 0.381)
			(type default)
		)
		(fill no)
		(layer "In3.Cu")
	)
	(gr_line
		(start 44.45 -144.272)
		(end 44.958 -144.78)
		(stroke
			(width 0.381)
			(type default)
		)
		(layer "In3.Cu")
	)
	(gr_line
		(start 44.45 -142.367)
		(end 44.45 -144.272)
		(stroke
			(width 0.381)
			(type default)
		)
		(layer "In3.Cu")
	)
	(gr_line
		(start 44.958 -147.32)
		(end 44.45 -147.828)
		(stroke
			(width 0.381)
			(type default)
		)
		(layer "In3.Cu")
	)
	(gr_line
		(start 44.958 -144.78)
		(end 44.958 -147.32)
		(stroke
			(width 0.381)
			(type default)
		)
		(layer "In3.Cu")
	)
	(gr_line
		(start 46.355 -188.341)
		(end 39.838122 -181.824122)
		(stroke
			(width 0.381)
			(type default)
		)
		(layer "In3.Cu")
	)
	(gr_arc
		(start 72.030082 -110.050072)
		(mid 72.737187 -109.757179)
		(end 73.03008 -109.050074)
		(stroke
			(width 2.54)
			(type default)
		)
		(layer "In3.Cu")
	)
	(gr_line
		(start 73.03008 -109.050074)
		(end 73.03008 -0.999998)
		(stroke
			(width 2.54)
			(type default)
		)
		(layer "In3.Cu")
	)
	(gr_line
		(start 73.9902 -2.794)
		(end 174.97552 -2.794)
		(stroke
			(width 0.381)
			(type default)
		)
		(layer "In3.Cu")
	)
	(gr_arc
		(start 74.030078 0)
		(mid 73.322986 -0.2929)
		(end 73.03008 -0.999998)
		(stroke
			(width 2.54)
			(type default)
		)
		(layer "In3.Cu")
	)
	(gr_line
		(start 74.030078 0)
		(end 234.00004 0)
		(stroke
			(width 2.54)
			(type default)
		)
		(layer "In3.Cu")
	)
	(gr_line
		(start 74.295 -3.175)
		(end 74.676 -2.794)
		(stroke
			(width 0.381)
			(type default)
		)
		(layer "In3.Cu")
	)
	(gr_line
		(start 74.422 -188.341)
		(end 46.355 -188.341)
		(stroke
			(width 0.381)
			(type default)
		)
		(layer "In3.Cu")
	)
	(gr_line
		(start 74.676 -2.794)
		(end 74.2696 -2.3876)
		(stroke
			(width 0.381)
			(type default)
		)
		(layer "In3.Cu")
	)
	(gr_line
		(start 75.184 -187.579)
		(end 74.422 -188.341)
		(stroke
			(width 0.381)
			(type default)
		)
		(layer "In3.Cu")
	)
	(gr_line
		(start 75.184 -186.309)
		(end 75.184 -187.579)
		(stroke
			(width 0.381)
			(type default)
		)
		(layer "In3.Cu")
	)
	(gr_line
		(start 75.565 -185.928)
		(end 75.184 -186.309)
		(stroke
			(width 0.381)
			(type default)
		)
		(layer "In3.Cu")
	)
	(gr_line
		(start 75.819 -168.021)
		(end 76.2 -168.402)
		(stroke
			(width 0.381)
			(type default)
		)
		(layer "In3.Cu")
	)
	(gr_line
		(start 75.819 -165.1)
		(end 75.819 -168.021)
		(stroke
			(width 0.381)
			(type default)
		)
		(layer "In3.Cu")
	)
	(gr_line
		(start 75.819 -117.1956)
		(end 77.945234 -115.069366)
		(stroke
			(width 0.381)
			(type default)
		)
		(layer "In3.Cu")
	)
	(gr_line
		(start 76.2 -168.402)
		(end 77.724 -168.402)
		(stroke
			(width 0.381)
			(type default)
		)
		(layer "In3.Cu")
	)
	(gr_line
		(start 76.581 -164.338)
		(end 75.819 -165.1)
		(stroke
			(width 0.381)
			(type default)
		)
		(layer "In3.Cu")
	)
	(gr_arc
		(start 76.902818 -93.800168)
		(mid 77.283818 -94.181168)
		(end 77.664818 -93.800168)
		(stroke
			(width 0.2)
			(type default)
		)
		(layer "In3.Cu")
	)
	(gr_line
		(start 76.902818 -92.911168)
		(end 76.902818 -93.800168)
		(stroke
			(width 0.2)
			(type default)
		)
		(layer "In3.Cu")
	)
	(gr_arc
		(start 76.902818 -87.399368)
		(mid 77.283818 -87.780368)
		(end 77.664818 -87.399368)
		(stroke
			(width 0.2)
			(type default)
		)
		(layer "In3.Cu")
	)
	(gr_line
		(start 76.902818 -86.510368)
		(end 76.902818 -87.399368)
		(stroke
			(width 0.2)
			(type default)
		)
		(layer "In3.Cu")
	)
	(gr_arc
		(start 76.902818 -80.998568)
		(mid 77.283818 -81.379568)
		(end 77.664818 -80.998568)
		(stroke
			(width 0.2)
			(type default)
		)
		(layer "In3.Cu")
	)
	(gr_line
		(start 76.902818 -80.109568)
		(end 76.902818 -80.998568)
		(stroke
			(width 0.2)
			(type default)
		)
		(layer "In3.Cu")
	)
	(gr_arc
		(start 76.902818 -74.597768)
		(mid 77.283818 -74.978768)
		(end 77.664818 -74.597768)
		(stroke
			(width 0.2)
			(type default)
		)
		(layer "In3.Cu")
	)
	(gr_line
		(start 76.902818 -73.708768)
		(end 76.902818 -74.597768)
		(stroke
			(width 0.2)
			(type default)
		)
		(layer "In3.Cu")
	)
	(gr_arc
		(start 76.974192 -68.201032)
		(mid 77.355192 -68.582032)
		(end 77.736192 -68.201032)
		(stroke
			(width 0.2)
			(type default)
		)
		(layer "In3.Cu")
	)
	(gr_line
		(start 76.974192 -67.312032)
		(end 76.974192 -68.201032)
		(stroke
			(width 0.2)
			(type default)
		)
		(layer "In3.Cu")
	)
	(gr_line
		(start 77.3684 -2.794)
		(end 73.9902 -2.794)
		(stroke
			(width 0.381)
			(type default)
		)
		(layer "In3.Cu")
	)
	(gr_line
		(start 77.664818 -93.800168)
		(end 77.664818 -92.911422)
		(stroke
			(width 0.2)
			(type default)
		)
		(layer "In3.Cu")
	)
	(gr_arc
		(start 77.664818 -92.911422)
		(mid 77.283945 -92.530168)
		(end 76.902818 -92.911168)
		(stroke
			(width 0.2)
			(type default)
		)
		(layer "In3.Cu")
	)
	(gr_line
		(start 77.664818 -87.399368)
		(end 77.664818 -86.510622)
		(stroke
			(width 0.2)
			(type default)
		)
		(layer "In3.Cu")
	)
	(gr_arc
		(start 77.664818 -86.510622)
		(mid 77.283945 -86.129368)
		(end 76.902818 -86.510368)
		(stroke
			(width 0.2)
			(type default)
		)
		(layer "In3.Cu")
	)
	(gr_line
		(start 77.664818 -80.998568)
		(end 77.664818 -80.109822)
		(stroke
			(width 0.2)
			(type default)
		)
		(layer "In3.Cu")
	)
	(gr_arc
		(start 77.664818 -80.109822)
		(mid 77.283945 -79.728568)
		(end 76.902818 -80.109568)
		(stroke
			(width 0.2)
			(type default)
		)
		(layer "In3.Cu")
	)
	(gr_line
		(start 77.664818 -74.597768)
		(end 77.664818 -73.709022)
		(stroke
			(width 0.2)
			(type default)
		)
		(layer "In3.Cu")
	)
	(gr_arc
		(start 77.664818 -73.709022)
		(mid 77.283945 -73.327768)
		(end 76.902818 -73.708768)
		(stroke
			(width 0.2)
			(type default)
		)
		(layer "In3.Cu")
	)
	(gr_line
		(start 77.724 -168.402)
		(end 78.105 -168.783)
		(stroke
			(width 0.381)
			(type default)
		)
		(layer "In3.Cu")
	)
	(gr_line
		(start 77.736192 -68.201032)
		(end 77.736192 -67.312286)
		(stroke
			(width 0.2)
			(type default)
		)
		(layer "In3.Cu")
	)
	(gr_arc
		(start 77.736192 -67.312286)
		(mid 77.355319 -66.931032)
		(end 76.974192 -67.312032)
		(stroke
			(width 0.2)
			(type default)
		)
		(layer "In3.Cu")
	)
	(gr_arc
		(start 77.741018 -90.599768)
		(mid 78.122018 -90.980768)
		(end 78.503018 -90.599768)
		(stroke
			(width 0.2)
			(type default)
		)
		(layer "In3.Cu")
	)
	(gr_line
		(start 77.741018 -89.710768)
		(end 77.741018 -90.599768)
		(stroke
			(width 0.2)
			(type default)
		)
		(layer "In3.Cu")
	)
	(gr_arc
		(start 77.741018 -84.198968)
		(mid 78.122018 -84.579968)
		(end 78.503018 -84.198968)
		(stroke
			(width 0.2)
			(type default)
		)
		(layer "In3.Cu")
	)
	(gr_line
		(start 77.741018 -83.309968)
		(end 77.741018 -84.198968)
		(stroke
			(width 0.2)
			(type default)
		)
		(layer "In3.Cu")
	)
	(gr_arc
		(start 77.741018 -77.798168)
		(mid 78.122018 -78.179168)
		(end 78.503018 -77.798168)
		(stroke
			(width 0.2)
			(type default)
		)
		(layer "In3.Cu")
	)
	(gr_line
		(start 77.741018 -76.909168)
		(end 77.741018 -77.798168)
		(stroke
			(width 0.2)
			(type default)
		)
		(layer "In3.Cu")
	)
	(gr_arc
		(start 77.741018 -71.397368)
		(mid 78.122018 -71.778368)
		(end 78.503018 -71.397368)
		(stroke
			(width 0.2)
			(type default)
		)
		(layer "In3.Cu")
	)
	(gr_line
		(start 77.741018 -70.508368)
		(end 77.741018 -71.397368)
		(stroke
			(width 0.2)
			(type default)
		)
		(layer "In3.Cu")
	)
	(gr_arc
		(start 77.963014 -115.062)
		(mid 77.953414 -115.063967)
		(end 77.945234 -115.069366)
		(stroke
			(width 0.381)
			(type default)
		)
		(layer "In3.Cu")
	)
	(gr_line
		(start 77.963014 -115.062)
		(end 80.01 -115.062)
		(stroke
			(width 0.381)
			(type default)
		)
		(layer "In3.Cu")
	)
	(gr_line
		(start 78.105 -168.783)
		(end 81.026 -168.783)
		(stroke
			(width 0.381)
			(type default)
		)
		(layer "In3.Cu")
	)
	(gr_line
		(start 78.503018 -90.599768)
		(end 78.503018 -89.711022)
		(stroke
			(width 0.2)
			(type default)
		)
		(layer "In3.Cu")
	)
	(gr_arc
		(start 78.503018 -89.711022)
		(mid 78.122145 -89.329768)
		(end 77.741018 -89.710768)
		(stroke
			(width 0.2)
			(type default)
		)
		(layer "In3.Cu")
	)
	(gr_line
		(start 78.503018 -84.198968)
		(end 78.503018 -83.310222)
		(stroke
			(width 0.2)
			(type default)
		)
		(layer "In3.Cu")
	)
	(gr_arc
		(start 78.503018 -83.310222)
		(mid 78.122145 -82.928968)
		(end 77.741018 -83.309968)
		(stroke
			(width 0.2)
			(type default)
		)
		(layer "In3.Cu")
	)
	(gr_line
		(start 78.503018 -77.798168)
		(end 78.503018 -76.909422)
		(stroke
			(width 0.2)
			(type default)
		)
		(layer "In3.Cu")
	)
	(gr_arc
		(start 78.503018 -76.909422)
		(mid 78.122145 -76.528168)
		(end 77.741018 -76.909168)
		(stroke
			(width 0.2)
			(type default)
		)
		(layer "In3.Cu")
	)
	(gr_line
		(start 78.503018 -71.397368)
		(end 78.503018 -70.508622)
		(stroke
			(width 0.2)
			(type default)
		)
		(layer "In3.Cu")
	)
	(gr_arc
		(start 78.503018 -70.508622)
		(mid 78.122145 -70.127368)
		(end 77.741018 -70.508368)
		(stroke
			(width 0.2)
			(type default)
		)
		(layer "In3.Cu")
	)
	(gr_line
		(start 79.883 -185.928)
		(end 75.565 -185.928)
		(stroke
			(width 0.381)
			(type default)
		)
		(layer "In3.Cu")
	)
	(gr_line
		(start 80.01 -115.062)
		(end 87.39505 -107.67695)
		(stroke
			(width 0.381)
			(type default)
		)
		(layer "In3.Cu")
	)
	(gr_line
		(start 80.899 -184.912)
		(end 79.883 -185.928)
		(stroke
			(width 0.381)
			(type default)
		)
		(layer "In3.Cu")
	)
	(gr_line
		(start 80.899 -179.578)
		(end 80.899 -184.912)
		(stroke
			(width 0.381)
			(type default)
		)
		(layer "In3.Cu")
	)
	(gr_line
		(start 81.026 -168.783)
		(end 84.201 -171.958)
		(stroke
			(width 0.381)
			(type default)
		)
		(layer "In3.Cu")
	)
	(gr_line
		(start 82.4992 -191.6938)
		(end 27.5844 -191.6938)
		(stroke
			(width 0.381)
			(type default)
		)
		(layer "In3.Cu")
	)
	(gr_arc
		(start 82.977228 -95.381572)
		(mid 83.358228 -95.762572)
		(end 83.739228 -95.381572)
		(stroke
			(width 0.2)
			(type default)
		)
		(layer "In3.Cu")
	)
	(gr_line
		(start 82.977228 -94.492572)
		(end 82.977228 -95.381572)
		(stroke
			(width 0.2)
			(type default)
		)
		(layer "In3.Cu")
	)
	(gr_arc
		(start 82.977228 -82.581496)
		(mid 83.358228 -82.962496)
		(end 83.739228 -82.581496)
		(stroke
			(width 0.2)
			(type default)
		)
		(layer "In3.Cu")
	)
	(gr_line
		(start 82.977228 -81.692496)
		(end 82.977228 -82.581496)
		(stroke
			(width 0.2)
			(type default)
		)
		(layer "In3.Cu")
	)
	(gr_arc
		(start 82.977228 -76.194158)
		(mid 83.358228 -76.575158)
		(end 83.739228 -76.194158)
		(stroke
			(width 0.2)
			(type default)
		)
		(layer "In3.Cu")
	)
	(gr_line
		(start 82.977228 -75.305158)
		(end 82.977228 -76.194158)
		(stroke
			(width 0.2)
			(type default)
		)
		(layer "In3.Cu")
	)
	(gr_arc
		(start 82.978498 -88.980264)
		(mid 83.359498 -89.361264)
		(end 83.740498 -88.980264)
		(stroke
			(width 0.2)
			(type default)
		)
		(layer "In3.Cu")
	)
	(gr_line
		(start 82.978498 -88.091264)
		(end 82.978498 -88.980264)
		(stroke
			(width 0.2)
			(type default)
		)
		(layer "In3.Cu")
	)
	(gr_line
		(start 83.739228 -95.381572)
		(end 83.739228 -94.492826)
		(stroke
			(width 0.2)
			(type default)
		)
		(layer "In3.Cu")
	)
	(gr_arc
		(start 83.739228 -94.492826)
		(mid 83.358355 -94.111572)
		(end 82.977228 -94.492572)
		(stroke
			(width 0.2)
			(type default)
		)
		(layer "In3.Cu")
	)
	(gr_line
		(start 83.739228 -82.581496)
		(end 83.739228 -81.69275)
		(stroke
			(width 0.2)
			(type default)
		)
		(layer "In3.Cu")
	)
	(gr_arc
		(start 83.739228 -81.69275)
		(mid 83.358355 -81.311496)
		(end 82.977228 -81.692496)
		(stroke
			(width 0.2)
			(type default)
		)
		(layer "In3.Cu")
	)
	(gr_line
		(start 83.739228 -76.194158)
		(end 83.739228 -75.305412)
		(stroke
			(width 0.2)
			(type default)
		)
		(layer "In3.Cu")
	)
	(gr_arc
		(start 83.739228 -75.305412)
		(mid 83.358355 -74.924158)
		(end 82.977228 -75.305158)
		(stroke
			(width 0.2)
			(type default)
		)
		(layer "In3.Cu")
	)
	(gr_line
		(start 83.740498 -88.980264)
		(end 83.740498 -88.091518)
		(stroke
			(width 0.2)
			(type default)
		)
		(layer "In3.Cu")
	)
	(gr_arc
		(start 83.740498 -88.091518)
		(mid 83.359625 -87.710264)
		(end 82.978498 -88.091264)
		(stroke
			(width 0.2)
			(type default)
		)
		(layer "In3.Cu")
	)
	(gr_line
		(start 84.1756 -97.288858)
		(end 84.1756 -52.6796)
		(stroke
			(width 0.381)
			(type default)
		)
		(layer "In3.Cu")
	)
	(gr_line
		(start 84.1756 -52.6796)
		(end 84.7852 -52.07)
		(stroke
			(width 0.381)
			(type default)
		)
		(layer "In3.Cu")
	)
	(gr_line
		(start 84.201 -176.276)
		(end 80.899 -179.578)
		(stroke
			(width 0.381)
			(type default)
		)
		(layer "In3.Cu")
	)
	(gr_line
		(start 84.201 -171.958)
		(end 84.201 -176.276)
		(stroke
			(width 0.381)
			(type default)
		)
		(layer "In3.Cu")
	)
	(gr_arc
		(start 84.482178 -72.987916)
		(mid 84.863178 -73.368916)
		(end 85.244178 -72.987916)
		(stroke
			(width 0.2)
			(type default)
		)
		(layer "In3.Cu")
	)
	(gr_line
		(start 84.482178 -72.098916)
		(end 84.482178 -72.987916)
		(stroke
			(width 0.2)
			(type default)
		)
		(layer "In3.Cu")
	)
	(gr_arc
		(start 84.602828 -92.195396)
		(mid 84.983828 -92.576396)
		(end 85.364828 -92.195396)
		(stroke
			(width 0.2)
			(type default)
		)
		(layer "In3.Cu")
	)
	(gr_line
		(start 84.602828 -91.306396)
		(end 84.602828 -92.195396)
		(stroke
			(width 0.2)
			(type default)
		)
		(layer "In3.Cu")
	)
	(gr_arc
		(start 84.602828 -85.781134)
		(mid 84.983828 -86.162134)
		(end 85.364828 -85.781134)
		(stroke
			(width 0.2)
			(type default)
		)
		(layer "In3.Cu")
	)
	(gr_line
		(start 84.602828 -84.892134)
		(end 84.602828 -85.781134)
		(stroke
			(width 0.2)
			(type default)
		)
		(layer "In3.Cu")
	)
	(gr_arc
		(start 84.605622 -79.396336)
		(mid 84.986622 -79.777336)
		(end 85.367622 -79.396336)
		(stroke
			(width 0.2)
			(type default)
		)
		(layer "In3.Cu")
	)
	(gr_line
		(start 84.605622 -78.507336)
		(end 84.605622 -79.396336)
		(stroke
			(width 0.2)
			(type default)
		)
		(layer "In3.Cu")
	)
	(gr_line
		(start 84.7852 -52.07)
		(end 92.837 -52.07)
		(stroke
			(width 0.381)
			(type default)
		)
		(layer "In3.Cu")
	)
	(gr_line
		(start 84.8868 -164.338)
		(end 76.581 -164.338)
		(stroke
			(width 0.381)
			(type default)
		)
		(layer "In3.Cu")
	)
	(gr_line
		(start 85.244178 -72.987916)
		(end 85.244178 -72.09917)
		(stroke
			(width 0.2)
			(type default)
		)
		(layer "In3.Cu")
	)
	(gr_arc
		(start 85.244178 -72.09917)
		(mid 84.863305 -71.717916)
		(end 84.482178 -72.098916)
		(stroke
			(width 0.2)
			(type default)
		)
		(layer "In3.Cu")
	)
	(gr_line
		(start 85.364828 -92.195396)
		(end 85.364828 -91.30665)
		(stroke
			(width 0.2)
			(type default)
		)
		(layer "In3.Cu")
	)
	(gr_arc
		(start 85.364828 -91.30665)
		(mid 84.983955 -90.925396)
		(end 84.602828 -91.306396)
		(stroke
			(width 0.2)
			(type default)
		)
		(layer "In3.Cu")
	)
	(gr_line
		(start 85.364828 -85.781134)
		(end 85.364828 -84.892388)
		(stroke
			(width 0.2)
			(type default)
		)
		(layer "In3.Cu")
	)
	(gr_arc
		(start 85.364828 -84.892388)
		(mid 84.983955 -84.511134)
		(end 84.602828 -84.892134)
		(stroke
			(width 0.2)
			(type default)
		)
		(layer "In3.Cu")
	)
	(gr_line
		(start 85.367622 -79.396336)
		(end 85.367622 -78.50759)
		(stroke
			(width 0.2)
			(type default)
		)
		(layer "In3.Cu")
	)
	(gr_arc
		(start 85.367622 -78.50759)
		(mid 84.986749 -78.126336)
		(end 84.605622 -78.507336)
		(stroke
			(width 0.2)
			(type default)
		)
		(layer "In3.Cu")
	)
	(gr_line
		(start 86.0552 -163.1696)
		(end 84.8868 -164.338)
		(stroke
			(width 0.381)
			(type default)
		)
		(layer "In3.Cu")
	)
	(gr_line
		(start 87.39505 -107.67695)
		(end 87.39505 -100.508308)
		(stroke
			(width 0.381)
			(type default)
		)
		(layer "In3.Cu")
	)
	(gr_line
		(start 87.39505 -100.508308)
		(end 84.1756 -97.288858)
		(stroke
			(width 0.381)
			(type default)
		)
		(layer "In3.Cu")
	)
	(gr_line
		(start 92.837 -52.07)
		(end 93.345 -51.562)
		(stroke
			(width 0.381)
			(type default)
		)
		(layer "In3.Cu")
	)
	(gr_line
		(start 93.345 -51.562)
		(end 93.345 -49.320958)
		(stroke
			(width 0.381)
			(type default)
		)
		(layer "In3.Cu")
	)
	(gr_line
		(start 93.345 -49.320958)
		(end 95.675958 -46.99)
		(stroke
			(width 0.381)
			(type default)
		)
		(layer "In3.Cu")
	)
	(gr_line
		(start 95.675958 -46.99)
		(end 97.663 -46.99)
		(stroke
			(width 0.381)
			(type default)
		)
		(layer "In3.Cu")
	)
	(gr_line
		(start 97.028 -145.635726)
		(end 98.425 -147.032726)
		(stroke
			(width 0.381)
			(type default)
		)
		(layer "In3.Cu")
	)
	(gr_line
		(start 97.028 -141.6812)
		(end 97.028 -145.635726)
		(stroke
			(width 0.381)
			(type default)
		)
		(layer "In3.Cu")
	)
	(gr_line
		(start 97.282 -46.99)
		(end 97.663 -46.609)
		(stroke
			(width 0.381)
			(type default)
		)
		(layer "In3.Cu")
	)
	(gr_line
		(start 97.5614 -163.1696)
		(end 86.0552 -163.1696)
		(stroke
			(width 0.381)
			(type default)
		)
		(layer "In3.Cu")
	)
	(gr_line
		(start 97.663 -134.7978)
		(end 99.0092 -136.144)
		(stroke
			(width 0.381)
			(type default)
		)
		(layer "In3.Cu")
	)
	(gr_line
		(start 97.663 -47.371)
		(end 97.282 -46.99)
		(stroke
			(width 0.381)
			(type default)
		)
		(layer "In3.Cu")
	)
	(gr_line
		(start 97.663 -20.912582)
		(end 97.663 -134.7978)
		(stroke
			(width 0.381)
			(type default)
		)
		(layer "In3.Cu")
	)
	(gr_line
		(start 98.081846 -194.00012)
		(end 5.617972 -194.00012)
		(stroke
			(width 2.54)
			(type default)
		)
		(layer "In3.Cu")
	)
	(gr_arc
		(start 98.081846 -194.00012)
		(mid 98.607706 -193.850755)
		(end 98.976434 -193.447162)
		(stroke
			(width 2.54)
			(type default)
		)
		(layer "In3.Cu")
	)
	(gr_line
		(start 98.425 -162.306)
		(end 97.5614 -163.1696)
		(stroke
			(width 0.381)
			(type default)
		)
		(layer "In3.Cu")
	)
	(gr_line
		(start 98.425 -147.032726)
		(end 98.425 -162.306)
		(stroke
			(width 0.381)
			(type default)
		)
		(layer "In3.Cu")
	)
	(gr_line
		(start 99.0092 -139.7)
		(end 97.028 -141.6812)
		(stroke
			(width 0.381)
			(type default)
		)
		(layer "In3.Cu")
	)
	(gr_line
		(start 99.0092 -136.144)
		(end 99.0092 -139.7)
		(stroke
			(width 0.381)
			(type default)
		)
		(layer "In3.Cu")
	)
	(gr_line
		(start 101.795072 -16.78051)
		(end 97.663 -20.912582)
		(stroke
			(width 0.381)
			(type default)
		)
		(layer "In3.Cu")
	)
	(gr_line
		(start 103.594408 -184.211214)
		(end 98.976434 -193.447162)
		(stroke
			(width 2.54)
			(type default)
		)
		(layer "In3.Cu")
	)
	(gr_arc
		(start 103.594408 -184.211214)
		(mid 103.673311 -183.993725)
		(end 103.700072 -183.76392)
		(stroke
			(width 2.54)
			(type default)
		)
		(layer "In3.Cu")
	)
	(gr_line
		(start 103.700072 -47.999904)
		(end 103.700072 -183.76392)
		(stroke
			(width 2.54)
			(type default)
		)
		(layer "In3.Cu")
	)
	(gr_line
		(start 103.99649 -16.78051)
		(end 101.795072 -16.78051)
		(stroke
			(width 0.381)
			(type default)
		)
		(layer "In3.Cu")
	)
	(gr_line
		(start 104.3432 -169.8498)
		(end 82.4992 -191.6938)
		(stroke
			(width 0.381)
			(type default)
		)
		(layer "In3.Cu")
	)
	(gr_line
		(start 104.3432 -47.310548)
		(end 104.3432 -169.8498)
		(stroke
			(width 0.381)
			(type default)
		)
		(layer "In3.Cu")
	)
	(gr_arc
		(start 104.70007 -47.999904)
		(mid 104.200198 -47.500032)
		(end 103.700072 -47.999904)
		(stroke
			(width 2.54)
			(type default)
		)
		(layer "In3.Cu")
	)
	(gr_line
		(start 104.775 -46.8122)
		(end 104.3432 -47.310548)
		(stroke
			(width 0.381)
			(type default)
		)
		(layer "In3.Cu")
	)
	(gr_line
		(start 104.775 -25.654)
		(end 104.775 -46.8122)
		(stroke
			(width 0.381)
			(type default)
		)
		(layer "In3.Cu")
	)
	(gr_line
		(start 104.8258 -46.8884)
		(end 104.775 -46.863)
		(stroke
			(width 0.381)
			(type default)
		)
		(layer "In3.Cu")
	)
	(gr_line
		(start 105.2576 -47.2186)
		(end 104.8258 -46.8884)
		(stroke
			(width 0.381)
			(type default)
		)
		(layer "In3.Cu")
	)
	(gr_line
		(start 105.8164 -47.2186)
		(end 105.2576 -47.2186)
		(stroke
			(width 0.381)
			(type default)
		)
		(layer "In3.Cu")
	)
	(gr_line
		(start 106.60507 -47.21987)
		(end 105.8164 -47.2186)
		(stroke
			(width 0.381)
			(type default)
		)
		(layer "In3.Cu")
	)
	(gr_arc
		(start 106.614722 -38.199822)
		(mid 107.099735 -38.685216)
		(end 107.585002 -38.200076)
		(stroke
			(width 0.2)
			(type default)
		)
		(layer "In3.Cu")
	)
	(gr_line
		(start 106.614722 -36.800028)
		(end 106.614722 -38.199822)
		(stroke
			(width 0.2)
			(type default)
		)
		(layer "In3.Cu")
	)
	(gr_arc
		(start 106.614722 -34.600134)
		(mid 107.099862 -35.085274)
		(end 107.585002 -34.600134)
		(stroke
			(width 0.2)
			(type default)
		)
		(layer "In3.Cu")
	)
	(gr_line
		(start 106.614722 -33.200086)
		(end 106.614722 -34.600134)
		(stroke
			(width 0.2)
			(type default)
		)
		(layer "In3.Cu")
	)
	(gr_line
		(start 107.585002 -38.200076)
		(end 107.585002 -36.800028)
		(stroke
			(width 0.2)
			(type default)
		)
		(layer "In3.Cu")
	)
	(gr_arc
		(start 107.585002 -36.800028)
		(mid 107.099862 -36.314888)
		(end 106.614722 -36.800028)
		(stroke
			(width 0.2)
			(type default)
		)
		(layer "In3.Cu")
	)
	(gr_line
		(start 107.585002 -34.600134)
		(end 107.585002 -33.20034)
		(stroke
			(width 0.2)
			(type default)
		)
		(layer "In3.Cu")
	)
	(gr_arc
		(start 107.585002 -33.20034)
		(mid 107.099989 -32.714946)
		(end 106.614722 -33.200086)
		(stroke
			(width 0.2)
			(type default)
		)
		(layer "In3.Cu")
	)
	(gr_arc
		(start 108.41482 -36.999926)
		(mid 108.899833 -37.48532)
		(end 109.3851 -37.00018)
		(stroke
			(width 0.2)
			(type default)
		)
		(layer "In3.Cu")
	)
	(gr_line
		(start 108.41482 -35.600132)
		(end 108.41482 -36.999926)
		(stroke
			(width 0.2)
			(type default)
		)
		(layer "In3.Cu")
	)
	(gr_arc
		(start 108.41482 -33.39973)
		(mid 108.899833 -33.885124)
		(end 109.3851 -33.399984)
		(stroke
			(width 0.2)
			(type default)
		)
		(layer "In3.Cu")
	)
	(gr_line
		(start 108.41482 -32.00019)
		(end 108.41482 -33.39973)
		(stroke
			(width 0.2)
			(type default)
		)
		(layer "In3.Cu")
	)
	(gr_line
		(start 109.3851 -37.00018)
		(end 109.3851 -35.600132)
		(stroke
			(width 0.2)
			(type default)
		)
		(layer "In3.Cu")
	)
	(gr_arc
		(start 109.3851 -35.600132)
		(mid 108.89996 -35.114992)
		(end 108.41482 -35.600132)
		(stroke
			(width 0.2)
			(type default)
		)
		(layer "In3.Cu")
	)
	(gr_line
		(start 109.3851 -33.399984)
		(end 109.3851 -32.00019)
		(stroke
			(width 0.2)
			(type default)
		)
		(layer "In3.Cu")
	)
	(gr_arc
		(start 109.3851 -32.00019)
		(mid 108.89996 -31.51505)
		(end 108.41482 -32.00019)
		(stroke
			(width 0.2)
			(type default)
		)
		(layer "In3.Cu")
	)
	(gr_arc
		(start 110.214918 -38.199822)
		(mid 110.699931 -38.685216)
		(end 111.185198 -38.200076)
		(stroke
			(width 0.2)
			(type default)
		)
		(layer "In3.Cu")
	)
	(gr_line
		(start 110.214918 -36.800028)
		(end 110.214918 -38.199822)
		(stroke
			(width 0.2)
			(type default)
		)
		(layer "In3.Cu")
	)
	(gr_arc
		(start 110.214918 -34.600134)
		(mid 110.700058 -35.085274)
		(end 111.185198 -34.600134)
		(stroke
			(width 0.2)
			(type default)
		)
		(layer "In3.Cu")
	)
	(gr_line
		(start 110.214918 -33.200086)
		(end 110.214918 -34.600134)
		(stroke
			(width 0.2)
			(type default)
		)
		(layer "In3.Cu")
	)
	(gr_line
		(start 110.49 -10.287)
		(end 103.99649 -16.78051)
		(stroke
			(width 0.381)
			(type default)
		)
		(layer "In3.Cu")
	)
	(gr_line
		(start 111.185198 -38.200076)
		(end 111.185198 -36.800028)
		(stroke
			(width 0.2)
			(type default)
		)
		(layer "In3.Cu")
	)
	(gr_arc
		(start 111.185198 -36.800028)
		(mid 110.700058 -36.314888)
		(end 110.214918 -36.800028)
		(stroke
			(width 0.2)
			(type default)
		)
		(layer "In3.Cu")
	)
	(gr_line
		(start 111.185198 -34.600134)
		(end 111.185198 -33.20034)
		(stroke
			(width 0.2)
			(type default)
		)
		(layer "In3.Cu")
	)
	(gr_arc
		(start 111.185198 -33.20034)
		(mid 110.700185 -32.714946)
		(end 110.214918 -33.200086)
		(stroke
			(width 0.2)
			(type default)
		)
		(layer "In3.Cu")
	)
	(gr_arc
		(start 112.014762 -36.999926)
		(mid 112.499775 -37.48532)
		(end 112.985042 -37.00018)
		(stroke
			(width 0.2)
			(type default)
		)
		(layer "In3.Cu")
	)
	(gr_line
		(start 112.014762 -35.600132)
		(end 112.014762 -36.999926)
		(stroke
			(width 0.2)
			(type default)
		)
		(layer "In3.Cu")
	)
	(gr_arc
		(start 112.014762 -33.39973)
		(mid 112.499775 -33.885124)
		(end 112.985042 -33.399984)
		(stroke
			(width 0.2)
			(type default)
		)
		(layer "In3.Cu")
	)
	(gr_line
		(start 112.014762 -32.00019)
		(end 112.014762 -33.39973)
		(stroke
			(width 0.2)
			(type default)
		)
		(layer "In3.Cu")
	)
	(gr_line
		(start 112.985042 -37.00018)
		(end 112.985042 -35.600132)
		(stroke
			(width 0.2)
			(type default)
		)
		(layer "In3.Cu")
	)
	(gr_arc
		(start 112.985042 -35.600132)
		(mid 112.499902 -35.114992)
		(end 112.014762 -35.600132)
		(stroke
			(width 0.2)
			(type default)
		)
		(layer "In3.Cu")
	)
	(gr_line
		(start 112.985042 -33.399984)
		(end 112.985042 -32.00019)
		(stroke
			(width 0.2)
			(type default)
		)
		(layer "In3.Cu")
	)
	(gr_arc
		(start 112.985042 -32.00019)
		(mid 112.499902 -31.51505)
		(end 112.014762 -32.00019)
		(stroke
			(width 0.2)
			(type default)
		)
		(layer "In3.Cu")
	)
	(gr_arc
		(start 113.81486 -38.199822)
		(mid 114.299873 -38.685216)
		(end 114.78514 -38.200076)
		(stroke
			(width 0.2)
			(type default)
		)
		(layer "In3.Cu")
	)
	(gr_line
		(start 113.81486 -36.800028)
		(end 113.81486 -38.199822)
		(stroke
			(width 0.2)
			(type default)
		)
		(layer "In3.Cu")
	)
	(gr_arc
		(start 113.81486 -34.600134)
		(mid 114.3 -35.085274)
		(end 114.78514 -34.600134)
		(stroke
			(width 0.2)
			(type default)
		)
		(layer "In3.Cu")
	)
	(gr_line
		(start 113.81486 -33.200086)
		(end 113.81486 -34.600134)
		(stroke
			(width 0.2)
			(type default)
		)
		(layer "In3.Cu")
	)
	(gr_line
		(start 114.78514 -38.200076)
		(end 114.78514 -36.800028)
		(stroke
			(width 0.2)
			(type default)
		)
		(layer "In3.Cu")
	)
	(gr_arc
		(start 114.78514 -36.800028)
		(mid 114.3 -36.314888)
		(end 113.81486 -36.800028)
		(stroke
			(width 0.2)
			(type default)
		)
		(layer "In3.Cu")
	)
	(gr_line
		(start 114.78514 -34.600134)
		(end 114.78514 -33.20034)
		(stroke
			(width 0.2)
			(type default)
		)
		(layer "In3.Cu")
	)
	(gr_arc
		(start 114.78514 -33.20034)
		(mid 114.300127 -32.714946)
		(end 113.81486 -33.200086)
		(stroke
			(width 0.2)
			(type default)
		)
		(layer "In3.Cu")
	)
	(gr_arc
		(start 115.614704 -36.999926)
		(mid 116.099717 -37.48532)
		(end 116.584984 -37.00018)
		(stroke
			(width 0.2)
			(type default)
		)
		(layer "In3.Cu")
	)
	(gr_line
		(start 115.614704 -35.600132)
		(end 115.614704 -36.999926)
		(stroke
			(width 0.2)
			(type default)
		)
		(layer "In3.Cu")
	)
	(gr_arc
		(start 115.614704 -33.39973)
		(mid 116.099717 -33.885124)
		(end 116.584984 -33.399984)
		(stroke
			(width 0.2)
			(type default)
		)
		(layer "In3.Cu")
	)
	(gr_line
		(start 115.614704 -32.00019)
		(end 115.614704 -33.39973)
		(stroke
			(width 0.2)
			(type default)
		)
		(layer "In3.Cu")
	)
	(gr_line
		(start 115.697 -14.732)
		(end 104.775 -25.654)
		(stroke
			(width 0.381)
			(type default)
		)
		(layer "In3.Cu")
	)
	(gr_line
		(start 116.584984 -37.00018)
		(end 116.584984 -35.600132)
		(stroke
			(width 0.2)
			(type default)
		)
		(layer "In3.Cu")
	)
	(gr_arc
		(start 116.584984 -35.600132)
		(mid 116.099844 -35.114992)
		(end 115.614704 -35.600132)
		(stroke
			(width 0.2)
			(type default)
		)
		(layer "In3.Cu")
	)
	(gr_line
		(start 116.584984 -33.399984)
		(end 116.584984 -32.00019)
		(stroke
			(width 0.2)
			(type default)
		)
		(layer "In3.Cu")
	)
	(gr_arc
		(start 116.584984 -32.00019)
		(mid 116.099844 -31.51505)
		(end 115.614704 -32.00019)
		(stroke
			(width 0.2)
			(type default)
		)
		(layer "In3.Cu")
	)
	(gr_arc
		(start 117.414802 -38.199822)
		(mid 117.899815 -38.685216)
		(end 118.385082 -38.200076)
		(stroke
			(width 0.2)
			(type default)
		)
		(layer "In3.Cu")
	)
	(gr_line
		(start 117.414802 -36.800028)
		(end 117.414802 -38.199822)
		(stroke
			(width 0.2)
			(type default)
		)
		(layer "In3.Cu")
	)
	(gr_arc
		(start 117.414802 -34.600134)
		(mid 117.899942 -35.085274)
		(end 118.385082 -34.600134)
		(stroke
			(width 0.2)
			(type default)
		)
		(layer "In3.Cu")
	)
	(gr_line
		(start 117.414802 -33.200086)
		(end 117.414802 -34.600134)
		(stroke
			(width 0.2)
			(type default)
		)
		(layer "In3.Cu")
	)
	(gr_line
		(start 118.385082 -38.200076)
		(end 118.385082 -36.800028)
		(stroke
			(width 0.2)
			(type default)
		)
		(layer "In3.Cu")
	)
	(gr_arc
		(start 118.385082 -36.800028)
		(mid 117.899942 -36.314888)
		(end 117.414802 -36.800028)
		(stroke
			(width 0.2)
			(type default)
		)
		(layer "In3.Cu")
	)
	(gr_line
		(start 118.385082 -34.600134)
		(end 118.385082 -33.20034)
		(stroke
			(width 0.2)
			(type default)
		)
		(layer "In3.Cu")
	)
	(gr_arc
		(start 118.385082 -33.20034)
		(mid 117.900069 -32.714946)
		(end 117.414802 -33.200086)
		(stroke
			(width 0.2)
			(type default)
		)
		(layer "In3.Cu")
	)
	(gr_arc
		(start 119.2149 -44.19981)
		(mid 119.699913 -44.685204)
		(end 120.18518 -44.200064)
		(stroke
			(width 0.2)
			(type default)
		)
		(layer "In3.Cu")
	)
	(gr_line
		(start 119.2149 -42.800016)
		(end 119.2149 -44.19981)
		(stroke
			(width 0.2)
			(type default)
		)
		(layer "In3.Cu")
	)
	(gr_arc
		(start 119.2149 -36.999926)
		(mid 119.699913 -37.48532)
		(end 120.18518 -37.00018)
		(stroke
			(width 0.2)
			(type default)
		)
		(layer "In3.Cu")
	)
	(gr_line
		(start 119.2149 -35.600132)
		(end 119.2149 -36.999926)
		(stroke
			(width 0.2)
			(type default)
		)
		(layer "In3.Cu")
	)
	(gr_arc
		(start 119.2149 -33.39973)
		(mid 119.699913 -33.885124)
		(end 120.18518 -33.399984)
		(stroke
			(width 0.2)
			(type default)
		)
		(layer "In3.Cu")
	)
	(gr_line
		(start 119.2149 -32.00019)
		(end 119.2149 -33.39973)
		(stroke
			(width 0.2)
			(type default)
		)
		(layer "In3.Cu")
	)
	(gr_line
		(start 120.18518 -44.200064)
		(end 120.18518 -42.800016)
		(stroke
			(width 0.2)
			(type default)
		)
		(layer "In3.Cu")
	)
	(gr_arc
		(start 120.18518 -42.800016)
		(mid 119.70004 -42.314876)
		(end 119.2149 -42.800016)
		(stroke
			(width 0.2)
			(type default)
		)
		(layer "In3.Cu")
	)
	(gr_line
		(start 120.18518 -37.00018)
		(end 120.18518 -35.600132)
		(stroke
			(width 0.2)
			(type default)
		)
		(layer "In3.Cu")
	)
	(gr_arc
		(start 120.18518 -35.600132)
		(mid 119.70004 -35.114992)
		(end 119.2149 -35.600132)
		(stroke
			(width 0.2)
			(type default)
		)
		(layer "In3.Cu")
	)
	(gr_line
		(start 120.18518 -33.399984)
		(end 120.18518 -32.00019)
		(stroke
			(width 0.2)
			(type default)
		)
		(layer "In3.Cu")
	)
	(gr_arc
		(start 120.18518 -32.00019)
		(mid 119.70004 -31.51505)
		(end 119.2149 -32.00019)
		(stroke
			(width 0.2)
			(type default)
		)
		(layer "In3.Cu")
	)
	(gr_line
		(start 121.307352 -46.825154)
		(end 121.307352 -15.053818)
		(stroke
			(width 0.381)
			(type default)
		)
		(layer "In3.Cu")
	)
	(gr_line
		(start 121.307352 -15.053818)
		(end 121.013982 -14.760448)
		(stroke
			(width 0.381)
			(type default)
		)
		(layer "In3.Cu")
	)
	(gr_line
		(start 121.307352 -15.053818)
		(end 121.324116 -15.053818)
		(stroke
			(width 0.381)
			(type default)
		)
		(layer "In3.Cu")
	)
	(gr_line
		(start 121.324116 -15.053818)
		(end 121.621042 -14.756892)
		(stroke
			(width 0.381)
			(type default)
		)
		(layer "In3.Cu")
	)
	(gr_line
		(start 125.222 -14.732)
		(end 115.697 -14.732)
		(stroke
			(width 0.381)
			(type default)
		)
		(layer "In3.Cu")
	)
	(gr_line
		(start 125.857 -15.367)
		(end 125.222 -14.732)
		(stroke
			(width 0.381)
			(type default)
		)
		(layer "In3.Cu")
	)
	(gr_line
		(start 128.143 -10.287)
		(end 110.49 -10.287)
		(stroke
			(width 0.381)
			(type default)
		)
		(layer "In3.Cu")
	)
	(gr_arc
		(start 128.214882 -38.199822)
		(mid 128.699895 -38.685216)
		(end 129.185162 -38.200076)
		(stroke
			(width 0.2)
			(type default)
		)
		(layer "In3.Cu")
	)
	(gr_line
		(start 128.214882 -36.800028)
		(end 128.214882 -38.199822)
		(stroke
			(width 0.2)
			(type default)
		)
		(layer "In3.Cu")
	)
	(gr_arc
		(start 128.214882 -34.600134)
		(mid 128.700022 -35.085274)
		(end 129.185162 -34.600134)
		(stroke
			(width 0.2)
			(type default)
		)
		(layer "In3.Cu")
	)
	(gr_line
		(start 128.214882 -33.200086)
		(end 128.214882 -34.600134)
		(stroke
			(width 0.2)
			(type default)
		)
		(layer "In3.Cu")
	)
	(gr_line
		(start 128.467866 -26.592276)
		(end 129.53492 -26.592276)
		(stroke
			(width 0.2)
			(type default)
		)
		(layer "In3.Cu")
	)
	(gr_arc
		(start 128.467866 -25.830276)
		(mid 128.086866 -26.211276)
		(end 128.467866 -26.592276)
		(stroke
			(width 0.2)
			(type default)
		)
		(layer "In3.Cu")
	)
	(gr_line
		(start 128.905 -11.049)
		(end 128.143 -10.287)
		(stroke
			(width 0.381)
			(type default)
		)
		(layer "In3.Cu")
	)
	(gr_line
		(start 129.185162 -38.200076)
		(end 129.185162 -36.800028)
		(stroke
			(width 0.2)
			(type default)
		)
		(layer "In3.Cu")
	)
	(gr_arc
		(start 129.185162 -36.800028)
		(mid 128.700022 -36.314888)
		(end 128.214882 -36.800028)
		(stroke
			(width 0.2)
			(type default)
		)
		(layer "In3.Cu")
	)
	(gr_line
		(start 129.185162 -34.600134)
		(end 129.185162 -33.20034)
		(stroke
			(width 0.2)
			(type default)
		)
		(layer "In3.Cu")
	)
	(gr_arc
		(start 129.185162 -33.20034)
		(mid 128.700149 -32.714946)
		(end 128.214882 -33.200086)
		(stroke
			(width 0.2)
			(type default)
		)
		(layer "In3.Cu")
	)
	(gr_arc
		(start 129.53492 -26.592276)
		(mid 129.916174 -26.211403)
		(end 129.535174 -25.830276)
		(stroke
			(width 0.2)
			(type default)
		)
		(layer "In3.Cu")
	)
	(gr_line
		(start 129.535174 -25.830276)
		(end 128.467866 -25.830276)
		(stroke
			(width 0.2)
			(type default)
		)
		(layer "In3.Cu")
	)
	(gr_arc
		(start 130.014726 -36.999926)
		(mid 130.499739 -37.48532)
		(end 130.985006 -37.00018)
		(stroke
			(width 0.2)
			(type default)
		)
		(layer "In3.Cu")
	)
	(gr_line
		(start 130.014726 -35.600132)
		(end 130.014726 -36.999926)
		(stroke
			(width 0.2)
			(type default)
		)
		(layer "In3.Cu")
	)
	(gr_arc
		(start 130.014726 -33.39973)
		(mid 130.499739 -33.885124)
		(end 130.985006 -33.399984)
		(stroke
			(width 0.2)
			(type default)
		)
		(layer "In3.Cu")
	)
	(gr_line
		(start 130.014726 -32.00019)
		(end 130.014726 -33.39973)
		(stroke
			(width 0.2)
			(type default)
		)
		(layer "In3.Cu")
	)
	(gr_line
		(start 130.985006 -37.00018)
		(end 130.985006 -35.600132)
		(stroke
			(width 0.2)
			(type default)
		)
		(layer "In3.Cu")
	)
	(gr_arc
		(start 130.985006 -35.600132)
		(mid 130.499866 -35.114992)
		(end 130.014726 -35.600132)
		(stroke
			(width 0.2)
			(type default)
		)
		(layer "In3.Cu")
	)
	(gr_line
		(start 130.985006 -33.399984)
		(end 130.985006 -32.00019)
		(stroke
			(width 0.2)
			(type default)
		)
		(layer "In3.Cu")
	)
	(gr_arc
		(start 130.985006 -32.00019)
		(mid 130.499866 -31.51505)
		(end 130.014726 -32.00019)
		(stroke
			(width 0.2)
			(type default)
		)
		(layer "In3.Cu")
	)
	(gr_arc
		(start 131.814824 -38.199822)
		(mid 132.299837 -38.685216)
		(end 132.785104 -38.200076)
		(stroke
			(width 0.2)
			(type default)
		)
		(layer "In3.Cu")
	)
	(gr_line
		(start 131.814824 -36.800028)
		(end 131.814824 -38.199822)
		(stroke
			(width 0.2)
			(type default)
		)
		(layer "In3.Cu")
	)
	(gr_arc
		(start 131.814824 -34.600134)
		(mid 132.299964 -35.085274)
		(end 132.785104 -34.600134)
		(stroke
			(width 0.2)
			(type default)
		)
		(layer "In3.Cu")
	)
	(gr_line
		(start 131.814824 -33.200086)
		(end 131.814824 -34.600134)
		(stroke
			(width 0.2)
			(type default)
		)
		(layer "In3.Cu")
	)
	(gr_line
		(start 132.334 -15.367)
		(end 125.857 -15.367)
		(stroke
			(width 0.381)
			(type default)
		)
		(layer "In3.Cu")
	)
	(gr_line
		(start 132.785104 -38.200076)
		(end 132.785104 -36.800028)
		(stroke
			(width 0.2)
			(type default)
		)
		(layer "In3.Cu")
	)
	(gr_arc
		(start 132.785104 -36.800028)
		(mid 132.299964 -36.314888)
		(end 131.814824 -36.800028)
		(stroke
			(width 0.2)
			(type default)
		)
		(layer "In3.Cu")
	)
	(gr_line
		(start 132.785104 -34.600134)
		(end 132.785104 -33.20034)
		(stroke
			(width 0.2)
			(type default)
		)
		(layer "In3.Cu")
	)
	(gr_arc
		(start 132.785104 -33.20034)
		(mid 132.300091 -32.714946)
		(end 131.814824 -33.200086)
		(stroke
			(width 0.2)
			(type default)
		)
		(layer "In3.Cu")
	)
	(gr_line
		(start 133.477 -11.049)
		(end 128.905 -11.049)
		(stroke
			(width 0.381)
			(type default)
		)
		(layer "In3.Cu")
	)
	(gr_line
		(start 133.604 -14.097)
		(end 132.334 -15.367)
		(stroke
			(width 0.381)
			(type default)
		)
		(layer "In3.Cu")
	)
	(gr_arc
		(start 133.614922 -44.19981)
		(mid 134.099935 -44.685204)
		(end 134.585202 -44.200064)
		(stroke
			(width 0.2)
			(type default)
		)
		(layer "In3.Cu")
	)
	(gr_line
		(start 133.614922 -42.800016)
		(end 133.614922 -44.19981)
		(stroke
			(width 0.2)
			(type default)
		)
		(layer "In3.Cu")
	)
	(gr_arc
		(start 133.614922 -36.999926)
		(mid 134.099935 -37.48532)
		(end 134.585202 -37.00018)
		(stroke
			(width 0.2)
			(type default)
		)
		(layer "In3.Cu")
	)
	(gr_line
		(start 133.614922 -35.600132)
		(end 133.614922 -36.999926)
		(stroke
			(width 0.2)
			(type default)
		)
		(layer "In3.Cu")
	)
	(gr_arc
		(start 133.614922 -33.39973)
		(mid 134.099935 -33.885124)
		(end 134.585202 -33.399984)
		(stroke
			(width 0.2)
			(type default)
		)
		(layer "In3.Cu")
	)
	(gr_line
		(start 133.614922 -32.00019)
		(end 133.614922 -33.39973)
		(stroke
			(width 0.2)
			(type default)
		)
		(layer "In3.Cu")
	)
	(gr_line
		(start 134.585202 -44.200064)
		(end 134.585202 -42.800016)
		(stroke
			(width 0.2)
			(type default)
		)
		(layer "In3.Cu")
	)
	(gr_arc
		(start 134.585202 -42.800016)
		(mid 134.100062 -42.314876)
		(end 133.614922 -42.800016)
		(stroke
			(width 0.2)
			(type default)
		)
		(layer "In3.Cu")
	)
	(gr_line
		(start 134.585202 -37.00018)
		(end 134.585202 -35.600132)
		(stroke
			(width 0.2)
			(type default)
		)
		(layer "In3.Cu")
	)
	(gr_arc
		(start 134.585202 -35.600132)
		(mid 134.100062 -35.114992)
		(end 133.614922 -35.600132)
		(stroke
			(width 0.2)
			(type default)
		)
		(layer "In3.Cu")
	)
	(gr_line
		(start 134.585202 -33.399984)
		(end 134.585202 -32.00019)
		(stroke
			(width 0.2)
			(type default)
		)
		(layer "In3.Cu")
	)
	(gr_arc
		(start 134.585202 -32.00019)
		(mid 134.100062 -31.51505)
		(end 133.614922 -32.00019)
		(stroke
			(width 0.2)
			(type default)
		)
		(layer "In3.Cu")
	)
	(gr_line
		(start 135.057642 -46.77029)
		(end 135.057642 -30.571186)
		(stroke
			(width 0.381)
			(type default)
		)
		(layer "In3.Cu")
	)
	(gr_line
		(start 135.057642 -30.571186)
		(end 135.804656 -29.824172)
		(stroke
			(width 0.381)
			(type default)
		)
		(layer "In3.Cu")
	)
	(gr_line
		(start 135.128 -9.398)
		(end 133.477 -11.049)
		(stroke
			(width 0.381)
			(type default)
		)
		(layer "In3.Cu")
	)
	(gr_arc
		(start 135.414766 -38.199822)
		(mid 135.899779 -38.685216)
		(end 136.385046 -38.200076)
		(stroke
			(width 0.2)
			(type default)
		)
		(layer "In3.Cu")
	)
	(gr_line
		(start 135.414766 -36.800028)
		(end 135.414766 -38.199822)
		(stroke
			(width 0.2)
			(type default)
		)
		(layer "In3.Cu")
	)
	(gr_arc
		(start 135.414766 -34.600134)
		(mid 135.899906 -35.085274)
		(end 136.385046 -34.600134)
		(stroke
			(width 0.2)
			(type default)
		)
		(layer "In3.Cu")
	)
	(gr_line
		(start 135.414766 -33.200086)
		(end 135.414766 -34.600134)
		(stroke
			(width 0.2)
			(type default)
		)
		(layer "In3.Cu")
	)
	(gr_line
		(start 135.804656 -29.824172)
		(end 143.727424 -29.824172)
		(stroke
			(width 0.381)
			(type default)
		)
		(layer "In3.Cu")
	)
	(gr_line
		(start 136.385046 -38.200076)
		(end 136.385046 -36.800028)
		(stroke
			(width 0.2)
			(type default)
		)
		(layer "In3.Cu")
	)
	(gr_arc
		(start 136.385046 -36.800028)
		(mid 135.899906 -36.314888)
		(end 135.414766 -36.800028)
		(stroke
			(width 0.2)
			(type default)
		)
		(layer "In3.Cu")
	)
	(gr_line
		(start 136.385046 -34.600134)
		(end 136.385046 -33.20034)
		(stroke
			(width 0.2)
			(type default)
		)
		(layer "In3.Cu")
	)
	(gr_arc
		(start 136.385046 -33.20034)
		(mid 135.900033 -32.714946)
		(end 135.414766 -33.200086)
		(stroke
			(width 0.2)
			(type default)
		)
		(layer "In3.Cu")
	)
	(gr_arc
		(start 137.214864 -36.999926)
		(mid 137.699877 -37.48532)
		(end 138.185144 -37.00018)
		(stroke
			(width 0.2)
			(type default)
		)
		(layer "In3.Cu")
	)
	(gr_line
		(start 137.214864 -35.600132)
		(end 137.214864 -36.999926)
		(stroke
			(width 0.2)
			(type default)
		)
		(layer "In3.Cu")
	)
	(gr_arc
		(start 137.214864 -33.39973)
		(mid 137.699877 -33.885124)
		(end 138.185144 -33.399984)
		(stroke
			(width 0.2)
			(type default)
		)
		(layer "In3.Cu")
	)
	(gr_line
		(start 137.214864 -32.00019)
		(end 137.214864 -33.39973)
		(stroke
			(width 0.2)
			(type default)
		)
		(layer "In3.Cu")
	)
	(gr_line
		(start 138.185144 -37.00018)
		(end 138.185144 -35.600132)
		(stroke
			(width 0.2)
			(type default)
		)
		(layer "In3.Cu")
	)
	(gr_arc
		(start 138.185144 -35.600132)
		(mid 137.700004 -35.114992)
		(end 137.214864 -35.600132)
		(stroke
			(width 0.2)
			(type default)
		)
		(layer "In3.Cu")
	)
	(gr_line
		(start 138.185144 -33.399984)
		(end 138.185144 -32.00019)
		(stroke
			(width 0.2)
			(type default)
		)
		(layer "In3.Cu")
	)
	(gr_arc
		(start 138.185144 -32.00019)
		(mid 137.700004 -31.51505)
		(end 137.214864 -32.00019)
		(stroke
			(width 0.2)
			(type default)
		)
		(layer "In3.Cu")
	)
	(gr_arc
		(start 139.014708 -38.199822)
		(mid 139.499721 -38.685216)
		(end 139.984988 -38.200076)
		(stroke
			(width 0.2)
			(type default)
		)
		(layer "In3.Cu")
	)
	(gr_line
		(start 139.014708 -36.800028)
		(end 139.014708 -38.199822)
		(stroke
			(width 0.2)
			(type default)
		)
		(layer "In3.Cu")
	)
	(gr_arc
		(start 139.014708 -34.600134)
		(mid 139.499848 -35.085274)
		(end 139.984988 -34.600134)
		(stroke
			(width 0.2)
			(type default)
		)
		(layer "In3.Cu")
	)
	(gr_line
		(start 139.014708 -33.200086)
		(end 139.014708 -34.600134)
		(stroke
			(width 0.2)
			(type default)
		)
		(layer "In3.Cu")
	)
	(gr_line
		(start 139.984988 -38.200076)
		(end 139.984988 -36.800028)
		(stroke
			(width 0.2)
			(type default)
		)
		(layer "In3.Cu")
	)
	(gr_arc
		(start 139.984988 -36.800028)
		(mid 139.499848 -36.314888)
		(end 139.014708 -36.800028)
		(stroke
			(width 0.2)
			(type default)
		)
		(layer "In3.Cu")
	)
	(gr_line
		(start 139.984988 -34.600134)
		(end 139.984988 -33.20034)
		(stroke
			(width 0.2)
			(type default)
		)
		(layer "In3.Cu")
	)
	(gr_arc
		(start 139.984988 -33.20034)
		(mid 139.499975 -32.714946)
		(end 139.014708 -33.200086)
		(stroke
			(width 0.2)
			(type default)
		)
		(layer "In3.Cu")
	)
	(gr_line
		(start 140.335 -14.097)
		(end 133.604 -14.097)
		(stroke
			(width 0.381)
			(type default)
		)
		(layer "In3.Cu")
	)
	(gr_arc
		(start 140.814806 -44.19981)
		(mid 141.299819 -44.685204)
		(end 141.785086 -44.200064)
		(stroke
			(width 0.2)
			(type default)
		)
		(layer "In3.Cu")
	)
	(gr_line
		(start 140.814806 -42.800016)
		(end 140.814806 -44.19981)
		(stroke
			(width 0.2)
			(type default)
		)
		(layer "In3.Cu")
	)
	(gr_arc
		(start 140.814806 -36.999926)
		(mid 141.299819 -37.48532)
		(end 141.785086 -37.00018)
		(stroke
			(width 0.2)
			(type default)
		)
		(layer "In3.Cu")
	)
	(gr_line
		(start 140.814806 -35.600132)
		(end 140.814806 -36.999926)
		(stroke
			(width 0.2)
			(type default)
		)
		(layer "In3.Cu")
	)
	(gr_arc
		(start 140.814806 -33.39973)
		(mid 141.299819 -33.885124)
		(end 141.785086 -33.399984)
		(stroke
			(width 0.2)
			(type default)
		)
		(layer "In3.Cu")
	)
	(gr_line
		(start 140.814806 -32.00019)
		(end 140.814806 -33.39973)
		(stroke
			(width 0.2)
			(type default)
		)
		(layer "In3.Cu")
	)
	(gr_line
		(start 141.785086 -44.200064)
		(end 141.785086 -42.800016)
		(stroke
			(width 0.2)
			(type default)
		)
		(layer "In3.Cu")
	)
	(gr_arc
		(start 141.785086 -42.800016)
		(mid 141.299946 -42.314876)
		(end 140.814806 -42.800016)
		(stroke
			(width 0.2)
			(type default)
		)
		(layer "In3.Cu")
	)
	(gr_line
		(start 141.785086 -37.00018)
		(end 141.785086 -35.600132)
		(stroke
			(width 0.2)
			(type default)
		)
		(layer "In3.Cu")
	)
	(gr_arc
		(start 141.785086 -35.600132)
		(mid 141.299946 -35.114992)
		(end 140.814806 -35.600132)
		(stroke
			(width 0.2)
			(type default)
		)
		(layer "In3.Cu")
	)
	(gr_line
		(start 141.785086 -33.399984)
		(end 141.785086 -32.00019)
		(stroke
			(width 0.2)
			(type default)
		)
		(layer "In3.Cu")
	)
	(gr_arc
		(start 141.785086 -32.00019)
		(mid 141.299946 -31.51505)
		(end 140.814806 -32.00019)
		(stroke
			(width 0.2)
			(type default)
		)
		(layer "In3.Cu")
	)
	(gr_line
		(start 143.299942 -47.999904)
		(end 104.70007 -47.999904)
		(stroke
			(width 2.54)
			(type default)
		)
		(layer "In3.Cu")
	)
	(gr_line
		(start 143.5354 -47.2186)
		(end 144.0434 -46.7106)
		(stroke
			(width 0.381)
			(type default)
		)
		(layer "In3.Cu")
	)
	(gr_line
		(start 143.727424 -29.824172)
		(end 143.75765 -29.824172)
		(stroke
			(width 0.381)
			(type default)
		)
		(layer "In3.Cu")
	)
	(gr_line
		(start 143.727424 -29.824172)
		(end 144.023334 -30.120082)
		(stroke
			(width 0.381)
			(type default)
		)
		(layer "In3.Cu")
	)
	(gr_line
		(start 143.75765 -29.824172)
		(end 144.044162 -29.53766)
		(stroke
			(width 0.381)
			(type default)
		)
		(layer "In3.Cu")
	)
	(gr_line
		(start 143.9545 -47.6377)
		(end 143.5354 -47.2186)
		(stroke
			(width 0.381)
			(type default)
		)
		(layer "In3.Cu")
	)
	(gr_line
		(start 143.9926 -47.21987)
		(end 106.60507 -47.21987)
		(stroke
			(width 0.381)
			(type default)
		)
		(layer "In3.Cu")
	)
	(gr_line
		(start 144.0434 -50.354738)
		(end 144.0434 -23.532084)
		(stroke
			(width 0.381)
			(type default)
		)
		(layer "In3.Cu")
	)
	(gr_line
		(start 144.0434 -23.532084)
		(end 144.60093 -22.974554)
		(stroke
			(width 0.381)
			(type default)
		)
		(layer "In3.Cu")
	)
	(gr_line
		(start 144.0434 -22.974554)
		(end 144.0434 -23.532084)
		(stroke
			(width 0.381)
			(type default)
		)
		(layer "In3.Cu")
	)
	(gr_line
		(start 144.0434 -22.974554)
		(end 144.0434 -22.417024)
		(stroke
			(width 0.381)
			(type default)
		)
		(layer "In3.Cu")
	)
	(gr_line
		(start 144.0434 -22.417024)
		(end 144.0434 -17.8054)
		(stroke
			(width 0.381)
			(type default)
		)
		(layer "In3.Cu")
	)
	(gr_line
		(start 144.0434 -17.8054)
		(end 140.335 -14.097)
		(stroke
			(width 0.381)
			(type default)
		)
		(layer "In3.Cu")
	)
	(gr_line
		(start 144.29994 -149.763988)
		(end 144.29994 -47.999904)
		(stroke
			(width 2.54)
			(type default)
		)
		(layer "In3.Cu")
	)
	(gr_arc
		(start 144.29994 -149.763988)
		(mid 144.326787 -149.993649)
		(end 144.405604 -150.211028)
		(stroke
			(width 2.54)
			(type default)
		)
		(layer "In3.Cu")
	)
	(gr_arc
		(start 144.29994 -47.999904)
		(mid 143.800068 -47.500032)
		(end 143.299942 -47.999904)
		(stroke
			(width 2.54)
			(type default)
		)
		(layer "In3.Cu")
	)
	(gr_line
		(start 144.60093 -22.974554)
		(end 144.0434 -22.974554)
		(stroke
			(width 0.381)
			(type default)
		)
		(layer "In3.Cu")
	)
	(gr_line
		(start 144.60093 -22.974554)
		(end 144.0434 -22.417024)
		(stroke
			(width 0.381)
			(type default)
		)
		(layer "In3.Cu")
	)
	(gr_line
		(start 144.60093 -22.974554)
		(end 153.994358 -22.974554)
		(stroke
			(width 0.381)
			(type default)
		)
		(layer "In3.Cu")
	)
	(gr_line
		(start 148.604224 -9.398)
		(end 135.128 -9.398)
		(stroke
			(width 0.381)
			(type default)
		)
		(layer "In3.Cu")
	)
	(gr_line
		(start 149.023578 -159.44723)
		(end 144.405604 -150.211028)
		(stroke
			(width 2.54)
			(type default)
		)
		(layer "In3.Cu")
	)
	(gr_arc
		(start 149.023578 -159.44723)
		(mid 149.392231 -159.850635)
		(end 149.917912 -159.999934)
		(stroke
			(width 2.54)
			(type default)
		)
		(layer "In3.Cu")
	)
	(gr_line
		(start 152.182322 -12.976098)
		(end 148.604224 -9.398)
		(stroke
			(width 0.381)
			(type default)
		)
		(layer "In3.Cu")
	)
	(gr_line
		(start 153.994358 -22.974554)
		(end 159.23895 -17.729962)
		(stroke
			(width 0.381)
			(type default)
		)
		(layer "In3.Cu")
	)
	(gr_line
		(start 155.382976 -12.976098)
		(end 152.182322 -12.976098)
		(stroke
			(width 0.381)
			(type default)
		)
		(layer "In3.Cu")
	)
	(gr_line
		(start 157.254194 -11.10488)
		(end 157.451298 -11.10488)
		(stroke
			(width 0.381)
			(type default)
		)
		(layer "In3.Cu")
	)
	(gr_line
		(start 157.310074 -11.049)
		(end 155.382976 -12.976098)
		(stroke
			(width 0.381)
			(type default)
		)
		(layer "In3.Cu")
	)
	(gr_line
		(start 159.23895 -17.729962)
		(end 169.506646 -17.729962)
		(stroke
			(width 0.381)
			(type default)
		)
		(layer "In3.Cu")
	)
	(gr_line
		(start 166.84244 -137.175494)
		(end 167.47109 -137.80389)
		(stroke
			(width 0.2)
			(type default)
		)
		(layer "In3.Cu")
	)
	(gr_arc
		(start 167.381428 -136.636506)
		(mid 166.84244 -136.636506)
		(end 166.84244 -137.175494)
		(stroke
			(width 0.2)
			(type default)
		)
		(layer "In3.Cu")
	)
	(gr_arc
		(start 167.47109 -137.80389)
		(mid 168.009888 -137.804081)
		(end 168.010078 -137.265156)
		(stroke
			(width 0.2)
			(type default)
		)
		(layer "In3.Cu")
	)
	(gr_line
		(start 168.010078 -137.265156)
		(end 167.381428 -136.636506)
		(stroke
			(width 0.2)
			(type default)
		)
		(layer "In3.Cu")
	)
	(gr_line
		(start 169.506646 -17.729962)
		(end 172.3136 -14.923008)
		(stroke
			(width 0.381)
			(type default)
		)
		(layer "In3.Cu")
	)
	(gr_line
		(start 170.170602 -138.590528)
		(end 170.799252 -139.218924)
		(stroke
			(width 0.2)
			(type default)
		)
		(layer "In3.Cu")
	)
	(gr_arc
		(start 170.70959 -138.05154)
		(mid 170.170602 -138.05154)
		(end 170.170602 -138.590528)
		(stroke
			(width 0.2)
			(type default)
		)
		(layer "In3.Cu")
	)
	(gr_arc
		(start 170.799252 -139.218924)
		(mid 171.33805 -139.219115)
		(end 171.33824 -138.68019)
		(stroke
			(width 0.2)
			(type default)
		)
		(layer "In3.Cu")
	)
	(gr_line
		(start 171.33824 -138.68019)
		(end 170.70959 -138.05154)
		(stroke
			(width 0.2)
			(type default)
		)
		(layer "In3.Cu")
	)
	(gr_line
		(start 171.723304 -11.049)
		(end 157.310074 -11.049)
		(stroke
			(width 0.381)
			(type default)
		)
		(layer "In3.Cu")
	)
	(gr_line
		(start 172.3136 -15.000986)
		(end 172.3136 -11.639296)
		(stroke
			(width 0.381)
			(type default)
		)
		(layer "In3.Cu")
	)
	(gr_line
		(start 172.3136 -11.639296)
		(end 171.723304 -11.049)
		(stroke
			(width 0.381)
			(type default)
		)
		(layer "In3.Cu")
	)
	(gr_line
		(start 173.521624 -16.20901)
		(end 172.3136 -15.000986)
		(stroke
			(width 0.381)
			(type default)
		)
		(layer "In3.Cu")
	)
	(gr_line
		(start 173.674278 -138.194542)
		(end 174.302928 -138.822938)
		(stroke
			(width 0.2)
			(type default)
		)
		(layer "In3.Cu")
	)
	(gr_line
		(start 174.024798 -140.502386)
		(end 174.653448 -141.130782)
		(stroke
			(width 0.2)
			(type default)
		)
		(layer "In3.Cu")
	)
	(gr_arc
		(start 174.213266 -137.655554)
		(mid 173.674278 -137.655554)
		(end 173.674278 -138.194542)
		(stroke
			(width 0.2)
			(type default)
		)
		(layer "In3.Cu")
	)
	(gr_arc
		(start 174.302928 -138.822938)
		(mid 174.841726 -138.823129)
		(end 174.841916 -138.284204)
		(stroke
			(width 0.2)
			(type default)
		)
		(layer "In3.Cu")
	)
	(gr_arc
		(start 174.563786 -139.963398)
		(mid 174.024798 -139.963398)
		(end 174.024798 -140.502386)
		(stroke
			(width 0.2)
			(type default)
		)
		(layer "In3.Cu")
	)
	(gr_arc
		(start 174.653448 -141.130782)
		(mid 175.192246 -141.130973)
		(end 175.192436 -140.592048)
		(stroke
			(width 0.2)
			(type default)
		)
		(layer "In3.Cu")
	)
	(gr_line
		(start 174.841916 -138.284204)
		(end 174.213266 -137.655554)
		(stroke
			(width 0.2)
			(type default)
		)
		(layer "In3.Cu")
	)
	(gr_line
		(start 174.97552 -2.794)
		(end 180.13553 -7.95401)
		(stroke
			(width 0.381)
			(type default)
		)
		(layer "In3.Cu")
	)
	(gr_line
		(start 175.192436 -140.592048)
		(end 174.563786 -139.963398)
		(stroke
			(width 0.2)
			(type default)
		)
		(layer "In3.Cu")
	)
	(gr_line
		(start 177.391568 -140.243306)
		(end 178.020218 -140.871702)
		(stroke
			(width 0.2)
			(type default)
		)
		(layer "In3.Cu")
	)
	(gr_arc
		(start 177.930556 -139.704318)
		(mid 177.391568 -139.704318)
		(end 177.391568 -140.243306)
		(stroke
			(width 0.2)
			(type default)
		)
		(layer "In3.Cu")
	)
	(gr_arc
		(start 178.020218 -140.871702)
		(mid 178.559016 -140.871893)
		(end 178.559206 -140.332968)
		(stroke
			(width 0.2)
			(type default)
		)
		(layer "In3.Cu")
	)
	(gr_line
		(start 178.559206 -140.332968)
		(end 177.930556 -139.704318)
		(stroke
			(width 0.2)
			(type default)
		)
		(layer "In3.Cu")
	)
	(gr_line
		(start 179.735734 -140.438378)
		(end 180.364384 -141.066774)
		(stroke
			(width 0.2)
			(type default)
		)
		(layer "In3.Cu")
	)
	(gr_line
		(start 180.13553 -7.95401)
		(end 210.23961 -7.95401)
		(stroke
			(width 0.381)
			(type default)
		)
		(layer "In3.Cu")
	)
	(gr_arc
		(start 180.274722 -139.89939)
		(mid 179.735734 -139.89939)
		(end 179.735734 -140.438378)
		(stroke
			(width 0.2)
			(type default)
		)
		(layer "In3.Cu")
	)
	(gr_arc
		(start 180.364384 -141.066774)
		(mid 180.903182 -141.066965)
		(end 180.903372 -140.52804)
		(stroke
			(width 0.2)
			(type default)
		)
		(layer "In3.Cu")
	)
	(gr_line
		(start 180.903372 -140.52804)
		(end 180.274722 -139.89939)
		(stroke
			(width 0.2)
			(type default)
		)
		(layer "In3.Cu")
	)
	(gr_line
		(start 182.059072 -139.932918)
		(end 182.687722 -140.561314)
		(stroke
			(width 0.2)
			(type default)
		)
		(layer "In3.Cu")
	)
	(gr_arc
		(start 182.59806 -139.39393)
		(mid 182.059072 -139.39393)
		(end 182.059072 -139.932918)
		(stroke
			(width 0.2)
			(type default)
		)
		(layer "In3.Cu")
	)
	(gr_arc
		(start 182.687722 -140.561314)
		(mid 183.22652 -140.561505)
		(end 183.22671 -140.02258)
		(stroke
			(width 0.2)
			(type default)
		)
		(layer "In3.Cu")
	)
	(gr_line
		(start 183.016144 -133.354826)
		(end 183.90489 -133.354826)
		(stroke
			(width 0.2)
			(type default)
		)
		(layer "In3.Cu")
	)
	(gr_arc
		(start 183.016144 -132.592826)
		(mid 182.635144 -132.973826)
		(end 183.016144 -133.354826)
		(stroke
			(width 0.2)
			(type default)
		)
		(layer "In3.Cu")
	)
	(gr_line
		(start 183.22671 -140.02258)
		(end 182.59806 -139.39393)
		(stroke
			(width 0.2)
			(type default)
		)
		(layer "In3.Cu")
	)
	(gr_arc
		(start 183.90489 -133.354826)
		(mid 184.286144 -132.973953)
		(end 183.905144 -132.592826)
		(stroke
			(width 0.2)
			(type default)
		)
		(layer "In3.Cu")
	)
	(gr_line
		(start 183.905144 -132.592826)
		(end 183.016144 -132.592826)
		(stroke
			(width 0.2)
			(type default)
		)
		(layer "In3.Cu")
	)
	(gr_line
		(start 184.815734 -139.955778)
		(end 185.444384 -140.584174)
		(stroke
			(width 0.2)
			(type default)
		)
		(layer "In3.Cu")
	)
	(gr_arc
		(start 185.354722 -139.41679)
		(mid 184.815734 -139.41679)
		(end 184.815734 -139.955778)
		(stroke
			(width 0.2)
			(type default)
		)
		(layer "In3.Cu")
	)
	(gr_arc
		(start 185.444384 -140.584174)
		(mid 185.983182 -140.584365)
		(end 185.983372 -140.04544)
		(stroke
			(width 0.2)
			(type default)
		)
		(layer "In3.Cu")
	)
	(gr_line
		(start 185.983372 -140.04544)
		(end 185.354722 -139.41679)
		(stroke
			(width 0.2)
			(type default)
		)
		(layer "In3.Cu")
	)
	(gr_line
		(start 191.821308 -139.528296)
		(end 192.449958 -140.156692)
		(stroke
			(width 0.2)
			(type default)
		)
		(layer "In3.Cu")
	)
	(gr_arc
		(start 192.360296 -138.989308)
		(mid 191.821308 -138.989308)
		(end 191.821308 -139.528296)
		(stroke
			(width 0.2)
			(type default)
		)
		(layer "In3.Cu")
	)
	(gr_arc
		(start 192.449958 -140.156692)
		(mid 192.988756 -140.156883)
		(end 192.988946 -139.617958)
		(stroke
			(width 0.2)
			(type default)
		)
		(layer "In3.Cu")
	)
	(gr_line
		(start 192.988946 -139.617958)
		(end 192.360296 -138.989308)
		(stroke
			(width 0.2)
			(type default)
		)
		(layer "In3.Cu")
	)
	(gr_line
		(start 194.869308 -140.671296)
		(end 195.497958 -141.299692)
		(stroke
			(width 0.2)
			(type default)
		)
		(layer "In3.Cu")
	)
	(gr_arc
		(start 195.408296 -140.132308)
		(mid 194.869308 -140.132308)
		(end 194.869308 -140.671296)
		(stroke
			(width 0.2)
			(type default)
		)
		(layer "In3.Cu")
	)
	(gr_arc
		(start 195.497958 -141.299692)
		(mid 196.036756 -141.299883)
		(end 196.036946 -140.760958)
		(stroke
			(width 0.2)
			(type default)
		)
		(layer "In3.Cu")
	)
	(gr_line
		(start 196.036946 -140.760958)
		(end 195.408296 -140.132308)
		(stroke
			(width 0.2)
			(type default)
		)
		(layer "In3.Cu")
	)
	(gr_line
		(start 197.536308 -140.925296)
		(end 198.164958 -141.553692)
		(stroke
			(width 0.2)
			(type default)
		)
		(layer "In3.Cu")
	)
	(gr_arc
		(start 198.075296 -140.386308)
		(mid 197.536308 -140.386308)
		(end 197.536308 -140.925296)
		(stroke
			(width 0.2)
			(type default)
		)
		(layer "In3.Cu")
	)
	(gr_arc
		(start 198.164958 -141.553692)
		(mid 198.703756 -141.553883)
		(end 198.703946 -141.014958)
		(stroke
			(width 0.2)
			(type default)
		)
		(layer "In3.Cu")
	)
	(gr_line
		(start 198.703946 -141.014958)
		(end 198.075296 -140.386308)
		(stroke
			(width 0.2)
			(type default)
		)
		(layer "In3.Cu")
	)
	(gr_line
		(start 199.949308 -141.179296)
		(end 200.577958 -141.807692)
		(stroke
			(width 0.2)
			(type default)
		)
		(layer "In3.Cu")
	)
	(gr_arc
		(start 200.488296 -140.640308)
		(mid 199.949308 -140.640308)
		(end 199.949308 -141.179296)
		(stroke
			(width 0.2)
			(type default)
		)
		(layer "In3.Cu")
	)
	(gr_arc
		(start 200.577958 -141.807692)
		(mid 201.116756 -141.807883)
		(end 201.116946 -141.268958)
		(stroke
			(width 0.2)
			(type default)
		)
		(layer "In3.Cu")
	)
	(gr_line
		(start 201.116946 -141.268958)
		(end 200.488296 -140.640308)
		(stroke
			(width 0.2)
			(type default)
		)
		(layer "In3.Cu")
	)
	(gr_line
		(start 202.362308 -141.052296)
		(end 202.990958 -141.680692)
		(stroke
			(width 0.2)
			(type default)
		)
		(layer "In3.Cu")
	)
	(gr_arc
		(start 202.901296 -140.513308)
		(mid 202.362308 -140.513308)
		(end 202.362308 -141.052296)
		(stroke
			(width 0.2)
			(type default)
		)
		(layer "In3.Cu")
	)
	(gr_arc
		(start 202.990958 -141.680692)
		(mid 203.529756 -141.680883)
		(end 203.529946 -141.141958)
		(stroke
			(width 0.2)
			(type default)
		)
		(layer "In3.Cu")
	)
	(gr_line
		(start 203.417424 -16.20901)
		(end 173.521624 -16.20901)
		(stroke
			(width 0.381)
			(type default)
		)
		(layer "In3.Cu")
	)
	(gr_line
		(start 203.529946 -141.141958)
		(end 202.901296 -140.513308)
		(stroke
			(width 0.2)
			(type default)
		)
		(layer "In3.Cu")
	)
	(gr_line
		(start 204.648308 -141.179296)
		(end 205.276958 -141.807692)
		(stroke
			(width 0.2)
			(type default)
		)
		(layer "In3.Cu")
	)
	(gr_arc
		(start 205.187296 -140.640308)
		(mid 204.648308 -140.640308)
		(end 204.648308 -141.179296)
		(stroke
			(width 0.2)
			(type default)
		)
		(layer "In3.Cu")
	)
	(gr_arc
		(start 205.276958 -141.807692)
		(mid 205.815756 -141.807883)
		(end 205.815946 -141.268958)
		(stroke
			(width 0.2)
			(type default)
		)
		(layer "In3.Cu")
	)
	(gr_line
		(start 205.815946 -141.268958)
		(end 205.187296 -140.640308)
		(stroke
			(width 0.2)
			(type default)
		)
		(layer "In3.Cu")
	)
	(gr_circle
		(center 206.000096 -6.199886)
		(end 206.815436 -6.199886)
		(stroke
			(width 0.2)
			(type default)
		)
		(fill no)
		(layer "In3.Cu")
	)
	(gr_line
		(start 206.172308 -139.528296)
		(end 206.800958 -140.156692)
		(stroke
			(width 0.2)
			(type default)
		)
		(layer "In3.Cu")
	)
	(gr_arc
		(start 206.711296 -138.989308)
		(mid 206.172308 -138.989308)
		(end 206.172308 -139.528296)
		(stroke
			(width 0.2)
			(type default)
		)
		(layer "In3.Cu")
	)
	(gr_arc
		(start 206.800958 -140.156692)
		(mid 207.339756 -140.156883)
		(end 207.339946 -139.617958)
		(stroke
			(width 0.2)
			(type default)
		)
		(layer "In3.Cu")
	)
	(gr_line
		(start 207.339946 -139.617958)
		(end 206.711296 -138.989308)
		(stroke
			(width 0.2)
			(type default)
		)
		(layer "In3.Cu")
	)
	(gr_line
		(start 209.347308 -140.798296)
		(end 209.975958 -141.426692)
		(stroke
			(width 0.2)
			(type default)
		)
		(layer "In3.Cu")
	)
	(gr_arc
		(start 209.886296 -140.259308)
		(mid 209.347308 -140.259308)
		(end 209.347308 -140.798296)
		(stroke
			(width 0.2)
			(type default)
		)
		(layer "In3.Cu")
	)
	(gr_arc
		(start 209.975958 -141.426692)
		(mid 210.514756 -141.426883)
		(end 210.514946 -140.887958)
		(stroke
			(width 0.2)
			(type default)
		)
		(layer "In3.Cu")
	)
	(gr_line
		(start 210.23961 -7.95401)
		(end 232.3084 -30.0228)
		(stroke
			(width 0.381)
			(type default)
		)
		(layer "In3.Cu")
	)
	(gr_line
		(start 210.514946 -140.887958)
		(end 209.886296 -140.259308)
		(stroke
			(width 0.2)
			(type default)
		)
		(layer "In3.Cu")
	)
	(gr_line
		(start 211.275168 -96.432116)
		(end 211.275168 -24.066754)
		(stroke
			(width 0.381)
			(type default)
		)
		(layer "In3.Cu")
	)
	(gr_line
		(start 211.275168 -24.066754)
		(end 203.417424 -16.20901)
		(stroke
			(width 0.381)
			(type default)
		)
		(layer "In3.Cu")
	)
	(gr_line
		(start 213.063836 -139.146534)
		(end 213.692486 -139.77493)
		(stroke
			(width 0.2)
			(type default)
		)
		(layer "In3.Cu")
	)
	(gr_arc
		(start 213.602824 -138.607546)
		(mid 213.063836 -138.607546)
		(end 213.063836 -139.146534)
		(stroke
			(width 0.2)
			(type default)
		)
		(layer "In3.Cu")
	)
	(gr_line
		(start 213.675214 -98.832162)
		(end 211.275168 -96.432116)
		(stroke
			(width 0.381)
			(type default)
		)
		(layer "In3.Cu")
	)
	(gr_arc
		(start 213.692486 -139.77493)
		(mid 214.231284 -139.775121)
		(end 214.231474 -139.236196)
		(stroke
			(width 0.2)
			(type default)
		)
		(layer "In3.Cu")
	)
	(gr_line
		(start 214.00008 -159.999934)
		(end 149.917912 -159.999934)
		(stroke
			(width 2.54)
			(type default)
		)
		(layer "In3.Cu")
	)
	(gr_line
		(start 214.231474 -139.236196)
		(end 213.602824 -138.607546)
		(stroke
			(width 0.2)
			(type default)
		)
		(layer "In3.Cu")
	)
	(gr_line
		(start 215.000078 -193.000122)
		(end 215.000078 -160.999932)
		(stroke
			(width 2.54)
			(type default)
		)
		(layer "In3.Cu")
	)
	(gr_arc
		(start 215.000078 -193.000122)
		(mid 215.292977 -193.707222)
		(end 216.000076 -194.00012)
		(stroke
			(width 2.54)
			(type default)
		)
		(layer "In3.Cu")
	)
	(gr_arc
		(start 215.000078 -160.999932)
		(mid 214.707185 -160.292827)
		(end 214.00008 -159.999934)
		(stroke
			(width 2.54)
			(type default)
		)
		(layer "In3.Cu")
	)
	(gr_line
		(start 222.990918 -98.832162)
		(end 213.675214 -98.832162)
		(stroke
			(width 0.381)
			(type default)
		)
		(layer "In3.Cu")
	)
	(gr_line
		(start 224.144078 -97.679002)
		(end 222.990918 -98.832162)
		(stroke
			(width 0.381)
			(type default)
		)
		(layer "In3.Cu")
	)
	(gr_line
		(start 229.382066 -194.00012)
		(end 216.000076 -194.00012)
		(stroke
			(width 2.54)
			(type default)
		)
		(layer "In3.Cu")
	)
	(gr_arc
		(start 229.382066 -194.00012)
		(mid 229.907793 -193.850701)
		(end 230.2764 -193.447162)
		(stroke
			(width 2.54)
			(type default)
		)
		(layer "In3.Cu")
	)
	(gr_line
		(start 231.216454 -97.679002)
		(end 224.144078 -97.679002)
		(stroke
			(width 0.381)
			(type default)
		)
		(layer "In3.Cu")
	)
	(gr_line
		(start 232.3084 -96.587056)
		(end 231.216454 -97.679002)
		(stroke
			(width 0.381)
			(type default)
		)
		(layer "In3.Cu")
	)
	(gr_line
		(start 232.3084 -30.0228)
		(end 232.3084 -96.587056)
		(stroke
			(width 0.381)
			(type default)
		)
		(layer "In3.Cu")
	)
	(gr_line
		(start 234.894374 -184.211214)
		(end 230.2764 -193.447162)
		(stroke
			(width 2.54)
			(type default)
		)
		(layer "In3.Cu")
	)
	(gr_arc
		(start 234.894374 -184.211214)
		(mid 234.97328 -183.993726)
		(end 235.000038 -183.76392)
		(stroke
			(width 2.54)
			(type default)
		)
		(layer "In3.Cu")
	)
	(gr_arc
		(start 235.000038 -0.999998)
		(mid 234.707147 -0.29288)
		(end 234.00004 0)
		(stroke
			(width 2.54)
			(type default)
		)
		(layer "In3.Cu")
	)
	(gr_line
		(start 235.000038 -0.999998)
		(end 235.000038 -183.76392)
		(stroke
			(width 2.54)
			(type default)
		)
		(layer "In3.Cu")
	)
	(gr_line
		(start 0 -183.76392)
		(end 0 -0.999998)
		(stroke
			(width 2.54)
			(type default)
		)
		(layer "In4.Cu")
	)
	(gr_arc
		(start 0 -183.76392)
		(mid 0.026807 -183.993715)
		(end 0.105664 -184.211214)
		(stroke
			(width 2.54)
			(type default)
		)
		(layer "In4.Cu")
	)
	(gr_arc
		(start 0.999998 0)
		(mid 0.292893 -0.292893)
		(end 0 -0.999998)
		(stroke
			(width 2.54)
			(type default)
		)
		(layer "In4.Cu")
	)
	(gr_line
		(start 0.999998 0)
		(end 29.53004 0)
		(stroke
			(width 2.54)
			(type default)
		)
		(layer "In4.Cu")
	)
	(gr_line
		(start 4.723638 -193.447162)
		(end 0.105664 -184.211214)
		(stroke
			(width 2.54)
			(type default)
		)
		(layer "In4.Cu")
	)
	(gr_arc
		(start 4.723638 -193.447162)
		(mid 5.092281 -193.850645)
		(end 5.617972 -194.00012)
		(stroke
			(width 2.54)
			(type default)
		)
		(layer "In4.Cu")
	)
	(gr_circle
		(center 14.249908 -6.249924)
		(end 15.141448 -6.249924)
		(stroke
			(width 0.2)
			(type default)
		)
		(fill no)
		(layer "In4.Cu")
	)
	(gr_line
		(start 15.21206 -139.884912)
		(end 15.53972 -140.212572)
		(stroke
			(width 0.381)
			(type default)
		)
		(layer "In4.Cu")
	)
	(gr_line
		(start 15.21206 -136.077452)
		(end 15.21206 -139.884912)
		(stroke
			(width 0.381)
			(type default)
		)
		(layer "In4.Cu")
	)
	(gr_line
		(start 15.53972 -140.212572)
		(end 16.11884 -140.212572)
		(stroke
			(width 0.381)
			(type default)
		)
		(layer "In4.Cu")
	)
	(gr_line
		(start 16.11884 -140.212572)
		(end 16.608298 -139.723114)
		(stroke
			(width 0.381)
			(type default)
		)
		(layer "In4.Cu")
	)
	(gr_line
		(start 16.608298 -139.723114)
		(end 16.608298 -135.790178)
		(stroke
			(width 0.381)
			(type default)
		)
		(layer "In4.Cu")
	)
	(gr_line
		(start 16.608298 -135.790178)
		(end 17.935194 -134.463282)
		(stroke
			(width 0.381)
			(type default)
		)
		(layer "In4.Cu")
	)
	(gr_line
		(start 17.609566 -133.679946)
		(end 15.21206 -136.077452)
		(stroke
			(width 0.381)
			(type default)
		)
		(layer "In4.Cu")
	)
	(gr_line
		(start 17.935194 -134.463282)
		(end 26.659586 -134.463282)
		(stroke
			(width 0.381)
			(type default)
		)
		(layer "In4.Cu")
	)
	(gr_circle
		(center 26.249884 -8.750046)
		(end 27.141424 -8.750046)
		(stroke
			(width 0.2)
			(type default)
		)
		(fill no)
		(layer "In4.Cu")
	)
	(gr_line
		(start 26.659586 -134.463282)
		(end 38.331648 -146.135344)
		(stroke
			(width 0.381)
			(type default)
		)
		(layer "In4.Cu")
	)
	(gr_line
		(start 27.002994 -133.679946)
		(end 17.609566 -133.679946)
		(stroke
			(width 0.381)
			(type default)
		)
		(layer "In4.Cu")
	)
	(gr_line
		(start 28.253436 -161.407094)
		(end 28.253436 -153.901902)
		(stroke
			(width 0.381)
			(type default)
		)
		(layer "In4.Cu")
	)
	(gr_line
		(start 28.253436 -153.901902)
		(end 32.02813 -150.127208)
		(stroke
			(width 0.381)
			(type default)
		)
		(layer "In4.Cu")
	)
	(gr_arc
		(start 30.530038 -109.050074)
		(mid 30.822931 -109.757179)
		(end 31.530036 -110.050072)
		(stroke
			(width 2.54)
			(type default)
		)
		(layer "In4.Cu")
	)
	(gr_arc
		(start 30.530038 -0.999998)
		(mid 30.237147 -0.29288)
		(end 29.53004 0)
		(stroke
			(width 2.54)
			(type default)
		)
		(layer "In4.Cu")
	)
	(gr_line
		(start 30.530038 -0.999998)
		(end 30.530038 -109.050074)
		(stroke
			(width 2.54)
			(type default)
		)
		(layer "In4.Cu")
	)
	(gr_line
		(start 31.530036 -110.050072)
		(end 72.030082 -110.050072)
		(stroke
			(width 2.54)
			(type default)
		)
		(layer "In4.Cu")
	)
	(gr_line
		(start 32.02813 -150.127208)
		(end 43.613832 -150.127208)
		(stroke
			(width 0.381)
			(type default)
		)
		(layer "In4.Cu")
	)
	(gr_line
		(start 32.58439 -165.738048)
		(end 28.253436 -161.407094)
		(stroke
			(width 0.381)
			(type default)
		)
		(layer "In4.Cu")
	)
	(gr_line
		(start 36.836096 -140.66901)
		(end 36.836096 -135.833104)
		(stroke
			(width 0.381)
			(type default)
		)
		(layer "In4.Cu")
	)
	(gr_line
		(start 36.836096 -135.833104)
		(end 40.527478 -132.141722)
		(stroke
			(width 0.381)
			(type default)
		)
		(layer "In4.Cu")
	)
	(gr_line
		(start 37.56279 -141.395704)
		(end 36.836096 -140.66901)
		(stroke
			(width 0.381)
			(type default)
		)
		(layer "In4.Cu")
	)
	(gr_line
		(start 38.331648 -146.135344)
		(end 43.090338 -146.135344)
		(stroke
			(width 0.381)
			(type default)
		)
		(layer "In4.Cu")
	)
	(gr_line
		(start 38.6842 -145.361152)
		(end 27.002994 -133.679946)
		(stroke
			(width 0.381)
			(type default)
		)
		(layer "In4.Cu")
	)
	(gr_arc
		(start 40.529256 -132.14096)
		(mid 40.528302 -132.141186)
		(end 40.527478 -132.141722)
		(stroke
			(width 0.381)
			(type default)
		)
		(layer "In4.Cu")
	)
	(gr_line
		(start 40.529256 -132.14096)
		(end 72.145144 -132.14096)
		(stroke
			(width 0.381)
			(type default)
		)
		(layer "In4.Cu")
	)
	(gr_line
		(start 43.090338 -146.135344)
		(end 43.270932 -146.315938)
		(stroke
			(width 0.381)
			(type default)
		)
		(layer "In4.Cu")
	)
	(gr_line
		(start 43.270932 -147.584922)
		(end 43.48353 -147.79752)
		(stroke
			(width 0.381)
			(type default)
		)
		(layer "In4.Cu")
	)
	(gr_line
		(start 43.270932 -146.315938)
		(end 43.270932 -147.584922)
		(stroke
			(width 0.381)
			(type default)
		)
		(layer "In4.Cu")
	)
	(gr_line
		(start 43.48353 -147.79752)
		(end 44.660058 -147.79752)
		(stroke
			(width 0.381)
			(type default)
		)
		(layer "In4.Cu")
	)
	(gr_line
		(start 43.613832 -150.127208)
		(end 44.66082 -149.08022)
		(stroke
			(width 0.381)
			(type default)
		)
		(layer "In4.Cu")
	)
	(gr_line
		(start 43.870118 -141.395704)
		(end 37.56279 -141.395704)
		(stroke
			(width 0.381)
			(type default)
		)
		(layer "In4.Cu")
	)
	(gr_line
		(start 44.035472 -147.793202)
		(end 44.634658 -148.392388)
		(stroke
			(width 0.381)
			(type default)
		)
		(layer "In4.Cu")
	)
	(gr_arc
		(start 44.035472 -147.792694)
		(mid 44.035218 -147.792948)
		(end 44.035472 -147.793202)
		(stroke
			(width 0.381)
			(type default)
		)
		(layer "In4.Cu")
	)
	(gr_line
		(start 44.054268 -145.36039)
		(end 44.653454 -145.959576)
		(stroke
			(width 0.381)
			(type default)
		)
		(layer "In4.Cu")
	)
	(gr_arc
		(start 44.054268 -145.359882)
		(mid 44.054014 -145.360136)
		(end 44.054268 -145.36039)
		(stroke
			(width 0.381)
			(type default)
		)
		(layer "In4.Cu")
	)
	(gr_line
		(start 44.592494 -145.361152)
		(end 38.6842 -145.361152)
		(stroke
			(width 0.381)
			(type default)
		)
		(layer "In4.Cu")
	)
	(gr_circle
		(center 44.634404 -148.392388)
		(end 44.634658 -148.392388)
		(stroke
			(width 0.381)
			(type default)
		)
		(fill no)
		(layer "In4.Cu")
	)
	(gr_circle
		(center 44.634404 -147.193508)
		(end 44.634658 -147.193508)
		(stroke
			(width 0.381)
			(type default)
		)
		(fill no)
		(layer "In4.Cu")
	)
	(gr_line
		(start 44.634658 -147.193508)
		(end 44.035472 -147.792694)
		(stroke
			(width 0.381)
			(type default)
		)
		(layer "In4.Cu")
	)
	(gr_circle
		(center 44.6532 -145.959576)
		(end 44.653454 -145.959576)
		(stroke
			(width 0.381)
			(type default)
		)
		(fill no)
		(layer "In4.Cu")
	)
	(gr_circle
		(center 44.6532 -144.760696)
		(end 44.653454 -144.760696)
		(stroke
			(width 0.381)
			(type default)
		)
		(fill no)
		(layer "In4.Cu")
	)
	(gr_line
		(start 44.653454 -144.760696)
		(end 44.054268 -145.359882)
		(stroke
			(width 0.381)
			(type default)
		)
		(layer "In4.Cu")
	)
	(gr_line
		(start 44.66082 -149.08022)
		(end 44.66082 -142.186406)
		(stroke
			(width 0.381)
			(type default)
		)
		(layer "In4.Cu")
	)
	(gr_line
		(start 44.66082 -142.186406)
		(end 43.870118 -141.395704)
		(stroke
			(width 0.381)
			(type default)
		)
		(layer "In4.Cu")
	)
	(gr_line
		(start 65.2272 -165.738048)
		(end 32.58439 -165.738048)
		(stroke
			(width 0.381)
			(type default)
		)
		(layer "In4.Cu")
	)
	(gr_arc
		(start 72.030082 -110.050072)
		(mid 72.737187 -109.757179)
		(end 73.03008 -109.050074)
		(stroke
			(width 2.54)
			(type default)
		)
		(layer "In4.Cu")
	)
	(gr_arc
		(start 72.146922 -132.141722)
		(mid 72.146115 -132.141151)
		(end 72.145144 -132.14096)
		(stroke
			(width 0.381)
			(type default)
		)
		(layer "In4.Cu")
	)
	(gr_line
		(start 72.146922 -132.141722)
		(end 78.8162 -138.811)
		(stroke
			(width 0.381)
			(type default)
		)
		(layer "In4.Cu")
	)
	(gr_line
		(start 73.03008 -109.050074)
		(end 73.03008 -0.999998)
		(stroke
			(width 2.54)
			(type default)
		)
		(layer "In4.Cu")
	)
	(gr_arc
		(start 74.030078 0)
		(mid 73.322986 -0.2929)
		(end 73.03008 -0.999998)
		(stroke
			(width 2.54)
			(type default)
		)
		(layer "In4.Cu")
	)
	(gr_line
		(start 74.030078 0)
		(end 234.00004 0)
		(stroke
			(width 2.54)
			(type default)
		)
		(layer "In4.Cu")
	)
	(gr_arc
		(start 76.902818 -93.800168)
		(mid 77.283818 -94.181168)
		(end 77.664818 -93.800168)
		(stroke
			(width 0.2)
			(type default)
		)
		(layer "In4.Cu")
	)
	(gr_line
		(start 76.902818 -92.911168)
		(end 76.902818 -93.800168)
		(stroke
			(width 0.2)
			(type default)
		)
		(layer "In4.Cu")
	)
	(gr_arc
		(start 76.902818 -87.399368)
		(mid 77.283818 -87.780368)
		(end 77.664818 -87.399368)
		(stroke
			(width 0.2)
			(type default)
		)
		(layer "In4.Cu")
	)
	(gr_line
		(start 76.902818 -86.510368)
		(end 76.902818 -87.399368)
		(stroke
			(width 0.2)
			(type default)
		)
		(layer "In4.Cu")
	)
	(gr_arc
		(start 76.902818 -80.998568)
		(mid 77.283818 -81.379568)
		(end 77.664818 -80.998568)
		(stroke
			(width 0.2)
			(type default)
		)
		(layer "In4.Cu")
	)
	(gr_line
		(start 76.902818 -80.109568)
		(end 76.902818 -80.998568)
		(stroke
			(width 0.2)
			(type default)
		)
		(layer "In4.Cu")
	)
	(gr_arc
		(start 76.902818 -74.597768)
		(mid 77.283818 -74.978768)
		(end 77.664818 -74.597768)
		(stroke
			(width 0.2)
			(type default)
		)
		(layer "In4.Cu")
	)
	(gr_line
		(start 76.902818 -73.708768)
		(end 76.902818 -74.597768)
		(stroke
			(width 0.2)
			(type default)
		)
		(layer "In4.Cu")
	)
	(gr_arc
		(start 76.974192 -68.201032)
		(mid 77.355192 -68.582032)
		(end 77.736192 -68.201032)
		(stroke
			(width 0.2)
			(type default)
		)
		(layer "In4.Cu")
	)
	(gr_line
		(start 76.974192 -67.312032)
		(end 76.974192 -68.201032)
		(stroke
			(width 0.2)
			(type default)
		)
		(layer "In4.Cu")
	)
	(gr_line
		(start 77.293216 -1.198372)
		(end 77.677264 -1.58242)
		(stroke
			(width 0.381)
			(type default)
		)
		(layer "In4.Cu")
	)
	(gr_line
		(start 77.652118 -1.607312)
		(end 77.677264 -1.582166)
		(stroke
			(width 0.381)
			(type default)
		)
		(layer "In4.Cu")
	)
	(gr_line
		(start 77.652118 -1.557274)
		(end 77.652118 -1.607312)
		(stroke
			(width 0.381)
			(type default)
		)
		(layer "In4.Cu")
	)
	(gr_line
		(start 77.664818 -93.800168)
		(end 77.664818 -92.911422)
		(stroke
			(width 0.2)
			(type default)
		)
		(layer "In4.Cu")
	)
	(gr_arc
		(start 77.664818 -92.911422)
		(mid 77.283945 -92.530168)
		(end 76.902818 -92.911168)
		(stroke
			(width 0.2)
			(type default)
		)
		(layer "In4.Cu")
	)
	(gr_line
		(start 77.664818 -87.399368)
		(end 77.664818 -86.510622)
		(stroke
			(width 0.2)
			(type default)
		)
		(layer "In4.Cu")
	)
	(gr_arc
		(start 77.664818 -86.510622)
		(mid 77.283945 -86.129368)
		(end 76.902818 -86.510368)
		(stroke
			(width 0.2)
			(type default)
		)
		(layer "In4.Cu")
	)
	(gr_line
		(start 77.664818 -80.998568)
		(end 77.664818 -80.109822)
		(stroke
			(width 0.2)
			(type default)
		)
		(layer "In4.Cu")
	)
	(gr_arc
		(start 77.664818 -80.109822)
		(mid 77.283945 -79.728568)
		(end 76.902818 -80.109568)
		(stroke
			(width 0.2)
			(type default)
		)
		(layer "In4.Cu")
	)
	(gr_line
		(start 77.664818 -74.597768)
		(end 77.664818 -73.709022)
		(stroke
			(width 0.2)
			(type default)
		)
		(layer "In4.Cu")
	)
	(gr_arc
		(start 77.664818 -73.709022)
		(mid 77.283945 -73.327768)
		(end 76.902818 -73.708768)
		(stroke
			(width 0.2)
			(type default)
		)
		(layer "In4.Cu")
	)
	(gr_circle
		(center 77.67701 -1.58242)
		(end 77.677264 -1.58242)
		(stroke
			(width 0.381)
			(type default)
		)
		(fill no)
		(layer "In4.Cu")
	)
	(gr_line
		(start 77.677264 -30.6959)
		(end 81.552034 -34.57067)
		(stroke
			(width 0.381)
			(type default)
		)
		(layer "In4.Cu")
	)
	(gr_line
		(start 77.677264 -1.58242)
		(end 77.677264 -30.6959)
		(stroke
			(width 0.381)
			(type default)
		)
		(layer "In4.Cu")
	)
	(gr_line
		(start 77.677264 -1.582166)
		(end 77.677264 -1.58242)
		(stroke
			(width 0.381)
			(type default)
		)
		(layer "In4.Cu")
	)
	(gr_line
		(start 77.677264 -0.954024)
		(end 77.677264 -1.582166)
		(stroke
			(width 0.381)
			(type default)
		)
		(layer "In4.Cu")
	)
	(gr_circle
		(center 77.677518 -30.6959)
		(end 77.677772 -30.6959)
		(stroke
			(width 0.381)
			(type default)
		)
		(fill no)
		(layer "In4.Cu")
	)
	(gr_circle
		(center 77.677518 -1.582166)
		(end 77.677772 -1.582166)
		(stroke
			(width 0.381)
			(type default)
		)
		(fill no)
		(layer "In4.Cu")
	)
	(gr_line
		(start 77.736192 -68.201032)
		(end 77.736192 -67.312286)
		(stroke
			(width 0.2)
			(type default)
		)
		(layer "In4.Cu")
	)
	(gr_arc
		(start 77.736192 -67.312286)
		(mid 77.355319 -66.931032)
		(end 76.974192 -67.312032)
		(stroke
			(width 0.2)
			(type default)
		)
		(layer "In4.Cu")
	)
	(gr_arc
		(start 77.741018 -90.599768)
		(mid 78.122018 -90.980768)
		(end 78.503018 -90.599768)
		(stroke
			(width 0.2)
			(type default)
		)
		(layer "In4.Cu")
	)
	(gr_line
		(start 77.741018 -89.710768)
		(end 77.741018 -90.599768)
		(stroke
			(width 0.2)
			(type default)
		)
		(layer "In4.Cu")
	)
	(gr_arc
		(start 77.741018 -84.198968)
		(mid 78.122018 -84.579968)
		(end 78.503018 -84.198968)
		(stroke
			(width 0.2)
			(type default)
		)
		(layer "In4.Cu")
	)
	(gr_line
		(start 77.741018 -83.309968)
		(end 77.741018 -84.198968)
		(stroke
			(width 0.2)
			(type default)
		)
		(layer "In4.Cu")
	)
	(gr_arc
		(start 77.741018 -77.798168)
		(mid 78.122018 -78.179168)
		(end 78.503018 -77.798168)
		(stroke
			(width 0.2)
			(type default)
		)
		(layer "In4.Cu")
	)
	(gr_line
		(start 77.741018 -76.909168)
		(end 77.741018 -77.798168)
		(stroke
			(width 0.2)
			(type default)
		)
		(layer "In4.Cu")
	)
	(gr_arc
		(start 77.741018 -71.397368)
		(mid 78.122018 -71.778368)
		(end 78.503018 -71.397368)
		(stroke
			(width 0.2)
			(type default)
		)
		(layer "In4.Cu")
	)
	(gr_line
		(start 77.741018 -70.508368)
		(end 77.741018 -71.397368)
		(stroke
			(width 0.2)
			(type default)
		)
		(layer "In4.Cu")
	)
	(gr_line
		(start 78.048866 -1.210564)
		(end 77.677264 -1.582166)
		(stroke
			(width 0.381)
			(type default)
		)
		(layer "In4.Cu")
	)
	(gr_line
		(start 78.503018 -90.599768)
		(end 78.503018 -89.711022)
		(stroke
			(width 0.2)
			(type default)
		)
		(layer "In4.Cu")
	)
	(gr_arc
		(start 78.503018 -89.711022)
		(mid 78.122145 -89.329768)
		(end 77.741018 -89.710768)
		(stroke
			(width 0.2)
			(type default)
		)
		(layer "In4.Cu")
	)
	(gr_line
		(start 78.503018 -84.198968)
		(end 78.503018 -83.310222)
		(stroke
			(width 0.2)
			(type default)
		)
		(layer "In4.Cu")
	)
	(gr_arc
		(start 78.503018 -83.310222)
		(mid 78.122145 -82.928968)
		(end 77.741018 -83.309968)
		(stroke
			(width 0.2)
			(type default)
		)
		(layer "In4.Cu")
	)
	(gr_line
		(start 78.503018 -77.798168)
		(end 78.503018 -76.909422)
		(stroke
			(width 0.2)
			(type default)
		)
		(layer "In4.Cu")
	)
	(gr_arc
		(start 78.503018 -76.909422)
		(mid 78.122145 -76.528168)
		(end 77.741018 -76.909168)
		(stroke
			(width 0.2)
			(type default)
		)
		(layer "In4.Cu")
	)
	(gr_line
		(start 78.503018 -71.397368)
		(end 78.503018 -70.508622)
		(stroke
			(width 0.2)
			(type default)
		)
		(layer "In4.Cu")
	)
	(gr_arc
		(start 78.503018 -70.508622)
		(mid 78.122145 -70.127368)
		(end 77.741018 -70.508368)
		(stroke
			(width 0.2)
			(type default)
		)
		(layer "In4.Cu")
	)
	(gr_line
		(start 78.8162 -152.149048)
		(end 65.2272 -165.738048)
		(stroke
			(width 0.381)
			(type default)
		)
		(layer "In4.Cu")
	)
	(gr_line
		(start 78.8162 -138.811)
		(end 78.8162 -152.149048)
		(stroke
			(width 0.381)
			(type default)
		)
		(layer "In4.Cu")
	)
	(gr_line
		(start 80.408526 -50.774346)
		(end 81.092802 -51.458622)
		(stroke
			(width 0.381)
			(type default)
		)
		(layer "In4.Cu")
	)
	(gr_line
		(start 80.408526 -43.08602)
		(end 80.408526 -50.774346)
		(stroke
			(width 0.381)
			(type default)
		)
		(layer "In4.Cu")
	)
	(gr_circle
		(center 80.40878 -50.774346)
		(end 80.409034 -50.774346)
		(stroke
			(width 0.381)
			(type default)
		)
		(fill no)
		(layer "In4.Cu")
	)
	(gr_line
		(start 81.092802 -51.458622)
		(end 86.462108 -51.458622)
		(stroke
			(width 0.381)
			(type default)
		)
		(layer "In4.Cu")
	)
	(gr_line
		(start 81.552034 -41.942512)
		(end 80.408526 -43.08602)
		(stroke
			(width 0.381)
			(type default)
		)
		(layer "In4.Cu")
	)
	(gr_line
		(start 81.552034 -34.57067)
		(end 81.552034 -41.942512)
		(stroke
			(width 0.381)
			(type default)
		)
		(layer "In4.Cu")
	)
	(gr_arc
		(start 82.977228 -95.381572)
		(mid 83.358228 -95.762572)
		(end 83.739228 -95.381572)
		(stroke
			(width 0.2)
			(type default)
		)
		(layer "In4.Cu")
	)
	(gr_line
		(start 82.977228 -94.492572)
		(end 82.977228 -95.381572)
		(stroke
			(width 0.2)
			(type default)
		)
		(layer "In4.Cu")
	)
	(gr_arc
		(start 82.977228 -82.581496)
		(mid 83.358228 -82.962496)
		(end 83.739228 -82.581496)
		(stroke
			(width 0.2)
			(type default)
		)
		(layer "In4.Cu")
	)
	(gr_line
		(start 82.977228 -81.692496)
		(end 82.977228 -82.581496)
		(stroke
			(width 0.2)
			(type default)
		)
		(layer "In4.Cu")
	)
	(gr_arc
		(start 82.977228 -76.194158)
		(mid 83.358228 -76.575158)
		(end 83.739228 -76.194158)
		(stroke
			(width 0.2)
			(type default)
		)
		(layer "In4.Cu")
	)
	(gr_line
		(start 82.977228 -75.305158)
		(end 82.977228 -76.194158)
		(stroke
			(width 0.2)
			(type default)
		)
		(layer "In4.Cu")
	)
	(gr_arc
		(start 82.978498 -88.980264)
		(mid 83.359498 -89.361264)
		(end 83.740498 -88.980264)
		(stroke
			(width 0.2)
			(type default)
		)
		(layer "In4.Cu")
	)
	(gr_line
		(start 82.978498 -88.091264)
		(end 82.978498 -88.980264)
		(stroke
			(width 0.2)
			(type default)
		)
		(layer "In4.Cu")
	)
	(gr_line
		(start 83.739228 -95.381572)
		(end 83.739228 -94.492826)
		(stroke
			(width 0.2)
			(type default)
		)
		(layer "In4.Cu")
	)
	(gr_arc
		(start 83.739228 -94.492826)
		(mid 83.358355 -94.111572)
		(end 82.977228 -94.492572)
		(stroke
			(width 0.2)
			(type default)
		)
		(layer "In4.Cu")
	)
	(gr_line
		(start 83.739228 -82.581496)
		(end 83.739228 -81.69275)
		(stroke
			(width 0.2)
			(type default)
		)
		(layer "In4.Cu")
	)
	(gr_arc
		(start 83.739228 -81.69275)
		(mid 83.358355 -81.311496)
		(end 82.977228 -81.692496)
		(stroke
			(width 0.2)
			(type default)
		)
		(layer "In4.Cu")
	)
	(gr_line
		(start 83.739228 -76.194158)
		(end 83.739228 -75.305412)
		(stroke
			(width 0.2)
			(type default)
		)
		(layer "In4.Cu")
	)
	(gr_arc
		(start 83.739228 -75.305412)
		(mid 83.358355 -74.924158)
		(end 82.977228 -75.305158)
		(stroke
			(width 0.2)
			(type default)
		)
		(layer "In4.Cu")
	)
	(gr_line
		(start 83.740498 -88.980264)
		(end 83.740498 -88.091518)
		(stroke
			(width 0.2)
			(type default)
		)
		(layer "In4.Cu")
	)
	(gr_arc
		(start 83.740498 -88.091518)
		(mid 83.359625 -87.710264)
		(end 82.978498 -88.091264)
		(stroke
			(width 0.2)
			(type default)
		)
		(layer "In4.Cu")
	)
	(gr_arc
		(start 84.482178 -72.987916)
		(mid 84.863178 -73.368916)
		(end 85.244178 -72.987916)
		(stroke
			(width 0.2)
			(type default)
		)
		(layer "In4.Cu")
	)
	(gr_line
		(start 84.482178 -72.098916)
		(end 84.482178 -72.987916)
		(stroke
			(width 0.2)
			(type default)
		)
		(layer "In4.Cu")
	)
	(gr_arc
		(start 84.602828 -92.195396)
		(mid 84.983828 -92.576396)
		(end 85.364828 -92.195396)
		(stroke
			(width 0.2)
			(type default)
		)
		(layer "In4.Cu")
	)
	(gr_line
		(start 84.602828 -91.306396)
		(end 84.602828 -92.195396)
		(stroke
			(width 0.2)
			(type default)
		)
		(layer "In4.Cu")
	)
	(gr_arc
		(start 84.602828 -85.781134)
		(mid 84.983828 -86.162134)
		(end 85.364828 -85.781134)
		(stroke
			(width 0.2)
			(type default)
		)
		(layer "In4.Cu")
	)
	(gr_line
		(start 84.602828 -84.892134)
		(end 84.602828 -85.781134)
		(stroke
			(width 0.2)
			(type default)
		)
		(layer "In4.Cu")
	)
	(gr_arc
		(start 84.605622 -79.396336)
		(mid 84.986622 -79.777336)
		(end 85.367622 -79.396336)
		(stroke
			(width 0.2)
			(type default)
		)
		(layer "In4.Cu")
	)
	(gr_line
		(start 84.605622 -78.507336)
		(end 84.605622 -79.396336)
		(stroke
			(width 0.2)
			(type default)
		)
		(layer "In4.Cu")
	)
	(gr_line
		(start 84.679282 -27.142948)
		(end 84.679282 -11.303508)
		(stroke
			(width 0.381)
			(type default)
		)
		(layer "In4.Cu")
	)
	(gr_line
		(start 84.679282 -11.303508)
		(end 89.968324 -6.014466)
		(stroke
			(width 0.381)
			(type default)
		)
		(layer "In4.Cu")
	)
	(gr_circle
		(center 84.679536 -27.142948)
		(end 84.67979 -27.142948)
		(stroke
			(width 0.381)
			(type default)
		)
		(fill no)
		(layer "In4.Cu")
	)
	(gr_line
		(start 85.244178 -72.987916)
		(end 85.244178 -72.09917)
		(stroke
			(width 0.2)
			(type default)
		)
		(layer "In4.Cu")
	)
	(gr_arc
		(start 85.244178 -72.09917)
		(mid 84.863305 -71.717916)
		(end 84.482178 -72.098916)
		(stroke
			(width 0.2)
			(type default)
		)
		(layer "In4.Cu")
	)
	(gr_line
		(start 85.364828 -92.195396)
		(end 85.364828 -91.30665)
		(stroke
			(width 0.2)
			(type default)
		)
		(layer "In4.Cu")
	)
	(gr_arc
		(start 85.364828 -91.30665)
		(mid 84.983955 -90.925396)
		(end 84.602828 -91.306396)
		(stroke
			(width 0.2)
			(type default)
		)
		(layer "In4.Cu")
	)
	(gr_line
		(start 85.364828 -85.781134)
		(end 85.364828 -84.892388)
		(stroke
			(width 0.2)
			(type default)
		)
		(layer "In4.Cu")
	)
	(gr_arc
		(start 85.364828 -84.892388)
		(mid 84.983955 -84.511134)
		(end 84.602828 -84.892134)
		(stroke
			(width 0.2)
			(type default)
		)
		(layer "In4.Cu")
	)
	(gr_line
		(start 85.367622 -79.396336)
		(end 85.367622 -78.50759)
		(stroke
			(width 0.2)
			(type default)
		)
		(layer "In4.Cu")
	)
	(gr_arc
		(start 85.367622 -78.50759)
		(mid 84.986749 -78.126336)
		(end 84.605622 -78.507336)
		(stroke
			(width 0.2)
			(type default)
		)
		(layer "In4.Cu")
	)
	(gr_line
		(start 86.462108 -51.458622)
		(end 87.932006 -49.988724)
		(stroke
			(width 0.381)
			(type default)
		)
		(layer "In4.Cu")
	)
	(gr_circle
		(center 86.462108 -51.458368)
		(end 86.462362 -51.458368)
		(stroke
			(width 0.381)
			(type default)
		)
		(fill no)
		(layer "In4.Cu")
	)
	(gr_line
		(start 87.80145 -30.265116)
		(end 84.679282 -27.142948)
		(stroke
			(width 0.381)
			(type default)
		)
		(layer "In4.Cu")
	)
	(gr_circle
		(center 87.931752 -49.988724)
		(end 87.932006 -49.988724)
		(stroke
			(width 0.381)
			(type default)
		)
		(fill no)
		(layer "In4.Cu")
	)
	(gr_line
		(start 87.932006 -49.988724)
		(end 87.932006 -44.066968)
		(stroke
			(width 0.381)
			(type default)
		)
		(layer "In4.Cu")
	)
	(gr_line
		(start 87.932006 -44.066968)
		(end 89.405968 -42.593006)
		(stroke
			(width 0.381)
			(type default)
		)
		(layer "In4.Cu")
	)
	(gr_line
		(start 89.405968 -42.593006)
		(end 89.405968 -36.975288)
		(stroke
			(width 0.381)
			(type default)
		)
		(layer "In4.Cu")
	)
	(gr_line
		(start 89.405968 -36.975288)
		(end 93.547438 -32.833818)
		(stroke
			(width 0.381)
			(type default)
		)
		(layer "In4.Cu")
	)
	(gr_line
		(start 89.968324 -6.014466)
		(end 150.55342 -6.014466)
		(stroke
			(width 0.381)
			(type default)
		)
		(layer "In4.Cu")
	)
	(gr_line
		(start 92.366084 -30.265116)
		(end 87.80145 -30.265116)
		(stroke
			(width 0.381)
			(type default)
		)
		(layer "In4.Cu")
	)
	(gr_line
		(start 93.547438 -32.833818)
		(end 93.547438 -31.44647)
		(stroke
			(width 0.381)
			(type default)
		)
		(layer "In4.Cu")
	)
	(gr_line
		(start 93.547438 -31.44647)
		(end 92.366084 -30.265116)
		(stroke
			(width 0.381)
			(type default)
		)
		(layer "In4.Cu")
	)
	(gr_line
		(start 98.081846 -194.00012)
		(end 5.617972 -194.00012)
		(stroke
			(width 2.54)
			(type default)
		)
		(layer "In4.Cu")
	)
	(gr_arc
		(start 98.081846 -194.00012)
		(mid 98.607706 -193.850755)
		(end 98.976434 -193.447162)
		(stroke
			(width 2.54)
			(type default)
		)
		(layer "In4.Cu")
	)
	(gr_line
		(start 103.594408 -184.211214)
		(end 98.976434 -193.447162)
		(stroke
			(width 2.54)
			(type default)
		)
		(layer "In4.Cu")
	)
	(gr_arc
		(start 103.594408 -184.211214)
		(mid 103.673311 -183.993725)
		(end 103.700072 -183.76392)
		(stroke
			(width 2.54)
			(type default)
		)
		(layer "In4.Cu")
	)
	(gr_line
		(start 103.700072 -47.999904)
		(end 103.700072 -183.76392)
		(stroke
			(width 2.54)
			(type default)
		)
		(layer "In4.Cu")
	)
	(gr_arc
		(start 104.70007 -47.999904)
		(mid 104.200198 -47.500032)
		(end 103.700072 -47.999904)
		(stroke
			(width 2.54)
			(type default)
		)
		(layer "In4.Cu")
	)
	(gr_arc
		(start 106.614722 -38.199822)
		(mid 107.099735 -38.685216)
		(end 107.585002 -38.200076)
		(stroke
			(width 0.2)
			(type default)
		)
		(layer "In4.Cu")
	)
	(gr_line
		(start 106.614722 -36.800028)
		(end 106.614722 -38.199822)
		(stroke
			(width 0.2)
			(type default)
		)
		(layer "In4.Cu")
	)
	(gr_arc
		(start 106.614722 -34.600134)
		(mid 107.099862 -35.085274)
		(end 107.585002 -34.600134)
		(stroke
			(width 0.2)
			(type default)
		)
		(layer "In4.Cu")
	)
	(gr_line
		(start 106.614722 -33.200086)
		(end 106.614722 -34.600134)
		(stroke
			(width 0.2)
			(type default)
		)
		(layer "In4.Cu")
	)
	(gr_line
		(start 107.585002 -38.200076)
		(end 107.585002 -36.800028)
		(stroke
			(width 0.2)
			(type default)
		)
		(layer "In4.Cu")
	)
	(gr_arc
		(start 107.585002 -36.800028)
		(mid 107.099862 -36.314888)
		(end 106.614722 -36.800028)
		(stroke
			(width 0.2)
			(type default)
		)
		(layer "In4.Cu")
	)
	(gr_line
		(start 107.585002 -34.600134)
		(end 107.585002 -33.20034)
		(stroke
			(width 0.2)
			(type default)
		)
		(layer "In4.Cu")
	)
	(gr_arc
		(start 107.585002 -33.20034)
		(mid 107.099989 -32.714946)
		(end 106.614722 -33.200086)
		(stroke
			(width 0.2)
			(type default)
		)
		(layer "In4.Cu")
	)
	(gr_arc
		(start 108.41482 -36.999926)
		(mid 108.899833 -37.48532)
		(end 109.3851 -37.00018)
		(stroke
			(width 0.2)
			(type default)
		)
		(layer "In4.Cu")
	)
	(gr_line
		(start 108.41482 -35.600132)
		(end 108.41482 -36.999926)
		(stroke
			(width 0.2)
			(type default)
		)
		(layer "In4.Cu")
	)
	(gr_arc
		(start 108.41482 -33.39973)
		(mid 108.899833 -33.885124)
		(end 109.3851 -33.399984)
		(stroke
			(width 0.2)
			(type default)
		)
		(layer "In4.Cu")
	)
	(gr_line
		(start 108.41482 -32.00019)
		(end 108.41482 -33.39973)
		(stroke
			(width 0.2)
			(type default)
		)
		(layer "In4.Cu")
	)
	(gr_line
		(start 109.3851 -37.00018)
		(end 109.3851 -35.600132)
		(stroke
			(width 0.2)
			(type default)
		)
		(layer "In4.Cu")
	)
	(gr_arc
		(start 109.3851 -35.600132)
		(mid 108.89996 -35.114992)
		(end 108.41482 -35.600132)
		(stroke
			(width 0.2)
			(type default)
		)
		(layer "In4.Cu")
	)
	(gr_line
		(start 109.3851 -33.399984)
		(end 109.3851 -32.00019)
		(stroke
			(width 0.2)
			(type default)
		)
		(layer "In4.Cu")
	)
	(gr_arc
		(start 109.3851 -32.00019)
		(mid 108.89996 -31.51505)
		(end 108.41482 -32.00019)
		(stroke
			(width 0.2)
			(type default)
		)
		(layer "In4.Cu")
	)
	(gr_arc
		(start 110.214918 -38.199822)
		(mid 110.699931 -38.685216)
		(end 111.185198 -38.200076)
		(stroke
			(width 0.2)
			(type default)
		)
		(layer "In4.Cu")
	)
	(gr_line
		(start 110.214918 -36.800028)
		(end 110.214918 -38.199822)
		(stroke
			(width 0.2)
			(type default)
		)
		(layer "In4.Cu")
	)
	(gr_arc
		(start 110.214918 -34.600134)
		(mid 110.700058 -35.085274)
		(end 111.185198 -34.600134)
		(stroke
			(width 0.2)
			(type default)
		)
		(layer "In4.Cu")
	)
	(gr_line
		(start 110.214918 -33.200086)
		(end 110.214918 -34.600134)
		(stroke
			(width 0.2)
			(type default)
		)
		(layer "In4.Cu")
	)
	(gr_line
		(start 111.185198 -38.200076)
		(end 111.185198 -36.800028)
		(stroke
			(width 0.2)
			(type default)
		)
		(layer "In4.Cu")
	)
	(gr_arc
		(start 111.185198 -36.800028)
		(mid 110.700058 -36.314888)
		(end 110.214918 -36.800028)
		(stroke
			(width 0.2)
			(type default)
		)
		(layer "In4.Cu")
	)
	(gr_line
		(start 111.185198 -34.600134)
		(end 111.185198 -33.20034)
		(stroke
			(width 0.2)
			(type default)
		)
		(layer "In4.Cu")
	)
	(gr_arc
		(start 111.185198 -33.20034)
		(mid 110.700185 -32.714946)
		(end 110.214918 -33.200086)
		(stroke
			(width 0.2)
			(type default)
		)
		(layer "In4.Cu")
	)
	(gr_arc
		(start 112.014762 -36.999926)
		(mid 112.499775 -37.48532)
		(end 112.985042 -37.00018)
		(stroke
			(width 0.2)
			(type default)
		)
		(layer "In4.Cu")
	)
	(gr_line
		(start 112.014762 -35.600132)
		(end 112.014762 -36.999926)
		(stroke
			(width 0.2)
			(type default)
		)
		(layer "In4.Cu")
	)
	(gr_arc
		(start 112.014762 -33.39973)
		(mid 112.499775 -33.885124)
		(end 112.985042 -33.399984)
		(stroke
			(width 0.2)
			(type default)
		)
		(layer "In4.Cu")
	)
	(gr_line
		(start 112.014762 -32.00019)
		(end 112.014762 -33.39973)
		(stroke
			(width 0.2)
			(type default)
		)
		(layer "In4.Cu")
	)
	(gr_line
		(start 112.985042 -37.00018)
		(end 112.985042 -35.600132)
		(stroke
			(width 0.2)
			(type default)
		)
		(layer "In4.Cu")
	)
	(gr_arc
		(start 112.985042 -35.600132)
		(mid 112.499902 -35.114992)
		(end 112.014762 -35.600132)
		(stroke
			(width 0.2)
			(type default)
		)
		(layer "In4.Cu")
	)
	(gr_line
		(start 112.985042 -33.399984)
		(end 112.985042 -32.00019)
		(stroke
			(width 0.2)
			(type default)
		)
		(layer "In4.Cu")
	)
	(gr_arc
		(start 112.985042 -32.00019)
		(mid 112.499902 -31.51505)
		(end 112.014762 -32.00019)
		(stroke
			(width 0.2)
			(type default)
		)
		(layer "In4.Cu")
	)
	(gr_arc
		(start 113.81486 -38.199822)
		(mid 114.299873 -38.685216)
		(end 114.78514 -38.200076)
		(stroke
			(width 0.2)
			(type default)
		)
		(layer "In4.Cu")
	)
	(gr_line
		(start 113.81486 -36.800028)
		(end 113.81486 -38.199822)
		(stroke
			(width 0.2)
			(type default)
		)
		(layer "In4.Cu")
	)
	(gr_arc
		(start 113.81486 -34.600134)
		(mid 114.3 -35.085274)
		(end 114.78514 -34.600134)
		(stroke
			(width 0.2)
			(type default)
		)
		(layer "In4.Cu")
	)
	(gr_line
		(start 113.81486 -33.200086)
		(end 113.81486 -34.600134)
		(stroke
			(width 0.2)
			(type default)
		)
		(layer "In4.Cu")
	)
	(gr_line
		(start 114.78514 -38.200076)
		(end 114.78514 -36.800028)
		(stroke
			(width 0.2)
			(type default)
		)
		(layer "In4.Cu")
	)
	(gr_arc
		(start 114.78514 -36.800028)
		(mid 114.3 -36.314888)
		(end 113.81486 -36.800028)
		(stroke
			(width 0.2)
			(type default)
		)
		(layer "In4.Cu")
	)
	(gr_line
		(start 114.78514 -34.600134)
		(end 114.78514 -33.20034)
		(stroke
			(width 0.2)
			(type default)
		)
		(layer "In4.Cu")
	)
	(gr_arc
		(start 114.78514 -33.20034)
		(mid 114.300127 -32.714946)
		(end 113.81486 -33.200086)
		(stroke
			(width 0.2)
			(type default)
		)
		(layer "In4.Cu")
	)
	(gr_arc
		(start 115.614704 -36.999926)
		(mid 116.099717 -37.48532)
		(end 116.584984 -37.00018)
		(stroke
			(width 0.2)
			(type default)
		)
		(layer "In4.Cu")
	)
	(gr_line
		(start 115.614704 -35.600132)
		(end 115.614704 -36.999926)
		(stroke
			(width 0.2)
			(type default)
		)
		(layer "In4.Cu")
	)
	(gr_arc
		(start 115.614704 -33.39973)
		(mid 116.099717 -33.885124)
		(end 116.584984 -33.399984)
		(stroke
			(width 0.2)
			(type default)
		)
		(layer "In4.Cu")
	)
	(gr_line
		(start 115.614704 -32.00019)
		(end 115.614704 -33.39973)
		(stroke
			(width 0.2)
			(type default)
		)
		(layer "In4.Cu")
	)
	(gr_line
		(start 116.584984 -37.00018)
		(end 116.584984 -35.600132)
		(stroke
			(width 0.2)
			(type default)
		)
		(layer "In4.Cu")
	)
	(gr_arc
		(start 116.584984 -35.600132)
		(mid 116.099844 -35.114992)
		(end 115.614704 -35.600132)
		(stroke
			(width 0.2)
			(type default)
		)
		(layer "In4.Cu")
	)
	(gr_line
		(start 116.584984 -33.399984)
		(end 116.584984 -32.00019)
		(stroke
			(width 0.2)
			(type default)
		)
		(layer "In4.Cu")
	)
	(gr_arc
		(start 116.584984 -32.00019)
		(mid 116.099844 -31.51505)
		(end 115.614704 -32.00019)
		(stroke
			(width 0.2)
			(type default)
		)
		(layer "In4.Cu")
	)
	(gr_arc
		(start 117.414802 -38.199822)
		(mid 117.899815 -38.685216)
		(end 118.385082 -38.200076)
		(stroke
			(width 0.2)
			(type default)
		)
		(layer "In4.Cu")
	)
	(gr_line
		(start 117.414802 -36.800028)
		(end 117.414802 -38.199822)
		(stroke
			(width 0.2)
			(type default)
		)
		(layer "In4.Cu")
	)
	(gr_arc
		(start 117.414802 -34.600134)
		(mid 117.899942 -35.085274)
		(end 118.385082 -34.600134)
		(stroke
			(width 0.2)
			(type default)
		)
		(layer "In4.Cu")
	)
	(gr_line
		(start 117.414802 -33.200086)
		(end 117.414802 -34.600134)
		(stroke
			(width 0.2)
			(type default)
		)
		(layer "In4.Cu")
	)
	(gr_line
		(start 118.385082 -38.200076)
		(end 118.385082 -36.800028)
		(stroke
			(width 0.2)
			(type default)
		)
		(layer "In4.Cu")
	)
	(gr_arc
		(start 118.385082 -36.800028)
		(mid 117.899942 -36.314888)
		(end 117.414802 -36.800028)
		(stroke
			(width 0.2)
			(type default)
		)
		(layer "In4.Cu")
	)
	(gr_line
		(start 118.385082 -34.600134)
		(end 118.385082 -33.20034)
		(stroke
			(width 0.2)
			(type default)
		)
		(layer "In4.Cu")
	)
	(gr_arc
		(start 118.385082 -33.20034)
		(mid 117.900069 -32.714946)
		(end 117.414802 -33.200086)
		(stroke
			(width 0.2)
			(type default)
		)
		(layer "In4.Cu")
	)
	(gr_arc
		(start 119.2149 -44.19981)
		(mid 119.699913 -44.685204)
		(end 120.18518 -44.200064)
		(stroke
			(width 0.2)
			(type default)
		)
		(layer "In4.Cu")
	)
	(gr_line
		(start 119.2149 -42.800016)
		(end 119.2149 -44.19981)
		(stroke
			(width 0.2)
			(type default)
		)
		(layer "In4.Cu")
	)
	(gr_arc
		(start 119.2149 -36.999926)
		(mid 119.699913 -37.48532)
		(end 120.18518 -37.00018)
		(stroke
			(width 0.2)
			(type default)
		)
		(layer "In4.Cu")
	)
	(gr_line
		(start 119.2149 -35.600132)
		(end 119.2149 -36.999926)
		(stroke
			(width 0.2)
			(type default)
		)
		(layer "In4.Cu")
	)
	(gr_arc
		(start 119.2149 -33.39973)
		(mid 119.699913 -33.885124)
		(end 120.18518 -33.399984)
		(stroke
			(width 0.2)
			(type default)
		)
		(layer "In4.Cu")
	)
	(gr_line
		(start 119.2149 -32.00019)
		(end 119.2149 -33.39973)
		(stroke
			(width 0.2)
			(type default)
		)
		(layer "In4.Cu")
	)
	(gr_line
		(start 120.18518 -44.200064)
		(end 120.18518 -42.800016)
		(stroke
			(width 0.2)
			(type default)
		)
		(layer "In4.Cu")
	)
	(gr_arc
		(start 120.18518 -42.800016)
		(mid 119.70004 -42.314876)
		(end 119.2149 -42.800016)
		(stroke
			(width 0.2)
			(type default)
		)
		(layer "In4.Cu")
	)
	(gr_line
		(start 120.18518 -37.00018)
		(end 120.18518 -35.600132)
		(stroke
			(width 0.2)
			(type default)
		)
		(layer "In4.Cu")
	)
	(gr_arc
		(start 120.18518 -35.600132)
		(mid 119.70004 -35.114992)
		(end 119.2149 -35.600132)
		(stroke
			(width 0.2)
			(type default)
		)
		(layer "In4.Cu")
	)
	(gr_line
		(start 120.18518 -33.399984)
		(end 120.18518 -32.00019)
		(stroke
			(width 0.2)
			(type default)
		)
		(layer "In4.Cu")
	)
	(gr_arc
		(start 120.18518 -32.00019)
		(mid 119.70004 -31.51505)
		(end 119.2149 -32.00019)
		(stroke
			(width 0.2)
			(type default)
		)
		(layer "In4.Cu")
	)
	(gr_arc
		(start 128.214882 -38.199822)
		(mid 128.699895 -38.685216)
		(end 129.185162 -38.200076)
		(stroke
			(width 0.2)
			(type default)
		)
		(layer "In4.Cu")
	)
	(gr_line
		(start 128.214882 -36.800028)
		(end 128.214882 -38.199822)
		(stroke
			(width 0.2)
			(type default)
		)
		(layer "In4.Cu")
	)
	(gr_arc
		(start 128.214882 -34.600134)
		(mid 128.700022 -35.085274)
		(end 129.185162 -34.600134)
		(stroke
			(width 0.2)
			(type default)
		)
		(layer "In4.Cu")
	)
	(gr_line
		(start 128.214882 -33.200086)
		(end 128.214882 -34.600134)
		(stroke
			(width 0.2)
			(type default)
		)
		(layer "In4.Cu")
	)
	(gr_line
		(start 128.467866 -26.592276)
		(end 129.53492 -26.592276)
		(stroke
			(width 0.2)
			(type default)
		)
		(layer "In4.Cu")
	)
	(gr_arc
		(start 128.467866 -25.830276)
		(mid 128.086866 -26.211276)
		(end 128.467866 -26.592276)
		(stroke
			(width 0.2)
			(type default)
		)
		(layer "In4.Cu")
	)
	(gr_line
		(start 129.185162 -38.200076)
		(end 129.185162 -36.800028)
		(stroke
			(width 0.2)
			(type default)
		)
		(layer "In4.Cu")
	)
	(gr_arc
		(start 129.185162 -36.800028)
		(mid 128.700022 -36.314888)
		(end 128.214882 -36.800028)
		(stroke
			(width 0.2)
			(type default)
		)
		(layer "In4.Cu")
	)
	(gr_line
		(start 129.185162 -34.600134)
		(end 129.185162 -33.20034)
		(stroke
			(width 0.2)
			(type default)
		)
		(layer "In4.Cu")
	)
	(gr_arc
		(start 129.185162 -33.20034)
		(mid 128.700149 -32.714946)
		(end 128.214882 -33.200086)
		(stroke
			(width 0.2)
			(type default)
		)
		(layer "In4.Cu")
	)
	(gr_arc
		(start 129.53492 -26.592276)
		(mid 129.916174 -26.211403)
		(end 129.535174 -25.830276)
		(stroke
			(width 0.2)
			(type default)
		)
		(layer "In4.Cu")
	)
	(gr_line
		(start 129.535174 -25.830276)
		(end 128.467866 -25.830276)
		(stroke
			(width 0.2)
			(type default)
		)
		(layer "In4.Cu")
	)
	(gr_arc
		(start 130.014726 -36.999926)
		(mid 130.499739 -37.48532)
		(end 130.985006 -37.00018)
		(stroke
			(width 0.2)
			(type default)
		)
		(layer "In4.Cu")
	)
	(gr_line
		(start 130.014726 -35.600132)
		(end 130.014726 -36.999926)
		(stroke
			(width 0.2)
			(type default)
		)
		(layer "In4.Cu")
	)
	(gr_arc
		(start 130.014726 -33.39973)
		(mid 130.499739 -33.885124)
		(end 130.985006 -33.399984)
		(stroke
			(width 0.2)
			(type default)
		)
		(layer "In4.Cu")
	)
	(gr_line
		(start 130.014726 -32.00019)
		(end 130.014726 -33.39973)
		(stroke
			(width 0.2)
			(type default)
		)
		(layer "In4.Cu")
	)
	(gr_line
		(start 130.985006 -37.00018)
		(end 130.985006 -35.600132)
		(stroke
			(width 0.2)
			(type default)
		)
		(layer "In4.Cu")
	)
	(gr_arc
		(start 130.985006 -35.600132)
		(mid 130.499866 -35.114992)
		(end 130.014726 -35.600132)
		(stroke
			(width 0.2)
			(type default)
		)
		(layer "In4.Cu")
	)
	(gr_line
		(start 130.985006 -33.399984)
		(end 130.985006 -32.00019)
		(stroke
			(width 0.2)
			(type default)
		)
		(layer "In4.Cu")
	)
	(gr_arc
		(start 130.985006 -32.00019)
		(mid 130.499866 -31.51505)
		(end 130.014726 -32.00019)
		(stroke
			(width 0.2)
			(type default)
		)
		(layer "In4.Cu")
	)
	(gr_arc
		(start 131.814824 -38.199822)
		(mid 132.299837 -38.685216)
		(end 132.785104 -38.200076)
		(stroke
			(width 0.2)
			(type default)
		)
		(layer "In4.Cu")
	)
	(gr_line
		(start 131.814824 -36.800028)
		(end 131.814824 -38.199822)
		(stroke
			(width 0.2)
			(type default)
		)
		(layer "In4.Cu")
	)
	(gr_arc
		(start 131.814824 -34.600134)
		(mid 132.299964 -35.085274)
		(end 132.785104 -34.600134)
		(stroke
			(width 0.2)
			(type default)
		)
		(layer "In4.Cu")
	)
	(gr_line
		(start 131.814824 -33.200086)
		(end 131.814824 -34.600134)
		(stroke
			(width 0.2)
			(type default)
		)
		(layer "In4.Cu")
	)
	(gr_line
		(start 132.785104 -38.200076)
		(end 132.785104 -36.800028)
		(stroke
			(width 0.2)
			(type default)
		)
		(layer "In4.Cu")
	)
	(gr_arc
		(start 132.785104 -36.800028)
		(mid 132.299964 -36.314888)
		(end 131.814824 -36.800028)
		(stroke
			(width 0.2)
			(type default)
		)
		(layer "In4.Cu")
	)
	(gr_line
		(start 132.785104 -34.600134)
		(end 132.785104 -33.20034)
		(stroke
			(width 0.2)
			(type default)
		)
		(layer "In4.Cu")
	)
	(gr_arc
		(start 132.785104 -33.20034)
		(mid 132.300091 -32.714946)
		(end 131.814824 -33.200086)
		(stroke
			(width 0.2)
			(type default)
		)
		(layer "In4.Cu")
	)
	(gr_arc
		(start 133.614922 -44.19981)
		(mid 134.099935 -44.685204)
		(end 134.585202 -44.200064)
		(stroke
			(width 0.2)
			(type default)
		)
		(layer "In4.Cu")
	)
	(gr_line
		(start 133.614922 -42.800016)
		(end 133.614922 -44.19981)
		(stroke
			(width 0.2)
			(type default)
		)
		(layer "In4.Cu")
	)
	(gr_arc
		(start 133.614922 -36.999926)
		(mid 134.099935 -37.48532)
		(end 134.585202 -37.00018)
		(stroke
			(width 0.2)
			(type default)
		)
		(layer "In4.Cu")
	)
	(gr_line
		(start 133.614922 -35.600132)
		(end 133.614922 -36.999926)
		(stroke
			(width 0.2)
			(type default)
		)
		(layer "In4.Cu")
	)
	(gr_arc
		(start 133.614922 -33.39973)
		(mid 134.099935 -33.885124)
		(end 134.585202 -33.399984)
		(stroke
			(width 0.2)
			(type default)
		)
		(layer "In4.Cu")
	)
	(gr_line
		(start 133.614922 -32.00019)
		(end 133.614922 -33.39973)
		(stroke
			(width 0.2)
			(type default)
		)
		(layer "In4.Cu")
	)
	(gr_line
		(start 134.585202 -44.200064)
		(end 134.585202 -42.800016)
		(stroke
			(width 0.2)
			(type default)
		)
		(layer "In4.Cu")
	)
	(gr_arc
		(start 134.585202 -42.800016)
		(mid 134.100062 -42.314876)
		(end 133.614922 -42.800016)
		(stroke
			(width 0.2)
			(type default)
		)
		(layer "In4.Cu")
	)
	(gr_line
		(start 134.585202 -37.00018)
		(end 134.585202 -35.600132)
		(stroke
			(width 0.2)
			(type default)
		)
		(layer "In4.Cu")
	)
	(gr_arc
		(start 134.585202 -35.600132)
		(mid 134.100062 -35.114992)
		(end 133.614922 -35.600132)
		(stroke
			(width 0.2)
			(type default)
		)
		(layer "In4.Cu")
	)
	(gr_line
		(start 134.585202 -33.399984)
		(end 134.585202 -32.00019)
		(stroke
			(width 0.2)
			(type default)
		)
		(layer "In4.Cu")
	)
	(gr_arc
		(start 134.585202 -32.00019)
		(mid 134.100062 -31.51505)
		(end 133.614922 -32.00019)
		(stroke
			(width 0.2)
			(type default)
		)
		(layer "In4.Cu")
	)
	(gr_arc
		(start 135.414766 -38.199822)
		(mid 135.899779 -38.685216)
		(end 136.385046 -38.200076)
		(stroke
			(width 0.2)
			(type default)
		)
		(layer "In4.Cu")
	)
	(gr_line
		(start 135.414766 -36.800028)
		(end 135.414766 -38.199822)
		(stroke
			(width 0.2)
			(type default)
		)
		(layer "In4.Cu")
	)
	(gr_arc
		(start 135.414766 -34.600134)
		(mid 135.899906 -35.085274)
		(end 136.385046 -34.600134)
		(stroke
			(width 0.2)
			(type default)
		)
		(layer "In4.Cu")
	)
	(gr_line
		(start 135.414766 -33.200086)
		(end 135.414766 -34.600134)
		(stroke
			(width 0.2)
			(type default)
		)
		(layer "In4.Cu")
	)
	(gr_line
		(start 136.385046 -38.200076)
		(end 136.385046 -36.800028)
		(stroke
			(width 0.2)
			(type default)
		)
		(layer "In4.Cu")
	)
	(gr_arc
		(start 136.385046 -36.800028)
		(mid 135.899906 -36.314888)
		(end 135.414766 -36.800028)
		(stroke
			(width 0.2)
			(type default)
		)
		(layer "In4.Cu")
	)
	(gr_line
		(start 136.385046 -34.600134)
		(end 136.385046 -33.20034)
		(stroke
			(width 0.2)
			(type default)
		)
		(layer "In4.Cu")
	)
	(gr_arc
		(start 136.385046 -33.20034)
		(mid 135.900033 -32.714946)
		(end 135.414766 -33.200086)
		(stroke
			(width 0.2)
			(type default)
		)
		(layer "In4.Cu")
	)
	(gr_arc
		(start 137.214864 -36.999926)
		(mid 137.699877 -37.48532)
		(end 138.185144 -37.00018)
		(stroke
			(width 0.2)
			(type default)
		)
		(layer "In4.Cu")
	)
	(gr_line
		(start 137.214864 -35.600132)
		(end 137.214864 -36.999926)
		(stroke
			(width 0.2)
			(type default)
		)
		(layer "In4.Cu")
	)
	(gr_arc
		(start 137.214864 -33.39973)
		(mid 137.699877 -33.885124)
		(end 138.185144 -33.399984)
		(stroke
			(width 0.2)
			(type default)
		)
		(layer "In4.Cu")
	)
	(gr_line
		(start 137.214864 -32.00019)
		(end 137.214864 -33.39973)
		(stroke
			(width 0.2)
			(type default)
		)
		(layer "In4.Cu")
	)
	(gr_line
		(start 138.185144 -37.00018)
		(end 138.185144 -35.600132)
		(stroke
			(width 0.2)
			(type default)
		)
		(layer "In4.Cu")
	)
	(gr_arc
		(start 138.185144 -35.600132)
		(mid 137.700004 -35.114992)
		(end 137.214864 -35.600132)
		(stroke
			(width 0.2)
			(type default)
		)
		(layer "In4.Cu")
	)
	(gr_line
		(start 138.185144 -33.399984)
		(end 138.185144 -32.00019)
		(stroke
			(width 0.2)
			(type default)
		)
		(layer "In4.Cu")
	)
	(gr_arc
		(start 138.185144 -32.00019)
		(mid 137.700004 -31.51505)
		(end 137.214864 -32.00019)
		(stroke
			(width 0.2)
			(type default)
		)
		(layer "In4.Cu")
	)
	(gr_arc
		(start 139.014708 -38.199822)
		(mid 139.499721 -38.685216)
		(end 139.984988 -38.200076)
		(stroke
			(width 0.2)
			(type default)
		)
		(layer "In4.Cu")
	)
	(gr_line
		(start 139.014708 -36.800028)
		(end 139.014708 -38.199822)
		(stroke
			(width 0.2)
			(type default)
		)
		(layer "In4.Cu")
	)
	(gr_arc
		(start 139.014708 -34.600134)
		(mid 139.499848 -35.085274)
		(end 139.984988 -34.600134)
		(stroke
			(width 0.2)
			(type default)
		)
		(layer "In4.Cu")
	)
	(gr_line
		(start 139.014708 -33.200086)
		(end 139.014708 -34.600134)
		(stroke
			(width 0.2)
			(type default)
		)
		(layer "In4.Cu")
	)
	(gr_line
		(start 139.984988 -38.200076)
		(end 139.984988 -36.800028)
		(stroke
			(width 0.2)
			(type default)
		)
		(layer "In4.Cu")
	)
	(gr_arc
		(start 139.984988 -36.800028)
		(mid 139.499848 -36.314888)
		(end 139.014708 -36.800028)
		(stroke
			(width 0.2)
			(type default)
		)
		(layer "In4.Cu")
	)
	(gr_line
		(start 139.984988 -34.600134)
		(end 139.984988 -33.20034)
		(stroke
			(width 0.2)
			(type default)
		)
		(layer "In4.Cu")
	)
	(gr_arc
		(start 139.984988 -33.20034)
		(mid 139.499975 -32.714946)
		(end 139.014708 -33.200086)
		(stroke
			(width 0.2)
			(type default)
		)
		(layer "In4.Cu")
	)
	(gr_arc
		(start 140.814806 -44.19981)
		(mid 141.299819 -44.685204)
		(end 141.785086 -44.200064)
		(stroke
			(width 0.2)
			(type default)
		)
		(layer "In4.Cu")
	)
	(gr_line
		(start 140.814806 -42.800016)
		(end 140.814806 -44.19981)
		(stroke
			(width 0.2)
			(type default)
		)
		(layer "In4.Cu")
	)
	(gr_arc
		(start 140.814806 -36.999926)
		(mid 141.299819 -37.48532)
		(end 141.785086 -37.00018)
		(stroke
			(width 0.2)
			(type default)
		)
		(layer "In4.Cu")
	)
	(gr_line
		(start 140.814806 -35.600132)
		(end 140.814806 -36.999926)
		(stroke
			(width 0.2)
			(type default)
		)
		(layer "In4.Cu")
	)
	(gr_arc
		(start 140.814806 -33.39973)
		(mid 141.299819 -33.885124)
		(end 141.785086 -33.399984)
		(stroke
			(width 0.2)
			(type default)
		)
		(layer "In4.Cu")
	)
	(gr_line
		(start 140.814806 -32.00019)
		(end 140.814806 -33.39973)
		(stroke
			(width 0.2)
			(type default)
		)
		(layer "In4.Cu")
	)
	(gr_line
		(start 141.785086 -44.200064)
		(end 141.785086 -42.800016)
		(stroke
			(width 0.2)
			(type default)
		)
		(layer "In4.Cu")
	)
	(gr_arc
		(start 141.785086 -42.800016)
		(mid 141.299946 -42.314876)
		(end 140.814806 -42.800016)
		(stroke
			(width 0.2)
			(type default)
		)
		(layer "In4.Cu")
	)
	(gr_line
		(start 141.785086 -37.00018)
		(end 141.785086 -35.600132)
		(stroke
			(width 0.2)
			(type default)
		)
		(layer "In4.Cu")
	)
	(gr_arc
		(start 141.785086 -35.600132)
		(mid 141.299946 -35.114992)
		(end 140.814806 -35.600132)
		(stroke
			(width 0.2)
			(type default)
		)
		(layer "In4.Cu")
	)
	(gr_line
		(start 141.785086 -33.399984)
		(end 141.785086 -32.00019)
		(stroke
			(width 0.2)
			(type default)
		)
		(layer "In4.Cu")
	)
	(gr_arc
		(start 141.785086 -32.00019)
		(mid 141.299946 -31.51505)
		(end 140.814806 -32.00019)
		(stroke
			(width 0.2)
			(type default)
		)
		(layer "In4.Cu")
	)
	(gr_line
		(start 143.299942 -47.999904)
		(end 104.70007 -47.999904)
		(stroke
			(width 2.54)
			(type default)
		)
		(layer "In4.Cu")
	)
	(gr_line
		(start 144.29994 -149.763988)
		(end 144.29994 -47.999904)
		(stroke
			(width 2.54)
			(type default)
		)
		(layer "In4.Cu")
	)
	(gr_arc
		(start 144.29994 -149.763988)
		(mid 144.326787 -149.993649)
		(end 144.405604 -150.211028)
		(stroke
			(width 2.54)
			(type default)
		)
		(layer "In4.Cu")
	)
	(gr_arc
		(start 144.29994 -47.999904)
		(mid 143.800068 -47.500032)
		(end 143.299942 -47.999904)
		(stroke
			(width 2.54)
			(type default)
		)
		(layer "In4.Cu")
	)
	(gr_line
		(start 149.023578 -159.44723)
		(end 144.405604 -150.211028)
		(stroke
			(width 2.54)
			(type default)
		)
		(layer "In4.Cu")
	)
	(gr_arc
		(start 149.023578 -159.44723)
		(mid 149.392231 -159.850635)
		(end 149.917912 -159.999934)
		(stroke
			(width 2.54)
			(type default)
		)
		(layer "In4.Cu")
	)
	(gr_line
		(start 150.55342 -6.014466)
		(end 152.539954 -8.001)
		(stroke
			(width 0.381)
			(type default)
		)
		(layer "In4.Cu")
	)
	(gr_line
		(start 152.539954 -8.001)
		(end 169.1513 -8.001)
		(stroke
			(width 0.381)
			(type default)
		)
		(layer "In4.Cu")
	)
	(gr_line
		(start 166.84244 -137.175494)
		(end 167.47109 -137.80389)
		(stroke
			(width 0.2)
			(type default)
		)
		(layer "In4.Cu")
	)
	(gr_arc
		(start 167.381428 -136.636506)
		(mid 166.84244 -136.636506)
		(end 166.84244 -137.175494)
		(stroke
			(width 0.2)
			(type default)
		)
		(layer "In4.Cu")
	)
	(gr_arc
		(start 167.47109 -137.80389)
		(mid 168.009888 -137.804081)
		(end 168.010078 -137.265156)
		(stroke
			(width 0.2)
			(type default)
		)
		(layer "In4.Cu")
	)
	(gr_line
		(start 168.010078 -137.265156)
		(end 167.381428 -136.636506)
		(stroke
			(width 0.2)
			(type default)
		)
		(layer "In4.Cu")
	)
	(gr_line
		(start 169.1513 -8.001)
		(end 173.9773 -12.827)
		(stroke
			(width 0.381)
			(type default)
		)
		(layer "In4.Cu")
	)
	(gr_line
		(start 170.170602 -138.590528)
		(end 170.799252 -139.218924)
		(stroke
			(width 0.2)
			(type default)
		)
		(layer "In4.Cu")
	)
	(gr_line
		(start 170.5483 -125.557026)
		(end 170.5483 -116.213636)
		(stroke
			(width 0.381)
			(type default)
		)
		(layer "In4.Cu")
	)
	(gr_line
		(start 170.5483 -116.213636)
		(end 172.117512 -114.644424)
		(stroke
			(width 0.381)
			(type default)
		)
		(layer "In4.Cu")
	)
	(gr_circle
		(center 170.548554 -116.213636)
		(end 170.548808 -116.213636)
		(stroke
			(width 0.381)
			(type default)
		)
		(fill no)
		(layer "In4.Cu")
	)
	(gr_arc
		(start 170.70959 -138.05154)
		(mid 170.170602 -138.05154)
		(end 170.170602 -138.590528)
		(stroke
			(width 0.2)
			(type default)
		)
		(layer "In4.Cu")
	)
	(gr_arc
		(start 170.799252 -139.218924)
		(mid 171.33805 -139.219115)
		(end 171.33824 -138.68019)
		(stroke
			(width 0.2)
			(type default)
		)
		(layer "In4.Cu")
	)
	(gr_line
		(start 171.33824 -138.68019)
		(end 170.70959 -138.05154)
		(stroke
			(width 0.2)
			(type default)
		)
		(layer "In4.Cu")
	)
	(gr_line
		(start 171.548298 -126.557024)
		(end 170.5483 -125.557026)
		(stroke
			(width 0.381)
			(type default)
		)
		(layer "In4.Cu")
	)
	(gr_circle
		(center 172.117512 -114.644678)
		(end 172.117766 -114.644678)
		(stroke
			(width 0.381)
			(type default)
		)
		(fill no)
		(layer "In4.Cu")
	)
	(gr_line
		(start 172.117512 -114.644424)
		(end 200.645014 -114.644424)
		(stroke
			(width 0.381)
			(type default)
		)
		(layer "In4.Cu")
	)
	(gr_line
		(start 173.674278 -138.194542)
		(end 174.302928 -138.822938)
		(stroke
			(width 0.2)
			(type default)
		)
		(layer "In4.Cu")
	)
	(gr_line
		(start 173.9773 -12.827)
		(end 199.974962 -12.827)
		(stroke
			(width 0.381)
			(type default)
		)
		(layer "In4.Cu")
	)
	(gr_line
		(start 174.024798 -140.502386)
		(end 174.653448 -141.130782)
		(stroke
			(width 0.2)
			(type default)
		)
		(layer "In4.Cu")
	)
	(gr_arc
		(start 174.213266 -137.655554)
		(mid 173.674278 -137.655554)
		(end 173.674278 -138.194542)
		(stroke
			(width 0.2)
			(type default)
		)
		(layer "In4.Cu")
	)
	(gr_arc
		(start 174.302928 -138.822938)
		(mid 174.841726 -138.823129)
		(end 174.841916 -138.284204)
		(stroke
			(width 0.2)
			(type default)
		)
		(layer "In4.Cu")
	)
	(gr_line
		(start 174.419768 -126.557024)
		(end 171.548298 -126.557024)
		(stroke
			(width 0.381)
			(type default)
		)
		(layer "In4.Cu")
	)
	(gr_arc
		(start 174.563786 -139.963398)
		(mid 174.024798 -139.963398)
		(end 174.024798 -140.502386)
		(stroke
			(width 0.2)
			(type default)
		)
		(layer "In4.Cu")
	)
	(gr_arc
		(start 174.653448 -141.130782)
		(mid 175.192246 -141.130973)
		(end 175.192436 -140.592048)
		(stroke
			(width 0.2)
			(type default)
		)
		(layer "In4.Cu")
	)
	(gr_line
		(start 174.841916 -138.284204)
		(end 174.213266 -137.655554)
		(stroke
			(width 0.2)
			(type default)
		)
		(layer "In4.Cu")
	)
	(gr_line
		(start 175.192436 -140.592048)
		(end 174.563786 -139.963398)
		(stroke
			(width 0.2)
			(type default)
		)
		(layer "In4.Cu")
	)
	(gr_line
		(start 176.149 -2.7686)
		(end 176.149 -1.5748)
		(stroke
			(width 0.381)
			(type default)
		)
		(layer "In4.Cu")
	)
	(gr_line
		(start 176.149 -1.5748)
		(end 175.3362 -0.762)
		(stroke
			(width 0.381)
			(type default)
		)
		(layer "In4.Cu")
	)
	(gr_line
		(start 176.149 -1.524)
		(end 176.149 -1.5748)
		(stroke
			(width 0.381)
			(type default)
		)
		(layer "In4.Cu")
	)
	(gr_line
		(start 176.149 -0.889)
		(end 176.149 -1.524)
		(stroke
			(width 0.381)
			(type default)
		)
		(layer "In4.Cu")
	)
	(gr_line
		(start 176.784 -0.889)
		(end 176.149 -1.524)
		(stroke
			(width 0.381)
			(type default)
		)
		(layer "In4.Cu")
	)
	(gr_line
		(start 177.391568 -140.243306)
		(end 178.020218 -140.871702)
		(stroke
			(width 0.2)
			(type default)
		)
		(layer "In4.Cu")
	)
	(gr_line
		(start 177.419 -4.0386)
		(end 176.149 -2.7686)
		(stroke
			(width 0.381)
			(type default)
		)
		(layer "In4.Cu")
	)
	(gr_arc
		(start 177.930556 -139.704318)
		(mid 177.391568 -139.704318)
		(end 177.391568 -140.243306)
		(stroke
			(width 0.2)
			(type default)
		)
		(layer "In4.Cu")
	)
	(gr_arc
		(start 178.020218 -140.871702)
		(mid 178.559016 -140.871893)
		(end 178.559206 -140.332968)
		(stroke
			(width 0.2)
			(type default)
		)
		(layer "In4.Cu")
	)
	(gr_line
		(start 178.559206 -140.332968)
		(end 177.930556 -139.704318)
		(stroke
			(width 0.2)
			(type default)
		)
		(layer "In4.Cu")
	)
	(gr_line
		(start 178.582574 -130.71983)
		(end 174.419768 -126.557024)
		(stroke
			(width 0.381)
			(type default)
		)
		(layer "In4.Cu")
	)
	(gr_circle
		(center 178.582574 -130.719576)
		(end 178.582828 -130.719576)
		(stroke
			(width 0.381)
			(type default)
		)
		(fill no)
		(layer "In4.Cu")
	)
	(gr_line
		(start 179.735734 -140.438378)
		(end 180.364384 -141.066774)
		(stroke
			(width 0.2)
			(type default)
		)
		(layer "In4.Cu")
	)
	(gr_arc
		(start 180.274722 -139.89939)
		(mid 179.735734 -139.89939)
		(end 179.735734 -140.438378)
		(stroke
			(width 0.2)
			(type default)
		)
		(layer "In4.Cu")
	)
	(gr_arc
		(start 180.364384 -141.066774)
		(mid 180.903182 -141.066965)
		(end 180.903372 -140.52804)
		(stroke
			(width 0.2)
			(type default)
		)
		(layer "In4.Cu")
	)
	(gr_line
		(start 180.903372 -140.52804)
		(end 180.274722 -139.89939)
		(stroke
			(width 0.2)
			(type default)
		)
		(layer "In4.Cu")
	)
	(gr_line
		(start 182.059072 -139.932918)
		(end 182.687722 -140.561314)
		(stroke
			(width 0.2)
			(type default)
		)
		(layer "In4.Cu")
	)
	(gr_arc
		(start 182.59806 -139.39393)
		(mid 182.059072 -139.39393)
		(end 182.059072 -139.932918)
		(stroke
			(width 0.2)
			(type default)
		)
		(layer "In4.Cu")
	)
	(gr_arc
		(start 182.687722 -140.561314)
		(mid 183.22652 -140.561505)
		(end 183.22671 -140.02258)
		(stroke
			(width 0.2)
			(type default)
		)
		(layer "In4.Cu")
	)
	(gr_line
		(start 183.016144 -133.354826)
		(end 183.90489 -133.354826)
		(stroke
			(width 0.2)
			(type default)
		)
		(layer "In4.Cu")
	)
	(gr_arc
		(start 183.016144 -132.592826)
		(mid 182.635144 -132.973826)
		(end 183.016144 -133.354826)
		(stroke
			(width 0.2)
			(type default)
		)
		(layer "In4.Cu")
	)
	(gr_line
		(start 183.22671 -140.02258)
		(end 182.59806 -139.39393)
		(stroke
			(width 0.2)
			(type default)
		)
		(layer "In4.Cu")
	)
	(gr_arc
		(start 183.90489 -133.354826)
		(mid 184.286144 -132.973953)
		(end 183.905144 -132.592826)
		(stroke
			(width 0.2)
			(type default)
		)
		(layer "In4.Cu")
	)
	(gr_line
		(start 183.905144 -132.592826)
		(end 183.016144 -132.592826)
		(stroke
			(width 0.2)
			(type default)
		)
		(layer "In4.Cu")
	)
	(gr_line
		(start 184.815734 -139.955778)
		(end 185.444384 -140.584174)
		(stroke
			(width 0.2)
			(type default)
		)
		(layer "In4.Cu")
	)
	(gr_arc
		(start 185.354722 -139.41679)
		(mid 184.815734 -139.41679)
		(end 184.815734 -139.955778)
		(stroke
			(width 0.2)
			(type default)
		)
		(layer "In4.Cu")
	)
	(gr_arc
		(start 185.444384 -140.584174)
		(mid 185.983182 -140.584365)
		(end 185.983372 -140.04544)
		(stroke
			(width 0.2)
			(type default)
		)
		(layer "In4.Cu")
	)
	(gr_line
		(start 185.983372 -140.04544)
		(end 185.354722 -139.41679)
		(stroke
			(width 0.2)
			(type default)
		)
		(layer "In4.Cu")
	)
	(gr_line
		(start 188.017912 -130.71983)
		(end 178.582574 -130.71983)
		(stroke
			(width 0.381)
			(type default)
		)
		(layer "In4.Cu")
	)
	(gr_line
		(start 189.528704 -132.230622)
		(end 188.017912 -130.71983)
		(stroke
			(width 0.381)
			(type default)
		)
		(layer "In4.Cu")
	)
	(gr_line
		(start 191.821308 -139.528296)
		(end 192.449958 -140.156692)
		(stroke
			(width 0.2)
			(type default)
		)
		(layer "In4.Cu")
	)
	(gr_arc
		(start 192.360296 -138.989308)
		(mid 191.821308 -138.989308)
		(end 191.821308 -139.528296)
		(stroke
			(width 0.2)
			(type default)
		)
		(layer "In4.Cu")
	)
	(gr_arc
		(start 192.449958 -140.156692)
		(mid 192.988756 -140.156883)
		(end 192.988946 -139.617958)
		(stroke
			(width 0.2)
			(type default)
		)
		(layer "In4.Cu")
	)
	(gr_line
		(start 192.988946 -139.617958)
		(end 192.360296 -138.989308)
		(stroke
			(width 0.2)
			(type default)
		)
		(layer "In4.Cu")
	)
	(gr_line
		(start 194.869308 -140.671296)
		(end 195.497958 -141.299692)
		(stroke
			(width 0.2)
			(type default)
		)
		(layer "In4.Cu")
	)
	(gr_arc
		(start 195.408296 -140.132308)
		(mid 194.869308 -140.132308)
		(end 194.869308 -140.671296)
		(stroke
			(width 0.2)
			(type default)
		)
		(layer "In4.Cu")
	)
	(gr_arc
		(start 195.497958 -141.299692)
		(mid 196.036756 -141.299883)
		(end 196.036946 -140.760958)
		(stroke
			(width 0.2)
			(type default)
		)
		(layer "In4.Cu")
	)
	(gr_line
		(start 196.036946 -140.760958)
		(end 195.408296 -140.132308)
		(stroke
			(width 0.2)
			(type default)
		)
		(layer "In4.Cu")
	)
	(gr_line
		(start 197.21195 -132.230622)
		(end 189.528704 -132.230622)
		(stroke
			(width 0.381)
			(type default)
		)
		(layer "In4.Cu")
	)
	(gr_line
		(start 197.536308 -140.925296)
		(end 198.164958 -141.553692)
		(stroke
			(width 0.2)
			(type default)
		)
		(layer "In4.Cu")
	)
	(gr_arc
		(start 198.075296 -140.386308)
		(mid 197.536308 -140.386308)
		(end 197.536308 -140.925296)
		(stroke
			(width 0.2)
			(type default)
		)
		(layer "In4.Cu")
	)
	(gr_arc
		(start 198.164958 -141.553692)
		(mid 198.703756 -141.553883)
		(end 198.703946 -141.014958)
		(stroke
			(width 0.2)
			(type default)
		)
		(layer "In4.Cu")
	)
	(gr_line
		(start 198.703946 -141.014958)
		(end 198.075296 -140.386308)
		(stroke
			(width 0.2)
			(type default)
		)
		(layer "In4.Cu")
	)
	(gr_line
		(start 199.046338 -130.396234)
		(end 197.21195 -132.230622)
		(stroke
			(width 0.381)
			(type default)
		)
		(layer "In4.Cu")
	)
	(gr_line
		(start 199.3138 -4.0386)
		(end 177.419 -4.0386)
		(stroke
			(width 0.381)
			(type default)
		)
		(layer "In4.Cu")
	)
	(gr_line
		(start 199.949308 -141.179296)
		(end 200.577958 -141.807692)
		(stroke
			(width 0.2)
			(type default)
		)
		(layer "In4.Cu")
	)
	(gr_line
		(start 199.974962 -12.827)
		(end 216.992962 -29.845)
		(stroke
			(width 0.381)
			(type default)
		)
		(layer "In4.Cu")
	)
	(gr_arc
		(start 200.488296 -140.640308)
		(mid 199.949308 -140.640308)
		(end 199.949308 -141.179296)
		(stroke
			(width 0.2)
			(type default)
		)
		(layer "In4.Cu")
	)
	(gr_arc
		(start 200.577958 -141.807692)
		(mid 201.116756 -141.807883)
		(end 201.116946 -141.268958)
		(stroke
			(width 0.2)
			(type default)
		)
		(layer "In4.Cu")
	)
	(gr_line
		(start 200.645014 -114.644424)
		(end 201.124566 -114.164872)
		(stroke
			(width 0.381)
			(type default)
		)
		(layer "In4.Cu")
	)
	(gr_circle
		(center 200.645014 -114.64417)
		(end 200.645268 -114.64417)
		(stroke
			(width 0.381)
			(type default)
		)
		(fill no)
		(layer "In4.Cu")
	)
	(gr_line
		(start 201.116946 -141.268958)
		(end 200.488296 -140.640308)
		(stroke
			(width 0.2)
			(type default)
		)
		(layer "In4.Cu")
	)
	(gr_circle
		(center 201.124312 -114.164872)
		(end 201.124566 -114.164872)
		(stroke
			(width 0.381)
			(type default)
		)
		(fill no)
		(layer "In4.Cu")
	)
	(gr_line
		(start 201.124566 -114.164872)
		(end 201.124566 -78.191106)
		(stroke
			(width 0.381)
			(type default)
		)
		(layer "In4.Cu")
	)
	(gr_line
		(start 201.124566 -78.191106)
		(end 211.244688 -68.070984)
		(stroke
			(width 0.381)
			(type default)
		)
		(layer "In4.Cu")
	)
	(gr_circle
		(center 201.12482 -78.191106)
		(end 201.125074 -78.191106)
		(stroke
			(width 0.381)
			(type default)
		)
		(fill no)
		(layer "In4.Cu")
	)
	(gr_line
		(start 202.362308 -141.052296)
		(end 202.990958 -141.680692)
		(stroke
			(width 0.2)
			(type default)
		)
		(layer "In4.Cu")
	)
	(gr_arc
		(start 202.901296 -140.513308)
		(mid 202.362308 -140.513308)
		(end 202.362308 -141.052296)
		(stroke
			(width 0.2)
			(type default)
		)
		(layer "In4.Cu")
	)
	(gr_arc
		(start 202.990958 -141.680692)
		(mid 203.529756 -141.680883)
		(end 203.529946 -141.141958)
		(stroke
			(width 0.2)
			(type default)
		)
		(layer "In4.Cu")
	)
	(gr_line
		(start 203.251308 -7.976108)
		(end 199.3138 -4.0386)
		(stroke
			(width 0.381)
			(type default)
		)
		(layer "In4.Cu")
	)
	(gr_line
		(start 203.529946 -141.141958)
		(end 202.901296 -140.513308)
		(stroke
			(width 0.2)
			(type default)
		)
		(layer "In4.Cu")
	)
	(gr_line
		(start 204.648308 -141.179296)
		(end 205.276958 -141.807692)
		(stroke
			(width 0.2)
			(type default)
		)
		(layer "In4.Cu")
	)
	(gr_arc
		(start 205.187296 -140.640308)
		(mid 204.648308 -140.640308)
		(end 204.648308 -141.179296)
		(stroke
			(width 0.2)
			(type default)
		)
		(layer "In4.Cu")
	)
	(gr_arc
		(start 205.276958 -141.807692)
		(mid 205.815756 -141.807883)
		(end 205.815946 -141.268958)
		(stroke
			(width 0.2)
			(type default)
		)
		(layer "In4.Cu")
	)
	(gr_line
		(start 205.815946 -141.268958)
		(end 205.187296 -140.640308)
		(stroke
			(width 0.2)
			(type default)
		)
		(layer "In4.Cu")
	)
	(gr_circle
		(center 206.000096 -6.199886)
		(end 206.815436 -6.199886)
		(stroke
			(width 0.2)
			(type default)
		)
		(fill no)
		(layer "In4.Cu")
	)
	(gr_line
		(start 206.172308 -139.528296)
		(end 206.800958 -140.156692)
		(stroke
			(width 0.2)
			(type default)
		)
		(layer "In4.Cu")
	)
	(gr_circle
		(center 206.247238 -7.976362)
		(end 206.247492 -7.976362)
		(stroke
			(width 0.381)
			(type default)
		)
		(fill no)
		(layer "In4.Cu")
	)
	(gr_line
		(start 206.247238 -7.976108)
		(end 203.251308 -7.976108)
		(stroke
			(width 0.381)
			(type default)
		)
		(layer "In4.Cu")
	)
	(gr_arc
		(start 206.711296 -138.989308)
		(mid 206.172308 -138.989308)
		(end 206.172308 -139.528296)
		(stroke
			(width 0.2)
			(type default)
		)
		(layer "In4.Cu")
	)
	(gr_arc
		(start 206.800958 -140.156692)
		(mid 207.339756 -140.156883)
		(end 207.339946 -139.617958)
		(stroke
			(width 0.2)
			(type default)
		)
		(layer "In4.Cu")
	)
	(gr_line
		(start 207.339946 -139.617958)
		(end 206.711296 -138.989308)
		(stroke
			(width 0.2)
			(type default)
		)
		(layer "In4.Cu")
	)
	(gr_line
		(start 209.347308 -140.798296)
		(end 209.975958 -141.426692)
		(stroke
			(width 0.2)
			(type default)
		)
		(layer "In4.Cu")
	)
	(gr_arc
		(start 209.886296 -140.259308)
		(mid 209.347308 -140.259308)
		(end 209.347308 -140.798296)
		(stroke
			(width 0.2)
			(type default)
		)
		(layer "In4.Cu")
	)
	(gr_arc
		(start 209.975958 -141.426692)
		(mid 210.514756 -141.426883)
		(end 210.514946 -140.887958)
		(stroke
			(width 0.2)
			(type default)
		)
		(layer "In4.Cu")
	)
	(gr_line
		(start 210.514946 -140.887958)
		(end 209.886296 -140.259308)
		(stroke
			(width 0.2)
			(type default)
		)
		(layer "In4.Cu")
	)
	(gr_circle
		(center 211.244688 -68.071238)
		(end 211.244942 -68.071238)
		(stroke
			(width 0.381)
			(type default)
		)
		(fill no)
		(layer "In4.Cu")
	)
	(gr_line
		(start 211.244688 -68.070984)
		(end 221.671896 -68.070984)
		(stroke
			(width 0.381)
			(type default)
		)
		(layer "In4.Cu")
	)
	(gr_line
		(start 211.910168 -130.396234)
		(end 199.046338 -130.396234)
		(stroke
			(width 0.381)
			(type default)
		)
		(layer "In4.Cu")
	)
	(gr_line
		(start 212.654642 -131.140708)
		(end 211.910168 -130.396234)
		(stroke
			(width 0.381)
			(type default)
		)
		(layer "In4.Cu")
	)
	(gr_line
		(start 213.063836 -139.146534)
		(end 213.692486 -139.77493)
		(stroke
			(width 0.2)
			(type default)
		)
		(layer "In4.Cu")
	)
	(gr_arc
		(start 213.602824 -138.607546)
		(mid 213.063836 -138.607546)
		(end 213.063836 -139.146534)
		(stroke
			(width 0.2)
			(type default)
		)
		(layer "In4.Cu")
	)
	(gr_arc
		(start 213.692486 -139.77493)
		(mid 214.231284 -139.775121)
		(end 214.231474 -139.236196)
		(stroke
			(width 0.2)
			(type default)
		)
		(layer "In4.Cu")
	)
	(gr_line
		(start 214.00008 -159.999934)
		(end 149.917912 -159.999934)
		(stroke
			(width 2.54)
			(type default)
		)
		(layer "In4.Cu")
	)
	(gr_line
		(start 214.231474 -139.236196)
		(end 213.602824 -138.607546)
		(stroke
			(width 0.2)
			(type default)
		)
		(layer "In4.Cu")
	)
	(gr_line
		(start 215.000078 -193.000122)
		(end 215.000078 -160.999932)
		(stroke
			(width 2.54)
			(type default)
		)
		(layer "In4.Cu")
	)
	(gr_arc
		(start 215.000078 -193.000122)
		(mid 215.292977 -193.707222)
		(end 216.000076 -194.00012)
		(stroke
			(width 2.54)
			(type default)
		)
		(layer "In4.Cu")
	)
	(gr_arc
		(start 215.000078 -160.999932)
		(mid 214.707185 -160.292827)
		(end 214.00008 -159.999934)
		(stroke
			(width 2.54)
			(type default)
		)
		(layer "In4.Cu")
	)
	(gr_line
		(start 215.244426 -131.140708)
		(end 212.654642 -131.140708)
		(stroke
			(width 0.381)
			(type default)
		)
		(layer "In4.Cu")
	)
	(gr_line
		(start 216.81313 -18.542)
		(end 206.247238 -7.976108)
		(stroke
			(width 0.381)
			(type default)
		)
		(layer "In4.Cu")
	)
	(gr_line
		(start 216.815162 -129.569972)
		(end 215.244426 -131.140708)
		(stroke
			(width 0.381)
			(type default)
		)
		(layer "In4.Cu")
	)
	(gr_line
		(start 216.815162 -82.562446)
		(end 216.815162 -129.569972)
		(stroke
			(width 0.381)
			(type default)
		)
		(layer "In4.Cu")
	)
	(gr_line
		(start 216.992962 -29.845)
		(end 229.5144 -29.845)
		(stroke
			(width 0.381)
			(type default)
		)
		(layer "In4.Cu")
	)
	(gr_circle
		(center 221.671896 -68.071238)
		(end 221.67215 -68.071238)
		(stroke
			(width 0.381)
			(type default)
		)
		(fill no)
		(layer "In4.Cu")
	)
	(gr_line
		(start 221.671896 -68.070984)
		(end 222.528638 -68.927726)
		(stroke
			(width 0.381)
			(type default)
		)
		(layer "In4.Cu")
	)
	(gr_line
		(start 222.528638 -76.84897)
		(end 216.815162 -82.562446)
		(stroke
			(width 0.381)
			(type default)
		)
		(layer "In4.Cu")
	)
	(gr_line
		(start 222.528638 -68.927726)
		(end 222.528638 -76.84897)
		(stroke
			(width 0.381)
			(type default)
		)
		(layer "In4.Cu")
	)
	(gr_line
		(start 229.382066 -194.00012)
		(end 216.000076 -194.00012)
		(stroke
			(width 2.54)
			(type default)
		)
		(layer "In4.Cu")
	)
	(gr_arc
		(start 229.382066 -194.00012)
		(mid 229.907793 -193.850701)
		(end 230.2764 -193.447162)
		(stroke
			(width 2.54)
			(type default)
		)
		(layer "In4.Cu")
	)
	(gr_line
		(start 229.5144 -29.845)
		(end 230.606092 -28.753308)
		(stroke
			(width 0.381)
			(type default)
		)
		(layer "In4.Cu")
	)
	(gr_line
		(start 229.7176 -18.542)
		(end 216.81313 -18.542)
		(stroke
			(width 0.381)
			(type default)
		)
		(layer "In4.Cu")
	)
	(gr_line
		(start 230.606092 -28.753308)
		(end 230.606092 -19.430492)
		(stroke
			(width 0.381)
			(type default)
		)
		(layer "In4.Cu")
	)
	(gr_line
		(start 230.606092 -19.430492)
		(end 229.7176 -18.542)
		(stroke
			(width 0.381)
			(type default)
		)
		(layer "In4.Cu")
	)
	(gr_line
		(start 234.894374 -184.211214)
		(end 230.2764 -193.447162)
		(stroke
			(width 2.54)
			(type default)
		)
		(layer "In4.Cu")
	)
	(gr_arc
		(start 234.894374 -184.211214)
		(mid 234.97328 -183.993726)
		(end 235.000038 -183.76392)
		(stroke
			(width 2.54)
			(type default)
		)
		(layer "In4.Cu")
	)
	(gr_arc
		(start 235.000038 -0.999998)
		(mid 234.707147 -0.29288)
		(end 234.00004 0)
		(stroke
			(width 2.54)
			(type default)
		)
		(layer "In4.Cu")
	)
	(gr_line
		(start 235.000038 -0.999998)
		(end 235.000038 -183.76392)
		(stroke
			(width 2.54)
			(type default)
		)
		(layer "In4.Cu")
	)
	(gr_line
		(start 65.362328 -153.052526)
		(end 65.560702 -152.854152)
		(stroke
			(width 0.06985)
			(type default)
		)
		(layer "In5.Cu")
	)
	(gr_line
		(start 65.365884 -152.188926)
		(end 65.560702 -152.383744)
		(stroke
			(width 0.06985)
			(type default)
		)
		(layer "In5.Cu")
	)
	(gr_line
		(start 65.633092 -154.808936)
		(end 65.851024 -154.591004)
		(stroke
			(width 0.06985)
			(type default)
		)
		(layer "In5.Cu")
	)
	(gr_line
		(start 65.633092 -153.90241)
		(end 65.851024 -154.120342)
		(stroke
			(width 0.06985)
			(type default)
		)
		(layer "In5.Cu")
	)
	(gr_line
		(start 74.652378 -154.662632)
		(end 74.72934 -154.739594)
		(stroke
			(width 0.06985)
			(type default)
		)
		(layer "In5.Cu")
	)
	(gr_line
		(start 74.654156 -154.193748)
		(end 74.90206 -154.193748)
		(stroke
			(width 0.06985)
			(type default)
		)
		(layer "In5.Cu")
	)
	(gr_line
		(start 74.90206 -154.193748)
		(end 75.198224 -154.489912)
		(stroke
			(width 0.06985)
			(type default)
		)
		(layer "In5.Cu")
	)
	(gr_line
		(start 75.198224 -154.489912)
		(end 75.198224 -154.737816)
		(stroke
			(width 0.06985)
			(type default)
		)
		(layer "In5.Cu")
	)
	(gr_line
		(start 75.49642 -155.506674)
		(end 75.573382 -155.583636)
		(stroke
			(width 0.06985)
			(type default)
		)
		(layer "In5.Cu")
	)
	(gr_line
		(start 75.498198 -155.03779)
		(end 75.746102 -155.03779)
		(stroke
			(width 0.06985)
			(type default)
		)
		(layer "In5.Cu")
	)
	(gr_line
		(start 75.746102 -155.03779)
		(end 76.042266 -155.333954)
		(stroke
			(width 0.06985)
			(type default)
		)
		(layer "In5.Cu")
	)
	(gr_line
		(start 76.042266 -155.333954)
		(end 76.042266 -155.581858)
		(stroke
			(width 0.06985)
			(type default)
		)
		(layer "In5.Cu")
	)
	(gr_line
		(start 77.127608 -154.830272)
		(end 77.302868 -155.005532)
		(stroke
			(width 0.06985)
			(type default)
		)
		(layer "In5.Cu")
	)
	(gr_line
		(start 77.302868 -155.005532)
		(end 77.721968 -155.005532)
		(stroke
			(width 0.06985)
			(type default)
		)
		(layer "In5.Cu")
	)
	(gr_line
		(start 77.457808 -154.497532)
		(end 77.567028 -154.497532)
		(stroke
			(width 0.06985)
			(type default)
		)
		(layer "In5.Cu")
	)
	(gr_line
		(start 77.721968 -155.005532)
		(end 77.897228 -154.830272)
		(stroke
			(width 0.06985)
			(type default)
		)
		(layer "In5.Cu")
	)
	(gr_line
		(start 77.776832 -155.879292)
		(end 77.952092 -155.704032)
		(stroke
			(width 0.06985)
			(type default)
		)
		(layer "In5.Cu")
	)
	(gr_line
		(start 77.952092 -155.704032)
		(end 78.371192 -155.704032)
		(stroke
			(width 0.06985)
			(type default)
		)
		(layer "In5.Cu")
	)
	(gr_line
		(start 78.107032 -156.212032)
		(end 78.216252 -156.212032)
		(stroke
			(width 0.06985)
			(type default)
		)
		(layer "In5.Cu")
	)
	(gr_line
		(start 78.321408 -154.830272)
		(end 78.496668 -155.005532)
		(stroke
			(width 0.06985)
			(type default)
		)
		(layer "In5.Cu")
	)
	(gr_line
		(start 78.371192 -155.704032)
		(end 78.546452 -155.879292)
		(stroke
			(width 0.06985)
			(type default)
		)
		(layer "In5.Cu")
	)
	(gr_line
		(start 78.496668 -155.005532)
		(end 78.915768 -155.005532)
		(stroke
			(width 0.06985)
			(type default)
		)
		(layer "In5.Cu")
	)
	(gr_line
		(start 78.651608 -154.497532)
		(end 78.760828 -154.497532)
		(stroke
			(width 0.06985)
			(type default)
		)
		(layer "In5.Cu")
	)
	(gr_line
		(start 78.915768 -155.005532)
		(end 79.091028 -154.830272)
		(stroke
			(width 0.06985)
			(type default)
		)
		(layer "In5.Cu")
	)
	(gr_line
		(start 78.970632 -155.879292)
		(end 79.145892 -155.704032)
		(stroke
			(width 0.06985)
			(type default)
		)
		(layer "In5.Cu")
	)
	(gr_line
		(start 79.145892 -155.704032)
		(end 79.564992 -155.704032)
		(stroke
			(width 0.06985)
			(type default)
		)
		(layer "In5.Cu")
	)
	(gr_line
		(start 79.300832 -156.212032)
		(end 79.410052 -156.212032)
		(stroke
			(width 0.06985)
			(type default)
		)
		(layer "In5.Cu")
	)
	(gr_line
		(start 79.515208 -154.830272)
		(end 79.690468 -155.005532)
		(stroke
			(width 0.06985)
			(type default)
		)
		(layer "In5.Cu")
	)
	(gr_line
		(start 79.564992 -155.704032)
		(end 79.740252 -155.879292)
		(stroke
			(width 0.06985)
			(type default)
		)
		(layer "In5.Cu")
	)
	(gr_line
		(start 79.690468 -155.005532)
		(end 80.109568 -155.005532)
		(stroke
			(width 0.06985)
			(type default)
		)
		(layer "In5.Cu")
	)
	(gr_line
		(start 79.845408 -154.497532)
		(end 79.954628 -154.497532)
		(stroke
			(width 0.06985)
			(type default)
		)
		(layer "In5.Cu")
	)
	(gr_line
		(start 80.109568 -155.005532)
		(end 80.284828 -154.830272)
		(stroke
			(width 0.06985)
			(type default)
		)
		(layer "In5.Cu")
	)
	(gr_line
		(start 80.164432 -155.879292)
		(end 80.339692 -155.704032)
		(stroke
			(width 0.06985)
			(type default)
		)
		(layer "In5.Cu")
	)
	(gr_line
		(start 80.339692 -155.704032)
		(end 80.758792 -155.704032)
		(stroke
			(width 0.06985)
			(type default)
		)
		(layer "In5.Cu")
	)
	(gr_line
		(start 80.494632 -156.212032)
		(end 80.603852 -156.212032)
		(stroke
			(width 0.06985)
			(type default)
		)
		(layer "In5.Cu")
	)
	(gr_line
		(start 80.709008 -154.830272)
		(end 80.884268 -155.005532)
		(stroke
			(width 0.06985)
			(type default)
		)
		(layer "In5.Cu")
	)
	(gr_line
		(start 80.758792 -155.704032)
		(end 80.934052 -155.879292)
		(stroke
			(width 0.06985)
			(type default)
		)
		(layer "In5.Cu")
	)
	(gr_line
		(start 80.884268 -155.005532)
		(end 81.303368 -155.005532)
		(stroke
			(width 0.06985)
			(type default)
		)
		(layer "In5.Cu")
	)
	(gr_line
		(start 81.039208 -154.497532)
		(end 81.148428 -154.497532)
		(stroke
			(width 0.06985)
			(type default)
		)
		(layer "In5.Cu")
	)
	(gr_line
		(start 81.303368 -155.005532)
		(end 81.478628 -154.830272)
		(stroke
			(width 0.06985)
			(type default)
		)
		(layer "In5.Cu")
	)
	(gr_line
		(start 81.358232 -155.879292)
		(end 81.533492 -155.704032)
		(stroke
			(width 0.06985)
			(type default)
		)
		(layer "In5.Cu")
	)
	(gr_line
		(start 81.533492 -155.704032)
		(end 81.952592 -155.704032)
		(stroke
			(width 0.06985)
			(type default)
		)
		(layer "In5.Cu")
	)
	(gr_line
		(start 81.688432 -156.212032)
		(end 81.797652 -156.212032)
		(stroke
			(width 0.06985)
			(type default)
		)
		(layer "In5.Cu")
	)
	(gr_line
		(start 81.952592 -155.704032)
		(end 82.127852 -155.879292)
		(stroke
			(width 0.06985)
			(type default)
		)
		(layer "In5.Cu")
	)
	(gr_line
		(start 83.358228 -95.381572)
		(end 83.567524 -95.172276)
		(stroke
			(width 0.06985)
			(type default)
		)
		(layer "In5.Cu")
	)
	(gr_line
		(start 83.358228 -94.492572)
		(end 83.567524 -94.701868)
		(stroke
			(width 0.06985)
			(type default)
		)
		(layer "In5.Cu")
	)
	(gr_line
		(start 83.358228 -82.581496)
		(end 83.567524 -82.3722)
		(stroke
			(width 0.06985)
			(type default)
		)
		(layer "In5.Cu")
	)
	(gr_line
		(start 83.358228 -81.692496)
		(end 83.567524 -81.901792)
		(stroke
			(width 0.06985)
			(type default)
		)
		(layer "In5.Cu")
	)
	(gr_line
		(start 83.358228 -76.194158)
		(end 83.567524 -75.984862)
		(stroke
			(width 0.06985)
			(type default)
		)
		(layer "In5.Cu")
	)
	(gr_line
		(start 83.358228 -75.305158)
		(end 83.567524 -75.514454)
		(stroke
			(width 0.06985)
			(type default)
		)
		(layer "In5.Cu")
	)
	(gr_line
		(start 83.359498 -88.980264)
		(end 83.568794 -88.770968)
		(stroke
			(width 0.06985)
			(type default)
		)
		(layer "In5.Cu")
	)
	(gr_line
		(start 83.359498 -88.091264)
		(end 83.568794 -88.30056)
		(stroke
			(width 0.06985)
			(type default)
		)
		(layer "In5.Cu")
	)
	(gr_line
		(start 84.479892 -152.055576)
		(end 84.655152 -152.230836)
		(stroke
			(width 0.06985)
			(type default)
		)
		(layer "In5.Cu")
	)
	(gr_line
		(start 84.655152 -152.230836)
		(end 85.074252 -152.230836)
		(stroke
			(width 0.06985)
			(type default)
		)
		(layer "In5.Cu")
	)
	(gr_line
		(start 84.810092 -151.722836)
		(end 84.919312 -151.722836)
		(stroke
			(width 0.06985)
			(type default)
		)
		(layer "In5.Cu")
	)
	(gr_line
		(start 84.863178 -72.987916)
		(end 85.072474 -72.77862)
		(stroke
			(width 0.06985)
			(type default)
		)
		(layer "In5.Cu")
	)
	(gr_line
		(start 84.863178 -72.098916)
		(end 85.072474 -72.308212)
		(stroke
			(width 0.06985)
			(type default)
		)
		(layer "In5.Cu")
	)
	(gr_line
		(start 84.903056 -153.072592)
		(end 85.118448 -153.287984)
		(stroke
			(width 0.06985)
			(type default)
		)
		(layer "In5.Cu")
	)
	(gr_line
		(start 84.983828 -92.195396)
		(end 85.193124 -91.9861)
		(stroke
			(width 0.06985)
			(type default)
		)
		(layer "In5.Cu")
	)
	(gr_line
		(start 84.983828 -91.306396)
		(end 85.193124 -91.515692)
		(stroke
			(width 0.06985)
			(type default)
		)
		(layer "In5.Cu")
	)
	(gr_line
		(start 84.983828 -85.781134)
		(end 85.193124 -85.571838)
		(stroke
			(width 0.06985)
			(type default)
		)
		(layer "In5.Cu")
	)
	(gr_line
		(start 84.983828 -84.892134)
		(end 85.193124 -85.10143)
		(stroke
			(width 0.06985)
			(type default)
		)
		(layer "In5.Cu")
	)
	(gr_line
		(start 84.986622 -79.396336)
		(end 85.195918 -79.18704)
		(stroke
			(width 0.06985)
			(type default)
		)
		(layer "In5.Cu")
	)
	(gr_line
		(start 84.986622 -78.507336)
		(end 85.195918 -78.716632)
		(stroke
			(width 0.06985)
			(type default)
		)
		(layer "In5.Cu")
	)
	(gr_line
		(start 85.074252 -152.230836)
		(end 85.249512 -152.055576)
		(stroke
			(width 0.06985)
			(type default)
		)
		(layer "In5.Cu")
	)
	(gr_line
		(start 85.404706 -88.6968)
		(end 85.472778 -88.628728)
		(stroke
			(width 0.06985)
			(type default)
		)
		(layer "In5.Cu")
	)
	(gr_line
		(start 85.58911 -153.287984)
		(end 85.804502 -153.072592)
		(stroke
			(width 0.06985)
			(type default)
		)
		(layer "In5.Cu")
	)
	(gr_line
		(start 85.673692 -152.055576)
		(end 85.848952 -152.230836)
		(stroke
			(width 0.06985)
			(type default)
		)
		(layer "In5.Cu")
	)
	(gr_line
		(start 85.848952 -152.230836)
		(end 86.268052 -152.230836)
		(stroke
			(width 0.06985)
			(type default)
		)
		(layer "In5.Cu")
	)
	(gr_line
		(start 85.998558 -72.708516)
		(end 86.06663 -72.640444)
		(stroke
			(width 0.06985)
			(type default)
		)
		(layer "In5.Cu")
	)
	(gr_line
		(start 86.003892 -151.722836)
		(end 86.113112 -151.722836)
		(stroke
			(width 0.06985)
			(type default)
		)
		(layer "In5.Cu")
	)
	(gr_line
		(start 86.268052 -152.230836)
		(end 86.443312 -152.055576)
		(stroke
			(width 0.06985)
			(type default)
		)
		(layer "In5.Cu")
	)
	(gr_line
		(start 86.7664 -156.708348)
		(end 86.981792 -156.492956)
		(stroke
			(width 0.06985)
			(type default)
		)
		(layer "In5.Cu")
	)
	(gr_line
		(start 86.7664 -155.806902)
		(end 86.981792 -156.022294)
		(stroke
			(width 0.06985)
			(type default)
		)
		(layer "In5.Cu")
	)
	(gr_line
		(start 86.952328 -71.755254)
		(end 86.961726 -71.745856)
		(stroke
			(width 0.06985)
			(type default)
		)
		(layer "In5.Cu")
	)
	(gr_line
		(start 86.961726 -71.745856)
		(end 86.967822 -71.733918)
		(stroke
			(width 0.06985)
			(type default)
		)
		(layer "In5.Cu")
	)
	(gr_line
		(start 87.392764 -153.999692)
		(end 87.568024 -154.174952)
		(stroke
			(width 0.06985)
			(type default)
		)
		(layer "In5.Cu")
	)
	(gr_line
		(start 87.392764 -153.580592)
		(end 87.392764 -153.999692)
		(stroke
			(width 0.06985)
			(type default)
		)
		(layer "In5.Cu")
	)
	(gr_line
		(start 87.392764 -153.580592)
		(end 87.568024 -153.405332)
		(stroke
			(width 0.06985)
			(type default)
		)
		(layer "In5.Cu")
	)
	(gr_line
		(start 87.65794 -70.352158)
		(end 87.658702 -70.350634)
		(stroke
			(width 0.06985)
			(type default)
		)
		(layer "In5.Cu")
	)
	(gr_line
		(start 87.658702 -70.350634)
		(end 87.658956 -70.349364)
		(stroke
			(width 0.06985)
			(type default)
		)
		(layer "In5.Cu")
	)
	(gr_line
		(start 87.900764 -153.735532)
		(end 87.900764 -153.844752)
		(stroke
			(width 0.06985)
			(type default)
		)
		(layer "In5.Cu")
	)
	(gr_line
		(start 88.3285 -48.683926)
		(end 88.33485 -48.71339)
		(stroke
			(width 0.06985)
			(type default)
		)
		(layer "In5.Cu")
	)
	(gr_line
		(start 88.3285 -48.683926)
		(end 88.33485 -48.6537)
		(stroke
			(width 0.06985)
			(type default)
		)
		(layer "In5.Cu")
	)
	(gr_line
		(start 88.779096 -70.755764)
		(end 88.790526 -70.737984)
		(stroke
			(width 0.06985)
			(type default)
		)
		(layer "In5.Cu")
	)
	(gr_line
		(start 88.790526 -70.737984)
		(end 88.79459 -70.718172)
		(stroke
			(width 0.06985)
			(type default)
		)
		(layer "In5.Cu")
	)
	(gr_line
		(start 89.082372 -74.699622)
		(end 89.094564 -74.681334)
		(stroke
			(width 0.06985)
			(type default)
		)
		(layer "In5.Cu")
	)
	(gr_line
		(start 89.094564 -74.681334)
		(end 89.098882 -74.65949)
		(stroke
			(width 0.06985)
			(type default)
		)
		(layer "In5.Cu")
	)
	(gr_line
		(start 89.435178 -43.479212)
		(end 89.439242 -43.4594)
		(stroke
			(width 0.06985)
			(type default)
		)
		(layer "In5.Cu")
	)
	(gr_line
		(start 89.439242 -43.4594)
		(end 89.450672 -43.44162)
		(stroke
			(width 0.06985)
			(type default)
		)
		(layer "In5.Cu")
	)
	(gr_line
		(start 89.897712 -82.476594)
		(end 89.90965 -82.42046)
		(stroke
			(width 0.06985)
			(type default)
		)
		(layer "In5.Cu")
	)
	(gr_line
		(start 90.131392 -51.461924)
		(end 90.137742 -51.491388)
		(stroke
			(width 0.06985)
			(type default)
		)
		(layer "In5.Cu")
	)
	(gr_line
		(start 90.131392 -51.461924)
		(end 90.137742 -51.431698)
		(stroke
			(width 0.06985)
			(type default)
		)
		(layer "In5.Cu")
	)
	(gr_line
		(start 90.445336 -57.109868)
		(end 90.451432 -57.081674)
		(stroke
			(width 0.06985)
			(type default)
		)
		(layer "In5.Cu")
	)
	(gr_line
		(start 90.445336 -57.053226)
		(end 90.451432 -57.081674)
		(stroke
			(width 0.06985)
			(type default)
		)
		(layer "In5.Cu")
	)
	(gr_line
		(start 90.62212 -74.733404)
		(end 90.636852 -74.711306)
		(stroke
			(width 0.06985)
			(type default)
		)
		(layer "In5.Cu")
	)
	(gr_line
		(start 90.636852 -74.711306)
		(end 90.642186 -74.685398)
		(stroke
			(width 0.06985)
			(type default)
		)
		(layer "In5.Cu")
	)
	(gr_line
		(start 90.786966 -83.314794)
		(end 90.828114 -83.273646)
		(stroke
			(width 0.06985)
			(type default)
		)
		(layer "In5.Cu")
	)
	(gr_line
		(start 90.828114 -83.273646)
		(end 90.840052 -83.21675)
		(stroke
			(width 0.06985)
			(type default)
		)
		(layer "In5.Cu")
	)
	(gr_line
		(start 91.095576 -87.263224)
		(end 91.10726 -87.206582)
		(stroke
			(width 0.06985)
			(type default)
		)
		(layer "In5.Cu")
	)
	(gr_line
		(start 91.651328 -89.028778)
		(end 91.663266 -88.972136)
		(stroke
			(width 0.06985)
			(type default)
		)
		(layer "In5.Cu")
	)
	(gr_line
		(start 91.654376 -40.654986)
		(end 91.665806 -40.637206)
		(stroke
			(width 0.06985)
			(type default)
		)
		(layer "In5.Cu")
	)
	(gr_line
		(start 91.665806 -40.637206)
		(end 91.66987 -40.617394)
		(stroke
			(width 0.06985)
			(type default)
		)
		(layer "In5.Cu")
	)
	(gr_line
		(start 91.673426 -57.129172)
		(end 91.68003 -57.159906)
		(stroke
			(width 0.06985)
			(type default)
		)
		(layer "In5.Cu")
	)
	(gr_line
		(start 91.67368 -57.190386)
		(end 91.68003 -57.159906)
		(stroke
			(width 0.06985)
			(type default)
		)
		(layer "In5.Cu")
	)
	(gr_line
		(start 91.778074 -50.57267)
		(end 91.783662 -50.544476)
		(stroke
			(width 0.06985)
			(type default)
		)
		(layer "In5.Cu")
	)
	(gr_line
		(start 91.778074 -50.57267)
		(end 91.783916 -50.60061)
		(stroke
			(width 0.06985)
			(type default)
		)
		(layer "In5.Cu")
	)
	(gr_line
		(start 91.97721 -37.583872)
		(end 91.98229 -37.56025)
		(stroke
			(width 0.06985)
			(type default)
		)
		(layer "In5.Cu")
	)
	(gr_line
		(start 91.98229 -37.56025)
		(end 91.995752 -37.540184)
		(stroke
			(width 0.06985)
			(type default)
		)
		(layer "In5.Cu")
	)
	(gr_line
		(start 93.067124 -37.65423)
		(end 93.07195 -37.631624)
		(stroke
			(width 0.06985)
			(type default)
		)
		(layer "In5.Cu")
	)
	(gr_line
		(start 93.07195 -37.631624)
		(end 93.084904 -37.612574)
		(stroke
			(width 0.06985)
			(type default)
		)
		(layer "In5.Cu")
	)
	(gr_line
		(start 93.089476 -55.153052)
		(end 93.095826 -55.18277)
		(stroke
			(width 0.06985)
			(type default)
		)
		(layer "In5.Cu")
	)
	(gr_line
		(start 93.089984 -55.211218)
		(end 93.095826 -55.18277)
		(stroke
			(width 0.06985)
			(type default)
		)
		(layer "In5.Cu")
	)
	(gr_line
		(start 93.290644 -47.689262)
		(end 93.296232 -47.661322)
		(stroke
			(width 0.06985)
			(type default)
		)
		(layer "In5.Cu")
	)
	(gr_line
		(start 93.290644 -47.689262)
		(end 93.296486 -47.717202)
		(stroke
			(width 0.06985)
			(type default)
		)
		(layer "In5.Cu")
	)
	(gr_line
		(start 93.556836 -51.50612)
		(end 93.563186 -51.535584)
		(stroke
			(width 0.06985)
			(type default)
		)
		(layer "In5.Cu")
	)
	(gr_line
		(start 93.556836 -51.50612)
		(end 93.563186 -51.475894)
		(stroke
			(width 0.06985)
			(type default)
		)
		(layer "In5.Cu")
	)
	(gr_line
		(start 94.160594 -50.193448)
		(end 94.167198 -50.224182)
		(stroke
			(width 0.06985)
			(type default)
		)
		(layer "In5.Cu")
	)
	(gr_line
		(start 94.160848 -50.253646)
		(end 94.167198 -50.224182)
		(stroke
			(width 0.06985)
			(type default)
		)
		(layer "In5.Cu")
	)
	(gr_line
		(start 94.38259 -37.553138)
		(end 94.38767 -37.527992)
		(stroke
			(width 0.06985)
			(type default)
		)
		(layer "In5.Cu")
	)
	(gr_line
		(start 94.38767 -37.527992)
		(end 94.401386 -37.507926)
		(stroke
			(width 0.06985)
			(type default)
		)
		(layer "In5.Cu")
	)
	(gr_line
		(start 94.572328 -46.638464)
		(end 94.577916 -46.610524)
		(stroke
			(width 0.06985)
			(type default)
		)
		(layer "In5.Cu")
	)
	(gr_line
		(start 94.572328 -46.638464)
		(end 94.57817 -46.666404)
		(stroke
			(width 0.06985)
			(type default)
		)
		(layer "In5.Cu")
	)
	(gr_line
		(start 94.643956 -55.031894)
		(end 94.649798 -55.059072)
		(stroke
			(width 0.06985)
			(type default)
		)
		(layer "In5.Cu")
	)
	(gr_line
		(start 94.64421 -55.086504)
		(end 94.649798 -55.059072)
		(stroke
			(width 0.06985)
			(type default)
		)
		(layer "In5.Cu")
	)
	(gr_line
		(start 95.165926 -38.308788)
		(end 95.171006 -38.283642)
		(stroke
			(width 0.06985)
			(type default)
		)
		(layer "In5.Cu")
	)
	(gr_line
		(start 95.171006 -38.283642)
		(end 95.184722 -38.263576)
		(stroke
			(width 0.06985)
			(type default)
		)
		(layer "In5.Cu")
	)
	(gr_line
		(start 95.640144 -46.597062)
		(end 95.645732 -46.569122)
		(stroke
			(width 0.06985)
			(type default)
		)
		(layer "In5.Cu")
	)
	(gr_line
		(start 95.640144 -46.597062)
		(end 95.645986 -46.625002)
		(stroke
			(width 0.06985)
			(type default)
		)
		(layer "In5.Cu")
	)
	(gr_line
		(start 96.11614 -38.915594)
		(end 96.12122 -38.890448)
		(stroke
			(width 0.06985)
			(type default)
		)
		(layer "In5.Cu")
	)
	(gr_line
		(start 96.12122 -38.890448)
		(end 96.134936 -38.870382)
		(stroke
			(width 0.06985)
			(type default)
		)
		(layer "In5.Cu")
	)
	(gr_line
		(start 96.205548 -52.73294)
		(end 96.212152 -52.763674)
		(stroke
			(width 0.06985)
			(type default)
		)
		(layer "In5.Cu")
	)
	(gr_line
		(start 96.205802 -52.793138)
		(end 96.212152 -52.763674)
		(stroke
			(width 0.06985)
			(type default)
		)
		(layer "In5.Cu")
	)
	(gr_line
		(start 96.716342 -46.707044)
		(end 96.72193 -46.67885)
		(stroke
			(width 0.06985)
			(type default)
		)
		(layer "In5.Cu")
	)
	(gr_line
		(start 96.716342 -46.707044)
		(end 96.722184 -46.734984)
		(stroke
			(width 0.06985)
			(type default)
		)
		(layer "In5.Cu")
	)
	(gr_line
		(start 97.021904 -39.659306)
		(end 97.027492 -39.631366)
		(stroke
			(width 0.06985)
			(type default)
		)
		(layer "In5.Cu")
	)
	(gr_line
		(start 97.027492 -39.631366)
		(end 97.043494 -39.608506)
		(stroke
			(width 0.06985)
			(type default)
		)
		(layer "In5.Cu")
	)
	(gr_line
		(start 97.222818 -52.510944)
		(end 97.228914 -52.482496)
		(stroke
			(width 0.06985)
			(type default)
		)
		(layer "In5.Cu")
	)
	(gr_line
		(start 97.222818 -52.453286)
		(end 97.228914 -52.482496)
		(stroke
			(width 0.06985)
			(type default)
		)
		(layer "In5.Cu")
	)
	(gr_line
		(start 97.222818 -52.453032)
		(end 97.222818 -52.45354)
		(stroke
			(width 0.06985)
			(type default)
		)
		(layer "In5.Cu")
	)
	(gr_line
		(start 97.714054 -46.479206)
		(end 97.719642 -46.451012)
		(stroke
			(width 0.06985)
			(type default)
		)
		(layer "In5.Cu")
	)
	(gr_line
		(start 97.714054 -46.479206)
		(end 97.719896 -46.507146)
		(stroke
			(width 0.06985)
			(type default)
		)
		(layer "In5.Cu")
	)
	(gr_line
		(start 98.031554 -40.135556)
		(end 98.037396 -40.1066)
		(stroke
			(width 0.06985)
			(type default)
		)
		(layer "In5.Cu")
	)
	(gr_line
		(start 98.037396 -40.1066)
		(end 98.054414 -40.082216)
		(stroke
			(width 0.06985)
			(type default)
		)
		(layer "In5.Cu")
	)
	(gr_line
		(start 98.201226 -28.289758)
		(end 98.217228 -28.265882)
		(stroke
			(width 0.06985)
			(type default)
		)
		(layer "In5.Cu")
	)
	(gr_line
		(start 98.217228 -28.265882)
		(end 98.241358 -28.250134)
		(stroke
			(width 0.06985)
			(type default)
		)
		(layer "In5.Cu")
	)
	(gr_line
		(start 98.319844 -52.718716)
		(end 98.32594 -52.690268)
		(stroke
			(width 0.06985)
			(type default)
		)
		(layer "In5.Cu")
	)
	(gr_line
		(start 98.319844 -52.661566)
		(end 98.32594 -52.690268)
		(stroke
			(width 0.06985)
			(type default)
		)
		(layer "In5.Cu")
	)
	(gr_line
		(start 98.901504 -40.543988)
		(end 98.906584 -40.518842)
		(stroke
			(width 0.06985)
			(type default)
		)
		(layer "In5.Cu")
	)
	(gr_line
		(start 98.906584 -40.518842)
		(end 98.920808 -40.49776)
		(stroke
			(width 0.06985)
			(type default)
		)
		(layer "In5.Cu")
	)
	(gr_line
		(start 98.975926 -28.800298)
		(end 98.990912 -28.777946)
		(stroke
			(width 0.06985)
			(type default)
		)
		(layer "In5.Cu")
	)
	(gr_line
		(start 98.990912 -28.777946)
		(end 99.013518 -28.763214)
		(stroke
			(width 0.06985)
			(type default)
		)
		(layer "In5.Cu")
	)
	(gr_line
		(start 99.322382 -52.51577)
		(end 99.328478 -52.487576)
		(stroke
			(width 0.06985)
			(type default)
		)
		(layer "In5.Cu")
	)
	(gr_line
		(start 99.322382 -52.458874)
		(end 99.328478 -52.487576)
		(stroke
			(width 0.06985)
			(type default)
		)
		(layer "In5.Cu")
	)
	(gr_line
		(start 99.589082 -29.723842)
		(end 99.605338 -29.699458)
		(stroke
			(width 0.06985)
			(type default)
		)
		(layer "In5.Cu")
	)
	(gr_line
		(start 99.605338 -29.699458)
		(end 99.63023 -29.683202)
		(stroke
			(width 0.06985)
			(type default)
		)
		(layer "In5.Cu")
	)
	(gr_line
		(start 100.333556 -38.372796)
		(end 100.348288 -38.350698)
		(stroke
			(width 0.06985)
			(type default)
		)
		(layer "In5.Cu")
	)
	(gr_line
		(start 100.348288 -38.350698)
		(end 100.370386 -38.335966)
		(stroke
			(width 0.06985)
			(type default)
		)
		(layer "In5.Cu")
	)
	(gr_line
		(start 100.436426 -30.38475)
		(end 100.452682 -30.360366)
		(stroke
			(width 0.06985)
			(type default)
		)
		(layer "In5.Cu")
	)
	(gr_line
		(start 100.452682 -30.360366)
		(end 100.477574 -30.34411)
		(stroke
			(width 0.06985)
			(type default)
		)
		(layer "In5.Cu")
	)
	(gr_line
		(start 101.071426 -31.46298)
		(end 101.087682 -31.438596)
		(stroke
			(width 0.06985)
			(type default)
		)
		(layer "In5.Cu")
	)
	(gr_line
		(start 101.087682 -31.438596)
		(end 101.112574 -31.42234)
		(stroke
			(width 0.06985)
			(type default)
		)
		(layer "In5.Cu")
	)
	(gr_line
		(start 101.821234 -37.367718)
		(end 101.87051 -37.334952)
		(stroke
			(width 0.06985)
			(type default)
		)
		(layer "In5.Cu")
	)
	(gr_line
		(start 102.103936 -32.291782)
		(end 102.117906 -32.271716)
		(stroke
			(width 0.06985)
			(type default)
		)
		(layer "In5.Cu")
	)
	(gr_line
		(start 102.117906 -32.271716)
		(end 102.13848 -32.258254)
		(stroke
			(width 0.06985)
			(type default)
		)
		(layer "In5.Cu")
	)
	(gr_line
		(start 102.660196 -25.38095)
		(end 102.707694 -25.349962)
		(stroke
			(width 0.06985)
			(type default)
		)
		(layer "In5.Cu")
	)
	(gr_line
		(start 102.85984 -33.193736)
		(end 102.873302 -33.174432)
		(stroke
			(width 0.06985)
			(type default)
		)
		(layer "In5.Cu")
	)
	(gr_line
		(start 102.873302 -33.174432)
		(end 102.892098 -33.16224)
		(stroke
			(width 0.06985)
			(type default)
		)
		(layer "In5.Cu")
	)
	(gr_line
		(start 103.013002 -26.167588)
		(end 103.060754 -26.1366)
		(stroke
			(width 0.06985)
			(type default)
		)
		(layer "In5.Cu")
	)
	(gr_line
		(start 103.637334 -28.292552)
		(end 103.655114 -28.280868)
		(stroke
			(width 0.06985)
			(type default)
		)
		(layer "In5.Cu")
	)
	(gr_line
		(start 103.655114 -28.280868)
		(end 103.676704 -28.276296)
		(stroke
			(width 0.06985)
			(type default)
		)
		(layer "In5.Cu")
	)
	(gr_line
		(start 103.821992 -26.961338)
		(end 103.86949 -26.93035)
		(stroke
			(width 0.06985)
			(type default)
		)
		(layer "In5.Cu")
	)
	(gr_line
		(start 104.415844 -29.277818)
		(end 104.435148 -29.265118)
		(stroke
			(width 0.06985)
			(type default)
		)
		(layer "In5.Cu")
	)
	(gr_line
		(start 104.435148 -29.265118)
		(end 104.457754 -29.260546)
		(stroke
			(width 0.06985)
			(type default)
		)
		(layer "In5.Cu")
	)
	(gr_line
		(start 105.391458 -30.14599)
		(end 105.41 -30.134052)
		(stroke
			(width 0.06985)
			(type default)
		)
		(layer "In5.Cu")
	)
	(gr_line
		(start 105.41 -30.134052)
		(end 105.431336 -30.12948)
		(stroke
			(width 0.06985)
			(type default)
		)
		(layer "In5.Cu")
	)
	(gr_line
		(start 105.870502 -31.227776)
		(end 105.889044 -31.215838)
		(stroke
			(width 0.06985)
			(type default)
		)
		(layer "In5.Cu")
	)
	(gr_line
		(start 105.889044 -31.215838)
		(end 105.91038 -31.211266)
		(stroke
			(width 0.06985)
			(type default)
		)
		(layer "In5.Cu")
	)
	(gr_arc
		(start 106.945938 -37.334952)
		(mid 107.054764 -37.289857)
		(end 107.099862 -37.181028)
		(stroke
			(width 0.06985)
			(type default)
		)
		(layer "In5.Cu")
	)
	(gr_arc
		(start 107.099862 -37.819076)
		(mid 107.054779 -37.710235)
		(end 106.945938 -37.665152)
		(stroke
			(width 0.06985)
			(type default)
		)
		(layer "In5.Cu")
	)
	(gr_line
		(start 107.099862 -37.819076)
		(end 107.099862 -38.200076)
		(stroke
			(width 0.06985)
			(type default)
		)
		(layer "In5.Cu")
	)
	(gr_line
		(start 107.099862 -36.800028)
		(end 107.099862 -37.181028)
		(stroke
			(width 0.06985)
			(type default)
		)
		(layer "In5.Cu")
	)
	(gr_arc
		(start 108.746036 -36.135056)
		(mid 108.854865 -36.089962)
		(end 108.89996 -35.981132)
		(stroke
			(width 0.06985)
			(type default)
		)
		(layer "In5.Cu")
	)
	(gr_arc
		(start 108.89996 -36.61918)
		(mid 108.854877 -36.510339)
		(end 108.746036 -36.465256)
		(stroke
			(width 0.06985)
			(type default)
		)
		(layer "In5.Cu")
	)
	(gr_line
		(start 108.89996 -36.61918)
		(end 108.89996 -37.00018)
		(stroke
			(width 0.06985)
			(type default)
		)
		(layer "In5.Cu")
	)
	(gr_line
		(start 108.89996 -35.600132)
		(end 108.89996 -35.981132)
		(stroke
			(width 0.06985)
			(type default)
		)
		(layer "In5.Cu")
	)
	(gr_arc
		(start 110.546134 -37.334952)
		(mid 110.654963 -37.289858)
		(end 110.700058 -37.181028)
		(stroke
			(width 0.06985)
			(type default)
		)
		(layer "In5.Cu")
	)
	(gr_arc
		(start 110.700058 -37.819076)
		(mid 110.654975 -37.710235)
		(end 110.546134 -37.665152)
		(stroke
			(width 0.06985)
			(type default)
		)
		(layer "In5.Cu")
	)
	(gr_line
		(start 110.700058 -37.819076)
		(end 110.700058 -38.200076)
		(stroke
			(width 0.06985)
			(type default)
		)
		(layer "In5.Cu")
	)
	(gr_line
		(start 110.700058 -36.800028)
		(end 110.700058 -37.181028)
		(stroke
			(width 0.06985)
			(type default)
		)
		(layer "In5.Cu")
	)
	(gr_arc
		(start 112.345978 -36.135056)
		(mid 112.454844 -36.089982)
		(end 112.499902 -35.981132)
		(stroke
			(width 0.06985)
			(type default)
		)
		(layer "In5.Cu")
	)
	(gr_arc
		(start 112.499902 -36.61918)
		(mid 112.454819 -36.510339)
		(end 112.345978 -36.465256)
		(stroke
			(width 0.06985)
			(type default)
		)
		(layer "In5.Cu")
	)
	(gr_line
		(start 112.499902 -36.61918)
		(end 112.499902 -37.00018)
		(stroke
			(width 0.06985)
			(type default)
		)
		(layer "In5.Cu")
	)
	(gr_line
		(start 112.499902 -35.600132)
		(end 112.499902 -35.981132)
		(stroke
			(width 0.06985)
			(type default)
		)
		(layer "In5.Cu")
	)
	(gr_arc
		(start 114.146076 -37.334952)
		(mid 114.254942 -37.289879)
		(end 114.3 -37.181028)
		(stroke
			(width 0.06985)
			(type default)
		)
		(layer "In5.Cu")
	)
	(gr_arc
		(start 114.3 -37.819076)
		(mid 114.254917 -37.710235)
		(end 114.146076 -37.665152)
		(stroke
			(width 0.06985)
			(type default)
		)
		(layer "In5.Cu")
	)
	(gr_line
		(start 114.3 -37.819076)
		(end 114.3 -38.200076)
		(stroke
			(width 0.06985)
			(type default)
		)
		(layer "In5.Cu")
	)
	(gr_line
		(start 114.3 -36.800028)
		(end 114.3 -37.181028)
		(stroke
			(width 0.06985)
			(type default)
		)
		(layer "In5.Cu")
	)
	(gr_arc
		(start 115.94592 -36.135056)
		(mid 116.054759 -36.089968)
		(end 116.099844 -35.981132)
		(stroke
			(width 0.06985)
			(type default)
		)
		(layer "In5.Cu")
	)
	(gr_arc
		(start 116.099844 -36.61918)
		(mid 116.054761 -36.510339)
		(end 115.94592 -36.465256)
		(stroke
			(width 0.06985)
			(type default)
		)
		(layer "In5.Cu")
	)
	(gr_line
		(start 116.099844 -36.61918)
		(end 116.099844 -37.00018)
		(stroke
			(width 0.06985)
			(type default)
		)
		(layer "In5.Cu")
	)
	(gr_line
		(start 116.099844 -35.600132)
		(end 116.099844 -35.981132)
		(stroke
			(width 0.06985)
			(type default)
		)
		(layer "In5.Cu")
	)
	(gr_arc
		(start 117.746018 -37.334952)
		(mid 117.854857 -37.289864)
		(end 117.899942 -37.181028)
		(stroke
			(width 0.06985)
			(type default)
		)
		(layer "In5.Cu")
	)
	(gr_arc
		(start 117.899942 -37.819076)
		(mid 117.854859 -37.710235)
		(end 117.746018 -37.665152)
		(stroke
			(width 0.06985)
			(type default)
		)
		(layer "In5.Cu")
	)
	(gr_line
		(start 117.899942 -37.819076)
		(end 117.899942 -38.200076)
		(stroke
			(width 0.06985)
			(type default)
		)
		(layer "In5.Cu")
	)
	(gr_line
		(start 117.899942 -36.800028)
		(end 117.899942 -37.181028)
		(stroke
			(width 0.06985)
			(type default)
		)
		(layer "In5.Cu")
	)
	(gr_arc
		(start 119.546116 -36.135056)
		(mid 119.654958 -36.089969)
		(end 119.70004 -35.981132)
		(stroke
			(width 0.06985)
			(type default)
		)
		(layer "In5.Cu")
	)
	(gr_arc
		(start 119.70004 -36.61918)
		(mid 119.654957 -36.510339)
		(end 119.546116 -36.465256)
		(stroke
			(width 0.06985)
			(type default)
		)
		(layer "In5.Cu")
	)
	(gr_line
		(start 119.70004 -36.61918)
		(end 119.70004 -37.00018)
		(stroke
			(width 0.06985)
			(type default)
		)
		(layer "In5.Cu")
	)
	(gr_line
		(start 119.70004 -35.600132)
		(end 119.70004 -35.981132)
		(stroke
			(width 0.06985)
			(type default)
		)
		(layer "In5.Cu")
	)
	(gr_line
		(start 128.467866 -26.211276)
		(end 128.550924 -26.211276)
		(stroke
			(width 0.06985)
			(type default)
		)
		(layer "In5.Cu")
	)
	(gr_arc
		(start 128.546098 -37.334952)
		(mid 128.654939 -37.289869)
		(end 128.700022 -37.181028)
		(stroke
			(width 0.06985)
			(type default)
		)
		(layer "In5.Cu")
	)
	(gr_arc
		(start 128.550924 -26.211276)
		(mid 128.7528 -26.127656)
		(end 128.83642 -25.92578)
		(stroke
			(width 0.06985)
			(type default)
		)
		(layer "In5.Cu")
	)
	(gr_arc
		(start 128.700022 -37.819076)
		(mid 128.65493 -37.710252)
		(end 128.546098 -37.665152)
		(stroke
			(width 0.06985)
			(type default)
		)
		(layer "In5.Cu")
	)
	(gr_line
		(start 128.700022 -37.819076)
		(end 128.700022 -38.200076)
		(stroke
			(width 0.06985)
			(type default)
		)
		(layer "In5.Cu")
	)
	(gr_line
		(start 128.700022 -36.800028)
		(end 128.700022 -37.181028)
		(stroke
			(width 0.06985)
			(type default)
		)
		(layer "In5.Cu")
	)
	(gr_arc
		(start 129.16662 -25.92578)
		(mid 129.250234 -26.127663)
		(end 129.452116 -26.211276)
		(stroke
			(width 0.06985)
			(type default)
		)
		(layer "In5.Cu")
	)
	(gr_line
		(start 129.452116 -26.211276)
		(end 129.535174 -26.211276)
		(stroke
			(width 0.06985)
			(type default)
		)
		(layer "In5.Cu")
	)
	(gr_arc
		(start 130.345942 -36.135056)
		(mid 130.454783 -36.089973)
		(end 130.499866 -35.981132)
		(stroke
			(width 0.06985)
			(type default)
		)
		(layer "In5.Cu")
	)
	(gr_arc
		(start 130.499866 -36.61918)
		(mid 130.454778 -36.510337)
		(end 130.345942 -36.465256)
		(stroke
			(width 0.06985)
			(type default)
		)
		(layer "In5.Cu")
	)
	(gr_line
		(start 130.499866 -36.61918)
		(end 130.499866 -37.00018)
		(stroke
			(width 0.06985)
			(type default)
		)
		(layer "In5.Cu")
	)
	(gr_line
		(start 130.499866 -35.600132)
		(end 130.499866 -35.981132)
		(stroke
			(width 0.06985)
			(type default)
		)
		(layer "In5.Cu")
	)
	(gr_arc
		(start 132.14604 -37.334952)
		(mid 132.254881 -37.289869)
		(end 132.299964 -37.181028)
		(stroke
			(width 0.06985)
			(type default)
		)
		(layer "In5.Cu")
	)
	(gr_arc
		(start 132.299964 -37.819076)
		(mid 132.254875 -37.710237)
		(end 132.14604 -37.665152)
		(stroke
			(width 0.06985)
			(type default)
		)
		(layer "In5.Cu")
	)
	(gr_line
		(start 132.299964 -37.819076)
		(end 132.299964 -38.200076)
		(stroke
			(width 0.06985)
			(type default)
		)
		(layer "In5.Cu")
	)
	(gr_line
		(start 132.299964 -36.800028)
		(end 132.299964 -37.181028)
		(stroke
			(width 0.06985)
			(type default)
		)
		(layer "In5.Cu")
	)
	(gr_arc
		(start 133.946138 -36.135056)
		(mid 134.054979 -36.089973)
		(end 134.100062 -35.981132)
		(stroke
			(width 0.06985)
			(type default)
		)
		(layer "In5.Cu")
	)
	(gr_arc
		(start 134.100062 -36.61918)
		(mid 134.054974 -36.510339)
		(end 133.946138 -36.465256)
		(stroke
			(width 0.06985)
			(type default)
		)
		(layer "In5.Cu")
	)
	(gr_line
		(start 134.100062 -36.61918)
		(end 134.100062 -37.00018)
		(stroke
			(width 0.06985)
			(type default)
		)
		(layer "In5.Cu")
	)
	(gr_line
		(start 134.100062 -35.600132)
		(end 134.100062 -35.981132)
		(stroke
			(width 0.06985)
			(type default)
		)
		(layer "In5.Cu")
	)
	(gr_arc
		(start 135.745982 -37.334952)
		(mid 135.854823 -37.289869)
		(end 135.899906 -37.181028)
		(stroke
			(width 0.06985)
			(type default)
		)
		(layer "In5.Cu")
	)
	(gr_arc
		(start 135.899906 -37.819076)
		(mid 135.854813 -37.710257)
		(end 135.745982 -37.665152)
		(stroke
			(width 0.06985)
			(type default)
		)
		(layer "In5.Cu")
	)
	(gr_line
		(start 135.899906 -37.819076)
		(end 135.899906 -38.200076)
		(stroke
			(width 0.06985)
			(type default)
		)
		(layer "In5.Cu")
	)
	(gr_line
		(start 135.899906 -36.800028)
		(end 135.899906 -37.181028)
		(stroke
			(width 0.06985)
			(type default)
		)
		(layer "In5.Cu")
	)
	(gr_line
		(start 136.310624 -20.207224)
		(end 136.358122 -20.176236)
		(stroke
			(width 0.06985)
			(type default)
		)
		(layer "In5.Cu")
	)
	(gr_arc
		(start 137.54608 -36.135056)
		(mid 137.654921 -36.089973)
		(end 137.700004 -35.981132)
		(stroke
			(width 0.06985)
			(type default)
		)
		(layer "In5.Cu")
	)
	(gr_arc
		(start 137.700004 -36.61918)
		(mid 137.654912 -36.510359)
		(end 137.54608 -36.465256)
		(stroke
			(width 0.06985)
			(type default)
		)
		(layer "In5.Cu")
	)
	(gr_line
		(start 137.700004 -36.61918)
		(end 137.700004 -37.00018)
		(stroke
			(width 0.06985)
			(type default)
		)
		(layer "In5.Cu")
	)
	(gr_line
		(start 137.700004 -35.600132)
		(end 137.700004 -35.981132)
		(stroke
			(width 0.06985)
			(type default)
		)
		(layer "In5.Cu")
	)
	(gr_arc
		(start 139.345924 -37.334952)
		(mid 139.454765 -37.289869)
		(end 139.499848 -37.181028)
		(stroke
			(width 0.06985)
			(type default)
		)
		(layer "In5.Cu")
	)
	(gr_arc
		(start 139.499848 -37.819076)
		(mid 139.454758 -37.710242)
		(end 139.345924 -37.665152)
		(stroke
			(width 0.06985)
			(type default)
		)
		(layer "In5.Cu")
	)
	(gr_line
		(start 139.499848 -37.819076)
		(end 139.499848 -38.200076)
		(stroke
			(width 0.06985)
			(type default)
		)
		(layer "In5.Cu")
	)
	(gr_line
		(start 139.499848 -36.800028)
		(end 139.499848 -37.181028)
		(stroke
			(width 0.06985)
			(type default)
		)
		(layer "In5.Cu")
	)
	(gr_arc
		(start 141.146022 -36.135056)
		(mid 141.254863 -36.089973)
		(end 141.299946 -35.981132)
		(stroke
			(width 0.06985)
			(type default)
		)
		(layer "In5.Cu")
	)
	(gr_line
		(start 141.299946 -43.819064)
		(end 141.299946 -44.200064)
		(stroke
			(width 0.06985)
			(type default)
		)
		(layer "In5.Cu")
	)
	(gr_arc
		(start 141.299946 -43.181016)
		(mid 141.345033 -43.289857)
		(end 141.45387 -43.33494)
		(stroke
			(width 0.06985)
			(type default)
		)
		(layer "In5.Cu")
	)
	(gr_line
		(start 141.299946 -42.800016)
		(end 141.299946 -43.181016)
		(stroke
			(width 0.06985)
			(type default)
		)
		(layer "In5.Cu")
	)
	(gr_arc
		(start 141.299946 -36.61918)
		(mid 141.254857 -36.510344)
		(end 141.146022 -36.465256)
		(stroke
			(width 0.06985)
			(type default)
		)
		(layer "In5.Cu")
	)
	(gr_line
		(start 141.299946 -36.61918)
		(end 141.299946 -37.00018)
		(stroke
			(width 0.06985)
			(type default)
		)
		(layer "In5.Cu")
	)
	(gr_line
		(start 141.299946 -35.600132)
		(end 141.299946 -35.981132)
		(stroke
			(width 0.06985)
			(type default)
		)
		(layer "In5.Cu")
	)
	(gr_arc
		(start 141.45387 -43.66514)
		(mid 141.345029 -43.710223)
		(end 141.299946 -43.819064)
		(stroke
			(width 0.06985)
			(type default)
		)
		(layer "In5.Cu")
	)
	(gr_line
		(start 142.243048 -29.972508)
		(end 142.26794 -29.977588)
		(stroke
			(width 0.06985)
			(type default)
		)
		(layer "In5.Cu")
	)
	(gr_line
		(start 142.26794 -29.977588)
		(end 142.288006 -29.991304)
		(stroke
			(width 0.06985)
			(type default)
		)
		(layer "In5.Cu")
	)
	(gr_line
		(start 142.608554 -43.33494)
		(end 142.634716 -43.34637)
		(stroke
			(width 0.06985)
			(type default)
		)
		(layer "In5.Cu")
	)
	(gr_line
		(start 143.131794 -28.918662)
		(end 143.15694 -28.923742)
		(stroke
			(width 0.06985)
			(type default)
		)
		(layer "In5.Cu")
	)
	(gr_line
		(start 143.15694 -28.923742)
		(end 143.177006 -28.937458)
		(stroke
			(width 0.06985)
			(type default)
		)
		(layer "In5.Cu")
	)
	(gr_line
		(start 143.76527 -27.549602)
		(end 143.7894 -27.554428)
		(stroke
			(width 0.06985)
			(type default)
		)
		(layer "In5.Cu")
	)
	(gr_line
		(start 143.7894 -27.554428)
		(end 143.809974 -27.56789)
		(stroke
			(width 0.06985)
			(type default)
		)
		(layer "In5.Cu")
	)
	(gr_line
		(start 144.758664 -26.547064)
		(end 144.78254 -26.55189)
		(stroke
			(width 0.06985)
			(type default)
		)
		(layer "In5.Cu")
	)
	(gr_line
		(start 144.78254 -26.55189)
		(end 144.80286 -26.565098)
		(stroke
			(width 0.06985)
			(type default)
		)
		(layer "In5.Cu")
	)
	(gr_line
		(start 144.841468 -44.312586)
		(end 144.87398 -44.32681)
		(stroke
			(width 0.06985)
			(type default)
		)
		(layer "In5.Cu")
	)
	(gr_line
		(start 144.87398 -44.32681)
		(end 144.897602 -44.354242)
		(stroke
			(width 0.06985)
			(type default)
		)
		(layer "In5.Cu")
	)
	(gr_line
		(start 145.4277 -33.546796)
		(end 145.479262 -33.304226)
		(stroke
			(width 0.06985)
			(type default)
		)
		(layer "In5.Cu")
	)
	(gr_line
		(start 145.4277 -33.546796)
		(end 145.655792 -33.898332)
		(stroke
			(width 0.06985)
			(type default)
		)
		(layer "In5.Cu")
	)
	(gr_line
		(start 145.655792 -33.898332)
		(end 145.898362 -33.949894)
		(stroke
			(width 0.06985)
			(type default)
		)
		(layer "In5.Cu")
	)
	(gr_line
		(start 145.708878 -25.58542)
		(end 145.7325 -25.590246)
		(stroke
			(width 0.06985)
			(type default)
		)
		(layer "In5.Cu")
	)
	(gr_line
		(start 145.7325 -25.590246)
		(end 145.75282 -25.603454)
		(stroke
			(width 0.06985)
			(type default)
		)
		(layer "In5.Cu")
	)
	(gr_line
		(start 145.778982 -33.154874)
		(end 146.156934 -33.737042)
		(stroke
			(width 0.06985)
			(type default)
		)
		(layer "In5.Cu")
	)
	(gr_line
		(start 146.077686 -34.548064)
		(end 146.129248 -34.305494)
		(stroke
			(width 0.06985)
			(type default)
		)
		(layer "In5.Cu")
	)
	(gr_line
		(start 146.077686 -34.548064)
		(end 146.306032 -34.8996)
		(stroke
			(width 0.06985)
			(type default)
		)
		(layer "In5.Cu")
	)
	(gr_line
		(start 146.147282 -30.917388)
		(end 146.171666 -30.933644)
		(stroke
			(width 0.06985)
			(type default)
		)
		(layer "In5.Cu")
	)
	(gr_line
		(start 146.171666 -30.933644)
		(end 146.187922 -30.958536)
		(stroke
			(width 0.06985)
			(type default)
		)
		(layer "In5.Cu")
	)
	(gr_line
		(start 146.306032 -34.8996)
		(end 146.548602 -34.951162)
		(stroke
			(width 0.06985)
			(type default)
		)
		(layer "In5.Cu")
	)
	(gr_line
		(start 146.42846 -34.15538)
		(end 146.80692 -34.738056)
		(stroke
			(width 0.06985)
			(type default)
		)
		(layer "In5.Cu")
	)
	(gr_line
		(start 146.727672 -35.549332)
		(end 146.779234 -35.306762)
		(stroke
			(width 0.06985)
			(type default)
		)
		(layer "In5.Cu")
	)
	(gr_line
		(start 146.727672 -35.549332)
		(end 146.956018 -35.900868)
		(stroke
			(width 0.06985)
			(type default)
		)
		(layer "In5.Cu")
	)
	(gr_line
		(start 146.956018 -35.900868)
		(end 147.198588 -35.95243)
		(stroke
			(width 0.06985)
			(type default)
		)
		(layer "In5.Cu")
	)
	(gr_line
		(start 147.0787 -35.157156)
		(end 147.456652 -35.73907)
		(stroke
			(width 0.06985)
			(type default)
		)
		(layer "In5.Cu")
	)
	(gr_line
		(start 147.117562 -24.689054)
		(end 147.140422 -24.693626)
		(stroke
			(width 0.06985)
			(type default)
		)
		(layer "In5.Cu")
	)
	(gr_line
		(start 147.140422 -24.693626)
		(end 147.15998 -24.70658)
		(stroke
			(width 0.06985)
			(type default)
		)
		(layer "In5.Cu")
	)
	(gr_line
		(start 147.262088 -33.54578)
		(end 147.313396 -33.302956)
		(stroke
			(width 0.06985)
			(type default)
		)
		(layer "In5.Cu")
	)
	(gr_line
		(start 147.262088 -33.54578)
		(end 147.49018 -33.897316)
		(stroke
			(width 0.06985)
			(type default)
		)
		(layer "In5.Cu")
	)
	(gr_line
		(start 147.49018 -33.897316)
		(end 147.733004 -33.948878)
		(stroke
			(width 0.06985)
			(type default)
		)
		(layer "In5.Cu")
	)
	(gr_line
		(start 147.520152 -30.00629)
		(end 147.544282 -30.022292)
		(stroke
			(width 0.06985)
			(type default)
		)
		(layer "In5.Cu")
	)
	(gr_line
		(start 147.544282 -30.022292)
		(end 147.559776 -30.046168)
		(stroke
			(width 0.06985)
			(type default)
		)
		(layer "In5.Cu")
	)
	(gr_line
		(start 147.6121 -33.151572)
		(end 147.9931 -33.738312)
		(stroke
			(width 0.06985)
			(type default)
		)
		(layer "In5.Cu")
	)
	(gr_line
		(start 147.82419 -23.378414)
		(end 147.844764 -23.382732)
		(stroke
			(width 0.06985)
			(type default)
		)
		(layer "In5.Cu")
	)
	(gr_line
		(start 147.844764 -23.382732)
		(end 147.863306 -23.39467)
		(stroke
			(width 0.06985)
			(type default)
		)
		(layer "In5.Cu")
	)
	(gr_line
		(start 147.912074 -34.547048)
		(end 147.963636 -34.304224)
		(stroke
			(width 0.06985)
			(type default)
		)
		(layer "In5.Cu")
	)
	(gr_line
		(start 147.912074 -34.547048)
		(end 148.14042 -34.898584)
		(stroke
			(width 0.06985)
			(type default)
		)
		(layer "In5.Cu")
	)
	(gr_line
		(start 147.93468 -31.556452)
		(end 147.986242 -31.313882)
		(stroke
			(width 0.06985)
			(type default)
		)
		(layer "In5.Cu")
	)
	(gr_line
		(start 147.93468 -31.556452)
		(end 148.163026 -31.907988)
		(stroke
			(width 0.06985)
			(type default)
		)
		(layer "In5.Cu")
	)
	(gr_line
		(start 148.14042 -34.898584)
		(end 148.383244 -34.950146)
		(stroke
			(width 0.06985)
			(type default)
		)
		(layer "In5.Cu")
	)
	(gr_line
		(start 148.163026 -31.907988)
		(end 148.405596 -31.95955)
		(stroke
			(width 0.06985)
			(type default)
		)
		(layer "In5.Cu")
	)
	(gr_line
		(start 148.26234 -34.15284)
		(end 148.64334 -34.73958)
		(stroke
			(width 0.06985)
			(type default)
		)
		(layer "In5.Cu")
	)
	(gr_line
		(start 148.286216 -31.165292)
		(end 148.664422 -31.747206)
		(stroke
			(width 0.06985)
			(type default)
		)
		(layer "In5.Cu")
	)
	(gr_line
		(start 148.477478 -22.073616)
		(end 148.498814 -22.078188)
		(stroke
			(width 0.06985)
			(type default)
		)
		(layer "In5.Cu")
	)
	(gr_line
		(start 148.498814 -22.078188)
		(end 148.517356 -22.090126)
		(stroke
			(width 0.06985)
			(type default)
		)
		(layer "In5.Cu")
	)
	(gr_line
		(start 148.562314 -35.548316)
		(end 148.613876 -35.305492)
		(stroke
			(width 0.06985)
			(type default)
		)
		(layer "In5.Cu")
	)
	(gr_line
		(start 148.562314 -35.548316)
		(end 148.79066 -35.899852)
		(stroke
			(width 0.06985)
			(type default)
		)
		(layer "In5.Cu")
	)
	(gr_line
		(start 148.58492 -32.55772)
		(end 148.636482 -32.314896)
		(stroke
			(width 0.06985)
			(type default)
		)
		(layer "In5.Cu")
	)
	(gr_line
		(start 148.58492 -32.55772)
		(end 148.813266 -32.909256)
		(stroke
			(width 0.06985)
			(type default)
		)
		(layer "In5.Cu")
	)
	(gr_line
		(start 148.767546 -37.758116)
		(end 148.778976 -37.775896)
		(stroke
			(width 0.06985)
			(type default)
		)
		(layer "In5.Cu")
	)
	(gr_line
		(start 148.778976 -37.775896)
		(end 148.78304 -37.795708)
		(stroke
			(width 0.06985)
			(type default)
		)
		(layer "In5.Cu")
	)
	(gr_line
		(start 148.79066 -35.899852)
		(end 149.03323 -35.95116)
		(stroke
			(width 0.06985)
			(type default)
		)
		(layer "In5.Cu")
	)
	(gr_line
		(start 148.813266 -32.909256)
		(end 149.055836 -32.960564)
		(stroke
			(width 0.06985)
			(type default)
		)
		(layer "In5.Cu")
	)
	(gr_line
		(start 148.91258 -35.154108)
		(end 149.292564 -35.739324)
		(stroke
			(width 0.06985)
			(type default)
		)
		(layer "In5.Cu")
	)
	(gr_line
		(start 148.917406 -20.98548)
		(end 148.937218 -20.989544)
		(stroke
			(width 0.06985)
			(type default)
		)
		(layer "In5.Cu")
	)
	(gr_line
		(start 148.936202 -32.165544)
		(end 149.314662 -32.74822)
		(stroke
			(width 0.06985)
			(type default)
		)
		(layer "In5.Cu")
	)
	(gr_line
		(start 148.937218 -20.989544)
		(end 148.954998 -21.000974)
		(stroke
			(width 0.06985)
			(type default)
		)
		(layer "In5.Cu")
	)
	(gr_line
		(start 149.23516 -33.558988)
		(end 149.286722 -33.316164)
		(stroke
			(width 0.06985)
			(type default)
		)
		(layer "In5.Cu")
	)
	(gr_line
		(start 149.23516 -33.558988)
		(end 149.463506 -33.91027)
		(stroke
			(width 0.06985)
			(type default)
		)
		(layer "In5.Cu")
	)
	(gr_line
		(start 149.301708 -29.509466)
		(end 149.325584 -29.52496)
		(stroke
			(width 0.06985)
			(type default)
		)
		(layer "In5.Cu")
	)
	(gr_line
		(start 149.325584 -29.52496)
		(end 149.341332 -29.54909)
		(stroke
			(width 0.06985)
			(type default)
		)
		(layer "In5.Cu")
	)
	(gr_line
		(start 149.361652 -49.538636)
		(end 149.390354 -49.57191)
		(stroke
			(width 0.06985)
			(type default)
		)
		(layer "In5.Cu")
	)
	(gr_line
		(start 149.390354 -49.57191)
		(end 149.399752 -49.615852)
		(stroke
			(width 0.06985)
			(type default)
		)
		(layer "In5.Cu")
	)
	(gr_line
		(start 149.463506 -33.91027)
		(end 149.706076 -33.961832)
		(stroke
			(width 0.06985)
			(type default)
		)
		(layer "In5.Cu")
	)
	(gr_line
		(start 149.586188 -33.16605)
		(end 149.965156 -33.749742)
		(stroke
			(width 0.06985)
			(type default)
		)
		(layer "In5.Cu")
	)
	(gr_line
		(start 150.438358 -37.503862)
		(end 150.449788 -37.521642)
		(stroke
			(width 0.06985)
			(type default)
		)
		(layer "In5.Cu")
	)
	(gr_line
		(start 150.449788 -37.521642)
		(end 150.453852 -37.541454)
		(stroke
			(width 0.06985)
			(type default)
		)
		(layer "In5.Cu")
	)
	(gr_line
		(start 150.476458 -28.697936)
		(end 150.500334 -28.71343)
		(stroke
			(width 0.06985)
			(type default)
		)
		(layer "In5.Cu")
	)
	(gr_line
		(start 150.500334 -28.71343)
		(end 150.516082 -28.73756)
		(stroke
			(width 0.06985)
			(type default)
		)
		(layer "In5.Cu")
	)
	(gr_line
		(start 150.645368 -32.490156)
		(end 150.69693 -32.247332)
		(stroke
			(width 0.06985)
			(type default)
		)
		(layer "In5.Cu")
	)
	(gr_line
		(start 150.645368 -32.490156)
		(end 150.873714 -32.841438)
		(stroke
			(width 0.06985)
			(type default)
		)
		(layer "In5.Cu")
	)
	(gr_line
		(start 150.873714 -32.841438)
		(end 151.116284 -32.893)
		(stroke
			(width 0.06985)
			(type default)
		)
		(layer "In5.Cu")
	)
	(gr_line
		(start 150.996904 -32.098488)
		(end 151.37384 -32.678878)
		(stroke
			(width 0.06985)
			(type default)
		)
		(layer "In5.Cu")
	)
	(gr_line
		(start 151.295608 -33.49117)
		(end 151.34717 -33.2486)
		(stroke
			(width 0.06985)
			(type default)
		)
		(layer "In5.Cu")
	)
	(gr_line
		(start 151.295608 -33.49117)
		(end 151.523954 -33.842706)
		(stroke
			(width 0.06985)
			(type default)
		)
		(layer "In5.Cu")
	)
	(gr_line
		(start 151.523954 -33.842706)
		(end 151.766524 -33.894268)
		(stroke
			(width 0.06985)
			(type default)
		)
		(layer "In5.Cu")
	)
	(gr_line
		(start 151.647652 -33.100518)
		(end 152.02408 -33.6804)
		(stroke
			(width 0.06985)
			(type default)
		)
		(layer "In5.Cu")
	)
	(gr_line
		(start 151.765 -36.521136)
		(end 151.77643 -36.538916)
		(stroke
			(width 0.06985)
			(type default)
		)
		(layer "In5.Cu")
	)
	(gr_line
		(start 151.77643 -36.538916)
		(end 151.780494 -36.558728)
		(stroke
			(width 0.06985)
			(type default)
		)
		(layer "In5.Cu")
	)
	(gr_line
		(start 151.93264 -27.823922)
		(end 151.957532 -27.840178)
		(stroke
			(width 0.06985)
			(type default)
		)
		(layer "In5.Cu")
	)
	(gr_line
		(start 151.945848 -34.492438)
		(end 151.99741 -34.249868)
		(stroke
			(width 0.06985)
			(type default)
		)
		(layer "In5.Cu")
	)
	(gr_line
		(start 151.945848 -34.492438)
		(end 152.174194 -34.843974)
		(stroke
			(width 0.06985)
			(type default)
		)
		(layer "In5.Cu")
	)
	(gr_line
		(start 151.957532 -27.840178)
		(end 151.973534 -27.86507)
		(stroke
			(width 0.06985)
			(type default)
		)
		(layer "In5.Cu")
	)
	(gr_line
		(start 152.174194 -34.843974)
		(end 152.416764 -34.895536)
		(stroke
			(width 0.06985)
			(type default)
		)
		(layer "In5.Cu")
	)
	(gr_line
		(start 152.191974 -32.251396)
		(end 152.243536 -32.008572)
		(stroke
			(width 0.06985)
			(type default)
		)
		(layer "In5.Cu")
	)
	(gr_line
		(start 152.191974 -32.251396)
		(end 152.42032 -32.602678)
		(stroke
			(width 0.06985)
			(type default)
		)
		(layer "In5.Cu")
	)
	(gr_line
		(start 152.29713 -34.100262)
		(end 152.67559 -34.683192)
		(stroke
			(width 0.06985)
			(type default)
		)
		(layer "In5.Cu")
	)
	(gr_line
		(start 152.42032 -32.602678)
		(end 152.66289 -32.65424)
		(stroke
			(width 0.06985)
			(type default)
		)
		(layer "In5.Cu")
	)
	(gr_line
		(start 152.542494 -31.857442)
		(end 152.922732 -32.442912)
		(stroke
			(width 0.06985)
			(type default)
		)
		(layer "In5.Cu")
	)
	(gr_line
		(start 152.841706 -30.13456)
		(end 152.893014 -29.891736)
		(stroke
			(width 0.06985)
			(type default)
		)
		(layer "In5.Cu")
	)
	(gr_line
		(start 152.841706 -30.13456)
		(end 153.069798 -30.486096)
		(stroke
			(width 0.06985)
			(type default)
		)
		(layer "In5.Cu")
	)
	(gr_line
		(start 152.842214 -33.252664)
		(end 152.893776 -33.00984)
		(stroke
			(width 0.06985)
			(type default)
		)
		(layer "In5.Cu")
	)
	(gr_line
		(start 152.842214 -33.252664)
		(end 153.07056 -33.603946)
		(stroke
			(width 0.06985)
			(type default)
		)
		(layer "In5.Cu")
	)
	(gr_line
		(start 153.069798 -30.486096)
		(end 153.312368 -30.537404)
		(stroke
			(width 0.06985)
			(type default)
		)
		(layer "In5.Cu")
	)
	(gr_line
		(start 153.07056 -33.603946)
		(end 153.31313 -33.655508)
		(stroke
			(width 0.06985)
			(type default)
		)
		(layer "In5.Cu")
	)
	(gr_line
		(start 153.19248 -32.858202)
		(end 153.572972 -33.44418)
		(stroke
			(width 0.06985)
			(type default)
		)
		(layer "In5.Cu")
	)
	(gr_line
		(start 153.19248 -29.741622)
		(end 153.571448 -30.325314)
		(stroke
			(width 0.06985)
			(type default)
		)
		(layer "In5.Cu")
	)
	(gr_line
		(start 153.339038 -35.704526)
		(end 153.350468 -35.722306)
		(stroke
			(width 0.06985)
			(type default)
		)
		(layer "In5.Cu")
	)
	(gr_line
		(start 153.350468 -35.722306)
		(end 153.354786 -35.742626)
		(stroke
			(width 0.06985)
			(type default)
		)
		(layer "In5.Cu")
	)
	(gr_line
		(start 153.418286 -27.002232)
		(end 153.443178 -27.018488)
		(stroke
			(width 0.06985)
			(type default)
		)
		(layer "In5.Cu")
	)
	(gr_line
		(start 153.443178 -27.018488)
		(end 153.459434 -27.04338)
		(stroke
			(width 0.06985)
			(type default)
		)
		(layer "In5.Cu")
	)
	(gr_line
		(start 153.473404 -83.757262)
		(end 153.479754 -83.786726)
		(stroke
			(width 0.06985)
			(type default)
		)
		(layer "In5.Cu")
	)
	(gr_line
		(start 153.473404 -83.757262)
		(end 153.479754 -83.727036)
		(stroke
			(width 0.06985)
			(type default)
		)
		(layer "In5.Cu")
	)
	(gr_line
		(start 153.491692 -31.135828)
		(end 153.543254 -30.893004)
		(stroke
			(width 0.06985)
			(type default)
		)
		(layer "In5.Cu")
	)
	(gr_line
		(start 153.491692 -31.135828)
		(end 153.720038 -31.48711)
		(stroke
			(width 0.06985)
			(type default)
		)
		(layer "In5.Cu")
	)
	(gr_line
		(start 153.492708 -34.253932)
		(end 153.544016 -34.011108)
		(stroke
			(width 0.06985)
			(type default)
		)
		(layer "In5.Cu")
	)
	(gr_line
		(start 153.492708 -34.253932)
		(end 153.7208 -34.605214)
		(stroke
			(width 0.06985)
			(type default)
		)
		(layer "In5.Cu")
	)
	(gr_line
		(start 153.591514 -130.364484)
		(end 153.597864 -130.393948)
		(stroke
			(width 0.06985)
			(type default)
		)
		(layer "In5.Cu")
	)
	(gr_line
		(start 153.591514 -130.364484)
		(end 153.597864 -130.334258)
		(stroke
			(width 0.06985)
			(type default)
		)
		(layer "In5.Cu")
	)
	(gr_line
		(start 153.720038 -31.48711)
		(end 153.962608 -31.538672)
		(stroke
			(width 0.06985)
			(type default)
		)
		(layer "In5.Cu")
	)
	(gr_line
		(start 153.7208 -34.605214)
		(end 153.96337 -34.656776)
		(stroke
			(width 0.06985)
			(type default)
		)
		(layer "In5.Cu")
	)
	(gr_line
		(start 153.842974 -30.743906)
		(end 154.221688 -31.326582)
		(stroke
			(width 0.06985)
			(type default)
		)
		(layer "In5.Cu")
	)
	(gr_line
		(start 153.843228 -33.860486)
		(end 154.222704 -34.44494)
		(stroke
			(width 0.06985)
			(type default)
		)
		(layer "In5.Cu")
	)
	(gr_line
		(start 154.109674 -28.977844)
		(end 154.161236 -28.735274)
		(stroke
			(width 0.06985)
			(type default)
		)
		(layer "In5.Cu")
	)
	(gr_line
		(start 154.109674 -28.977844)
		(end 154.33802 -29.32938)
		(stroke
			(width 0.06985)
			(type default)
		)
		(layer "In5.Cu")
	)
	(gr_line
		(start 154.141932 -32.136842)
		(end 154.193494 -31.894272)
		(stroke
			(width 0.06985)
			(type default)
		)
		(layer "In5.Cu")
	)
	(gr_line
		(start 154.141932 -32.136842)
		(end 154.370278 -32.488378)
		(stroke
			(width 0.06985)
			(type default)
		)
		(layer "In5.Cu")
	)
	(gr_line
		(start 154.33802 -29.32938)
		(end 154.58059 -29.380942)
		(stroke
			(width 0.06985)
			(type default)
		)
		(layer "In5.Cu")
	)
	(gr_line
		(start 154.370278 -32.488378)
		(end 154.612848 -32.53994)
		(stroke
			(width 0.06985)
			(type default)
		)
		(layer "In5.Cu")
	)
	(gr_line
		(start 154.46121 -28.58643)
		(end 154.838908 -29.16809)
		(stroke
			(width 0.06985)
			(type default)
		)
		(layer "In5.Cu")
	)
	(gr_line
		(start 154.493214 -31.745174)
		(end 154.871928 -32.32785)
		(stroke
			(width 0.06985)
			(type default)
		)
		(layer "In5.Cu")
	)
	(gr_line
		(start 154.759914 -29.979112)
		(end 154.811476 -29.736796)
		(stroke
			(width 0.06985)
			(type default)
		)
		(layer "In5.Cu")
	)
	(gr_line
		(start 154.759914 -29.979112)
		(end 154.988006 -30.330648)
		(stroke
			(width 0.06985)
			(type default)
		)
		(layer "In5.Cu")
	)
	(gr_line
		(start 154.905964 -26.239978)
		(end 154.930602 -26.25598)
		(stroke
			(width 0.06985)
			(type default)
		)
		(layer "In5.Cu")
	)
	(gr_line
		(start 154.930602 -26.25598)
		(end 154.946858 -26.280872)
		(stroke
			(width 0.06985)
			(type default)
		)
		(layer "In5.Cu")
	)
	(gr_line
		(start 154.988006 -30.330648)
		(end 155.230576 -30.38221)
		(stroke
			(width 0.06985)
			(type default)
		)
		(layer "In5.Cu")
	)
	(gr_line
		(start 155.11145 -29.587952)
		(end 155.489656 -30.169866)
		(stroke
			(width 0.06985)
			(type default)
		)
		(layer "In5.Cu")
	)
	(gr_line
		(start 155.227528 -35.992308)
		(end 155.238958 -36.010088)
		(stroke
			(width 0.06985)
			(type default)
		)
		(layer "In5.Cu")
	)
	(gr_line
		(start 155.227782 -77.032612)
		(end 155.234386 -77.063346)
		(stroke
			(width 0.06985)
			(type default)
		)
		(layer "In5.Cu")
	)
	(gr_line
		(start 155.228036 -77.09281)
		(end 155.234386 -77.063346)
		(stroke
			(width 0.06985)
			(type default)
		)
		(layer "In5.Cu")
	)
	(gr_line
		(start 155.238958 -36.010088)
		(end 155.243022 -36.0299)
		(stroke
			(width 0.06985)
			(type default)
		)
		(layer "In5.Cu")
	)
	(gr_line
		(start 155.28544 -131.146804)
		(end 155.290012 -131.17068)
		(stroke
			(width 0.06985)
			(type default)
		)
		(layer "In5.Cu")
	)
	(gr_line
		(start 155.28544 -131.146804)
		(end 155.290012 -131.123182)
		(stroke
			(width 0.06985)
			(type default)
		)
		(layer "In5.Cu")
	)
	(gr_line
		(start 155.290012 -131.122928)
		(end 155.290266 -131.121912)
		(stroke
			(width 0.06985)
			(type default)
		)
		(layer "In5.Cu")
	)
	(gr_line
		(start 155.399994 -83.331558)
		(end 155.406344 -83.361022)
		(stroke
			(width 0.06985)
			(type default)
		)
		(layer "In5.Cu")
	)
	(gr_line
		(start 155.399994 -83.331558)
		(end 155.406598 -83.300824)
		(stroke
			(width 0.06985)
			(type default)
		)
		(layer "In5.Cu")
	)
	(gr_line
		(start 155.4099 -30.98038)
		(end 155.461462 -30.73781)
		(stroke
			(width 0.06985)
			(type default)
		)
		(layer "In5.Cu")
	)
	(gr_line
		(start 155.4099 -30.98038)
		(end 155.638246 -31.331916)
		(stroke
			(width 0.06985)
			(type default)
		)
		(layer "In5.Cu")
	)
	(gr_line
		(start 155.6004 -139.813792)
		(end 155.604464 -139.833604)
		(stroke
			(width 0.06985)
			(type default)
		)
		(layer "In5.Cu")
	)
	(gr_line
		(start 155.604464 -139.833604)
		(end 155.615894 -139.851384)
		(stroke
			(width 0.06985)
			(type default)
		)
		(layer "In5.Cu")
	)
	(gr_line
		(start 155.638246 -31.331916)
		(end 155.880816 -31.383478)
		(stroke
			(width 0.06985)
			(type default)
		)
		(layer "In5.Cu")
	)
	(gr_line
		(start 155.6766 -25.366472)
		(end 155.701492 -25.382728)
		(stroke
			(width 0.06985)
			(type default)
		)
		(layer "In5.Cu")
	)
	(gr_line
		(start 155.701492 -25.382728)
		(end 155.717748 -25.40762)
		(stroke
			(width 0.06985)
			(type default)
		)
		(layer "In5.Cu")
	)
	(gr_line
		(start 155.76042 -30.58668)
		(end 156.140404 -31.171896)
		(stroke
			(width 0.06985)
			(type default)
		)
		(layer "In5.Cu")
	)
	(gr_line
		(start 155.785312 -28.504896)
		(end 155.836874 -28.26258)
		(stroke
			(width 0.06985)
			(type default)
		)
		(layer "In5.Cu")
	)
	(gr_line
		(start 155.785312 -28.504896)
		(end 156.013404 -28.856432)
		(stroke
			(width 0.06985)
			(type default)
		)
		(layer "In5.Cu")
	)
	(gr_line
		(start 156.013404 -28.856432)
		(end 156.256228 -28.907994)
		(stroke
			(width 0.06985)
			(type default)
		)
		(layer "In5.Cu")
	)
	(gr_line
		(start 156.06014 -31.981648)
		(end 156.111702 -31.739078)
		(stroke
			(width 0.06985)
			(type default)
		)
		(layer "In5.Cu")
	)
	(gr_line
		(start 156.06014 -31.981648)
		(end 156.288486 -32.333184)
		(stroke
			(width 0.06985)
			(type default)
		)
		(layer "In5.Cu")
	)
	(gr_line
		(start 156.137356 -28.114498)
		(end 156.514546 -28.695142)
		(stroke
			(width 0.06985)
			(type default)
		)
		(layer "In5.Cu")
	)
	(gr_line
		(start 156.288486 -32.333184)
		(end 156.531056 -32.384746)
		(stroke
			(width 0.06985)
			(type default)
		)
		(layer "In5.Cu")
	)
	(gr_line
		(start 156.410914 -31.588964)
		(end 156.790136 -32.172656)
		(stroke
			(width 0.06985)
			(type default)
		)
		(layer "In5.Cu")
	)
	(gr_line
		(start 156.435552 -29.506164)
		(end 156.48686 -29.263594)
		(stroke
			(width 0.06985)
			(type default)
		)
		(layer "In5.Cu")
	)
	(gr_line
		(start 156.435552 -29.506164)
		(end 156.663644 -29.8577)
		(stroke
			(width 0.06985)
			(type default)
		)
		(layer "In5.Cu")
	)
	(gr_line
		(start 156.499306 -131.470908)
		(end 156.503878 -131.494784)
		(stroke
			(width 0.06985)
			(type default)
		)
		(layer "In5.Cu")
	)
	(gr_line
		(start 156.499306 -131.470908)
		(end 156.503878 -131.447286)
		(stroke
			(width 0.06985)
			(type default)
		)
		(layer "In5.Cu")
	)
	(gr_line
		(start 156.503878 -131.447032)
		(end 156.504132 -131.446016)
		(stroke
			(width 0.06985)
			(type default)
		)
		(layer "In5.Cu")
	)
	(gr_line
		(start 156.663644 -29.8577)
		(end 156.906468 -29.909262)
		(stroke
			(width 0.06985)
			(type default)
		)
		(layer "In5.Cu")
	)
	(gr_line
		(start 156.785564 -29.111956)
		(end 157.165548 -29.697172)
		(stroke
			(width 0.06985)
			(type default)
		)
		(layer "In5.Cu")
	)
	(gr_line
		(start 156.802328 -35.300412)
		(end 156.813758 -35.318192)
		(stroke
			(width 0.06985)
			(type default)
		)
		(layer "In5.Cu")
	)
	(gr_line
		(start 156.813758 -35.318192)
		(end 156.817822 -35.338004)
		(stroke
			(width 0.06985)
			(type default)
		)
		(layer "In5.Cu")
	)
	(gr_line
		(start 156.890212 -139.40282)
		(end 156.895038 -139.428474)
		(stroke
			(width 0.06985)
			(type default)
		)
		(layer "In5.Cu")
	)
	(gr_line
		(start 156.895038 -139.428474)
		(end 156.90977 -139.450064)
		(stroke
			(width 0.06985)
			(type default)
		)
		(layer "In5.Cu")
	)
	(gr_line
		(start 157.05709 -83.991958)
		(end 157.06344 -84.021422)
		(stroke
			(width 0.06985)
			(type default)
		)
		(layer "In5.Cu")
	)
	(gr_line
		(start 157.05709 -83.991958)
		(end 157.063694 -83.961224)
		(stroke
			(width 0.06985)
			(type default)
		)
		(layer "In5.Cu")
	)
	(gr_line
		(start 157.085538 -30.507432)
		(end 157.1371 -30.264862)
		(stroke
			(width 0.06985)
			(type default)
		)
		(layer "In5.Cu")
	)
	(gr_line
		(start 157.085538 -30.507432)
		(end 157.313884 -30.858968)
		(stroke
			(width 0.06985)
			(type default)
		)
		(layer "In5.Cu")
	)
	(gr_line
		(start 157.093158 -76.891134)
		(end 157.099762 -76.921868)
		(stroke
			(width 0.06985)
			(type default)
		)
		(layer "In5.Cu")
	)
	(gr_line
		(start 157.093412 -76.951332)
		(end 157.099762 -76.921868)
		(stroke
			(width 0.06985)
			(type default)
		)
		(layer "In5.Cu")
	)
	(gr_line
		(start 157.313884 -30.858968)
		(end 157.556708 -30.91053)
		(stroke
			(width 0.06985)
			(type default)
		)
		(layer "In5.Cu")
	)
	(gr_line
		(start 157.436312 -30.11424)
		(end 157.816296 -30.699202)
		(stroke
			(width 0.06985)
			(type default)
		)
		(layer "In5.Cu")
	)
	(gr_line
		(start 157.685486 -131.972304)
		(end 157.690058 -131.99618)
		(stroke
			(width 0.06985)
			(type default)
		)
		(layer "In5.Cu")
	)
	(gr_line
		(start 157.685486 -131.972304)
		(end 157.690312 -131.948174)
		(stroke
			(width 0.06985)
			(type default)
		)
		(layer "In5.Cu")
	)
	(gr_line
		(start 157.946598 -143.44015)
		(end 157.962854 -143.465042)
		(stroke
			(width 0.06985)
			(type default)
		)
		(layer "In5.Cu")
	)
	(gr_line
		(start 157.957774 -138.972036)
		(end 157.9626 -138.99769)
		(stroke
			(width 0.06985)
			(type default)
		)
		(layer "In5.Cu")
	)
	(gr_line
		(start 157.9626 -138.99769)
		(end 157.977332 -139.01928)
		(stroke
			(width 0.06985)
			(type default)
		)
		(layer "In5.Cu")
	)
	(gr_line
		(start 157.962854 -143.465042)
		(end 157.987746 -143.481298)
		(stroke
			(width 0.06985)
			(type default)
		)
		(layer "In5.Cu")
	)
	(gr_line
		(start 158.179516 -34.312352)
		(end 158.190946 -34.330132)
		(stroke
			(width 0.06985)
			(type default)
		)
		(layer "In5.Cu")
	)
	(gr_line
		(start 158.190946 -34.330132)
		(end 158.19501 -34.349944)
		(stroke
			(width 0.06985)
			(type default)
		)
		(layer "In5.Cu")
	)
	(gr_line
		(start 158.77159 -84.423504)
		(end 158.77794 -84.452968)
		(stroke
			(width 0.06985)
			(type default)
		)
		(layer "In5.Cu")
	)
	(gr_line
		(start 158.77159 -84.423504)
		(end 158.778194 -84.39277)
		(stroke
			(width 0.06985)
			(type default)
		)
		(layer "In5.Cu")
	)
	(gr_line
		(start 158.80334 -142.257526)
		(end 158.81731 -142.2781)
		(stroke
			(width 0.06985)
			(type default)
		)
		(layer "In5.Cu")
	)
	(gr_line
		(start 158.81731 -142.2781)
		(end 158.837884 -142.29207)
		(stroke
			(width 0.06985)
			(type default)
		)
		(layer "In5.Cu")
	)
	(gr_line
		(start 158.818072 -107.368848)
		(end 158.824422 -107.339384)
		(stroke
			(width 0.06985)
			(type default)
		)
		(layer "In5.Cu")
	)
	(gr_line
		(start 158.818072 -107.309158)
		(end 158.824422 -107.339384)
		(stroke
			(width 0.06985)
			(type default)
		)
		(layer "In5.Cu")
	)
	(gr_line
		(start 158.853886 -77.0636)
		(end 158.86049 -77.094334)
		(stroke
			(width 0.06985)
			(type default)
		)
		(layer "In5.Cu")
	)
	(gr_line
		(start 158.85414 -77.123798)
		(end 158.86049 -77.094334)
		(stroke
			(width 0.06985)
			(type default)
		)
		(layer "In5.Cu")
	)
	(gr_line
		(start 158.933896 -138.397488)
		(end 158.938976 -138.42365)
		(stroke
			(width 0.06985)
			(type default)
		)
		(layer "In5.Cu")
	)
	(gr_line
		(start 158.938468 -132.380482)
		(end 158.94304 -132.404358)
		(stroke
			(width 0.06985)
			(type default)
		)
		(layer "In5.Cu")
	)
	(gr_line
		(start 158.938468 -132.380482)
		(end 158.943294 -132.356606)
		(stroke
			(width 0.06985)
			(type default)
		)
		(layer "In5.Cu")
	)
	(gr_line
		(start 158.938976 -138.42365)
		(end 158.953708 -138.44524)
		(stroke
			(width 0.06985)
			(type default)
		)
		(layer "In5.Cu")
	)
	(gr_line
		(start 159.586422 -33.42513)
		(end 159.597852 -33.44291)
		(stroke
			(width 0.06985)
			(type default)
		)
		(layer "In5.Cu")
	)
	(gr_line
		(start 159.597852 -33.44291)
		(end 159.601916 -33.462722)
		(stroke
			(width 0.06985)
			(type default)
		)
		(layer "In5.Cu")
	)
	(gr_line
		(start 159.625538 -141.463522)
		(end 159.639508 -141.484096)
		(stroke
			(width 0.06985)
			(type default)
		)
		(layer "In5.Cu")
	)
	(gr_line
		(start 159.639508 -141.484096)
		(end 159.660082 -141.498066)
		(stroke
			(width 0.06985)
			(type default)
		)
		(layer "In5.Cu")
	)
	(gr_line
		(start 160.011872 -137.901426)
		(end 160.016698 -137.92708)
		(stroke
			(width 0.06985)
			(type default)
		)
		(layer "In5.Cu")
	)
	(gr_line
		(start 160.016698 -137.92708)
		(end 160.03143 -137.94867)
		(stroke
			(width 0.06985)
			(type default)
		)
		(layer "In5.Cu")
	)
	(gr_line
		(start 160.212532 -133.195822)
		(end 160.217104 -133.219952)
		(stroke
			(width 0.06985)
			(type default)
		)
		(layer "In5.Cu")
	)
	(gr_line
		(start 160.212532 -133.195822)
		(end 160.217358 -133.170676)
		(stroke
			(width 0.06985)
			(type default)
		)
		(layer "In5.Cu")
	)
	(gr_line
		(start 160.525714 -77.6986)
		(end 160.532318 -77.729334)
		(stroke
			(width 0.06985)
			(type default)
		)
		(layer "In5.Cu")
	)
	(gr_line
		(start 160.525968 -77.758798)
		(end 160.532318 -77.729334)
		(stroke
			(width 0.06985)
			(type default)
		)
		(layer "In5.Cu")
	)
	(gr_line
		(start 160.532064 -84.686648)
		(end 160.538414 -84.716112)
		(stroke
			(width 0.06985)
			(type default)
		)
		(layer "In5.Cu")
	)
	(gr_line
		(start 160.532064 -84.686648)
		(end 160.538668 -84.655914)
		(stroke
			(width 0.06985)
			(type default)
		)
		(layer "In5.Cu")
	)
	(gr_line
		(start 160.554924 -105.994454)
		(end 160.560512 -106.020616)
		(stroke
			(width 0.06985)
			(type default)
		)
		(layer "In5.Cu")
	)
	(gr_line
		(start 160.555432 -106.046778)
		(end 160.560512 -106.020616)
		(stroke
			(width 0.06985)
			(type default)
		)
		(layer "In5.Cu")
	)
	(gr_line
		(start 160.661604 -140.97762)
		(end 160.675574 -140.998194)
		(stroke
			(width 0.06985)
			(type default)
		)
		(layer "In5.Cu")
	)
	(gr_line
		(start 160.675574 -140.998194)
		(end 160.696148 -141.012164)
		(stroke
			(width 0.06985)
			(type default)
		)
		(layer "In5.Cu")
	)
	(gr_line
		(start 160.757108 -33.167066)
		(end 160.768538 -33.184846)
		(stroke
			(width 0.06985)
			(type default)
		)
		(layer "In5.Cu")
	)
	(gr_line
		(start 160.768538 -33.184846)
		(end 160.772602 -33.204658)
		(stroke
			(width 0.06985)
			(type default)
		)
		(layer "In5.Cu")
	)
	(gr_line
		(start 161.038794 -137.445496)
		(end 161.04362 -137.47115)
		(stroke
			(width 0.06985)
			(type default)
		)
		(layer "In5.Cu")
	)
	(gr_line
		(start 161.04362 -137.47115)
		(end 161.058352 -137.49274)
		(stroke
			(width 0.06985)
			(type default)
		)
		(layer "In5.Cu")
	)
	(gr_line
		(start 161.2773 -132.545074)
		(end 161.282126 -132.57022)
		(stroke
			(width 0.06985)
			(type default)
		)
		(layer "In5.Cu")
	)
	(gr_line
		(start 161.2773 -132.545074)
		(end 161.28238 -132.520182)
		(stroke
			(width 0.06985)
			(type default)
		)
		(layer "In5.Cu")
	)
	(gr_line
		(start 161.56051 -140.216128)
		(end 161.57448 -140.236702)
		(stroke
			(width 0.06985)
			(type default)
		)
		(layer "In5.Cu")
	)
	(gr_line
		(start 161.57448 -140.236702)
		(end 161.595054 -140.250672)
		(stroke
			(width 0.06985)
			(type default)
		)
		(layer "In5.Cu")
	)
	(gr_line
		(start 161.946336 -105.409746)
		(end 161.951924 -105.435908)
		(stroke
			(width 0.06985)
			(type default)
		)
		(layer "In5.Cu")
	)
	(gr_line
		(start 161.946844 -105.462324)
		(end 161.951924 -105.435908)
		(stroke
			(width 0.06985)
			(type default)
		)
		(layer "In5.Cu")
	)
	(gr_line
		(start 162.086544 -146.142964)
		(end 162.104324 -146.154394)
		(stroke
			(width 0.06985)
			(type default)
		)
		(layer "In5.Cu")
	)
	(gr_line
		(start 162.101784 -136.773412)
		(end 162.10661 -136.799066)
		(stroke
			(width 0.06985)
			(type default)
		)
		(layer "In5.Cu")
	)
	(gr_line
		(start 162.104324 -146.154394)
		(end 162.124136 -146.158458)
		(stroke
			(width 0.06985)
			(type default)
		)
		(layer "In5.Cu")
	)
	(gr_line
		(start 162.10661 -136.799066)
		(end 162.121342 -136.820656)
		(stroke
			(width 0.06985)
			(type default)
		)
		(layer "In5.Cu")
	)
	(gr_line
		(start 162.257486 -84.853526)
		(end 162.263836 -84.88299)
		(stroke
			(width 0.06985)
			(type default)
		)
		(layer "In5.Cu")
	)
	(gr_line
		(start 162.257486 -84.853526)
		(end 162.26409 -84.822792)
		(stroke
			(width 0.06985)
			(type default)
		)
		(layer "In5.Cu")
	)
	(gr_line
		(start 162.299142 -77.900784)
		(end 162.305746 -77.931518)
		(stroke
			(width 0.06985)
			(type default)
		)
		(layer "In5.Cu")
	)
	(gr_line
		(start 162.299396 -77.960982)
		(end 162.305746 -77.931518)
		(stroke
			(width 0.06985)
			(type default)
		)
		(layer "In5.Cu")
	)
	(gr_line
		(start 162.469068 -139.584938)
		(end 162.483038 -139.605512)
		(stroke
			(width 0.06985)
			(type default)
		)
		(layer "In5.Cu")
	)
	(gr_line
		(start 162.483038 -139.605512)
		(end 162.503612 -139.619482)
		(stroke
			(width 0.06985)
			(type default)
		)
		(layer "In5.Cu")
	)
	(gr_line
		(start 162.483038 -132.910072)
		(end 162.487864 -132.935218)
		(stroke
			(width 0.06985)
			(type default)
		)
		(layer "In5.Cu")
	)
	(gr_line
		(start 162.483038 -132.910072)
		(end 162.488118 -132.88518)
		(stroke
			(width 0.06985)
			(type default)
		)
		(layer "In5.Cu")
	)
	(gr_line
		(start 162.488118 -132.884672)
		(end 162.488118 -132.88518)
		(stroke
			(width 0.06985)
			(type default)
		)
		(layer "In5.Cu")
	)
	(gr_line
		(start 162.806634 -144.968722)
		(end 162.828224 -144.983454)
		(stroke
			(width 0.06985)
			(type default)
		)
		(layer "In5.Cu")
	)
	(gr_line
		(start 162.828224 -144.983454)
		(end 162.853878 -144.98828)
		(stroke
			(width 0.06985)
			(type default)
		)
		(layer "In5.Cu")
	)
	(gr_line
		(start 163.126166 -136.217406)
		(end 163.130992 -136.24306)
		(stroke
			(width 0.06985)
			(type default)
		)
		(layer "In5.Cu")
	)
	(gr_line
		(start 163.130992 -136.24306)
		(end 163.145724 -136.26465)
		(stroke
			(width 0.06985)
			(type default)
		)
		(layer "In5.Cu")
	)
	(gr_line
		(start 163.383468 -144.009364)
		(end 163.403788 -144.02308)
		(stroke
			(width 0.06985)
			(type default)
		)
		(layer "In5.Cu")
	)
	(gr_line
		(start 163.397184 -104.593898)
		(end 163.402772 -104.62006)
		(stroke
			(width 0.06985)
			(type default)
		)
		(layer "In5.Cu")
	)
	(gr_line
		(start 163.397692 -104.646222)
		(end 163.402772 -104.62006)
		(stroke
			(width 0.06985)
			(type default)
		)
		(layer "In5.Cu")
	)
	(gr_line
		(start 163.403788 -144.02308)
		(end 163.427664 -144.02816)
		(stroke
			(width 0.06985)
			(type default)
		)
		(layer "In5.Cu")
	)
	(gr_line
		(start 163.475416 -138.829034)
		(end 163.489386 -138.849608)
		(stroke
			(width 0.06985)
			(type default)
		)
		(layer "In5.Cu")
	)
	(gr_line
		(start 163.489386 -138.849608)
		(end 163.50996 -138.863578)
		(stroke
			(width 0.06985)
			(type default)
		)
		(layer "In5.Cu")
	)
	(gr_line
		(start 163.612322 -132.754878)
		(end 163.617402 -132.781294)
		(stroke
			(width 0.06985)
			(type default)
		)
		(layer "In5.Cu")
	)
	(gr_line
		(start 163.612322 -132.754878)
		(end 163.61791 -132.728462)
		(stroke
			(width 0.06985)
			(type default)
		)
		(layer "In5.Cu")
	)
	(gr_line
		(start 163.61791 -132.728208)
		(end 163.61791 -132.728462)
		(stroke
			(width 0.06985)
			(type default)
		)
		(layer "In5.Cu")
	)
	(gr_line
		(start 164.04844 -85.565742)
		(end 164.05479 -85.595206)
		(stroke
			(width 0.06985)
			(type default)
		)
		(layer "In5.Cu")
	)
	(gr_line
		(start 164.04844 -85.565742)
		(end 164.055044 -85.535008)
		(stroke
			(width 0.06985)
			(type default)
		)
		(layer "In5.Cu")
	)
	(gr_line
		(start 164.10178 -77.704696)
		(end 164.108384 -77.73543)
		(stroke
			(width 0.06985)
			(type default)
		)
		(layer "In5.Cu")
	)
	(gr_line
		(start 164.102034 -77.764894)
		(end 164.108384 -77.73543)
		(stroke
			(width 0.06985)
			(type default)
		)
		(layer "In5.Cu")
	)
	(gr_line
		(start 164.143436 -143.33728)
		(end 164.163756 -143.350996)
		(stroke
			(width 0.06985)
			(type default)
		)
		(layer "In5.Cu")
	)
	(gr_line
		(start 164.163756 -143.350996)
		(end 164.187632 -143.356076)
		(stroke
			(width 0.06985)
			(type default)
		)
		(layer "In5.Cu")
	)
	(gr_line
		(start 164.211 -135.83666)
		(end 164.22243 -135.896604)
		(stroke
			(width 0.06985)
			(type default)
		)
		(layer "In5.Cu")
	)
	(gr_line
		(start 164.22243 -135.896604)
		(end 164.251894 -135.926068)
		(stroke
			(width 0.06985)
			(type default)
		)
		(layer "In5.Cu")
	)
	(gr_arc
		(start 164.251894 -135.926068)
		(mid 164.252274 -135.92645)
		(end 164.252656 -135.92683)
		(stroke
			(width 0.06985)
			(type default)
		)
		(layer "In5.Cu")
	)
	(gr_line
		(start 164.252656 -135.92683)
		(end 164.266372 -135.940546)
		(stroke
			(width 0.06985)
			(type default)
		)
		(layer "In5.Cu")
	)
	(gr_line
		(start 164.416486 -138.149076)
		(end 164.430456 -138.16965)
		(stroke
			(width 0.06985)
			(type default)
		)
		(layer "In5.Cu")
	)
	(gr_line
		(start 164.430456 -138.16965)
		(end 164.45103 -138.18362)
		(stroke
			(width 0.06985)
			(type default)
		)
		(layer "In5.Cu")
	)
	(gr_line
		(start 164.86505 -142.4559)
		(end 164.884862 -142.469362)
		(stroke
			(width 0.06985)
			(type default)
		)
		(layer "In5.Cu")
	)
	(gr_line
		(start 164.884862 -142.469362)
		(end 164.908992 -142.474442)
		(stroke
			(width 0.06985)
			(type default)
		)
		(layer "In5.Cu")
	)
	(gr_line
		(start 164.915596 -103.734362)
		(end 164.921692 -103.762556)
		(stroke
			(width 0.06985)
			(type default)
		)
		(layer "In5.Cu")
	)
	(gr_line
		(start 164.916104 -103.790496)
		(end 164.921692 -103.762556)
		(stroke
			(width 0.06985)
			(type default)
		)
		(layer "In5.Cu")
	)
	(gr_line
		(start 165.36162 -141.547088)
		(end 165.38194 -141.560804)
		(stroke
			(width 0.06985)
			(type default)
		)
		(layer "In5.Cu")
	)
	(gr_line
		(start 165.38194 -141.560804)
		(end 165.405816 -141.565884)
		(stroke
			(width 0.06985)
			(type default)
		)
		(layer "In5.Cu")
	)
	(gr_line
		(start 165.800024 -85.839554)
		(end 165.806374 -85.869018)
		(stroke
			(width 0.06985)
			(type default)
		)
		(layer "In5.Cu")
	)
	(gr_line
		(start 165.800024 -85.839554)
		(end 165.806374 -85.809328)
		(stroke
			(width 0.06985)
			(type default)
		)
		(layer "In5.Cu")
	)
	(gr_line
		(start 165.933374 -78.222348)
		(end 165.939978 -78.253082)
		(stroke
			(width 0.06985)
			(type default)
		)
		(layer "In5.Cu")
	)
	(gr_line
		(start 165.933628 -78.282546)
		(end 165.939978 -78.253082)
		(stroke
			(width 0.06985)
			(type default)
		)
		(layer "In5.Cu")
	)
	(gr_line
		(start 166.23665 -140.703046)
		(end 166.260018 -140.718794)
		(stroke
			(width 0.06985)
			(type default)
		)
		(layer "In5.Cu")
	)
	(gr_line
		(start 166.260018 -140.718794)
		(end 166.28745 -140.724382)
		(stroke
			(width 0.06985)
			(type default)
		)
		(layer "In5.Cu")
	)
	(gr_line
		(start 166.428928 -102.891844)
		(end 166.434516 -102.918006)
		(stroke
			(width 0.06985)
			(type default)
		)
		(layer "In5.Cu")
	)
	(gr_line
		(start 166.428928 -102.891336)
		(end 166.428928 -102.89159)
		(stroke
			(width 0.06985)
			(type default)
		)
		(layer "In5.Cu")
	)
	(gr_line
		(start 166.429436 -102.944422)
		(end 166.434516 -102.918006)
		(stroke
			(width 0.06985)
			(type default)
		)
		(layer "In5.Cu")
	)
	(gr_line
		(start 167.0304 -139.923266)
		(end 167.053006 -139.938506)
		(stroke
			(width 0.06985)
			(type default)
		)
		(layer "In5.Cu")
	)
	(gr_line
		(start 167.053006 -139.938506)
		(end 167.07993 -139.94384)
		(stroke
			(width 0.06985)
			(type default)
		)
		(layer "In5.Cu")
	)
	(gr_line
		(start 167.111934 -136.906)
		(end 167.201596 -136.995662)
		(stroke
			(width 0.06985)
			(type default)
		)
		(layer "In5.Cu")
	)
	(gr_arc
		(start 167.201596 -137.210546)
		(mid 167.246116 -137.103103)
		(end 167.201596 -136.995662)
		(stroke
			(width 0.06985)
			(type default)
		)
		(layer "In5.Cu")
	)
	(gr_line
		(start 167.46474 -86.288118)
		(end 167.47109 -86.317582)
		(stroke
			(width 0.06985)
			(type default)
		)
		(layer "In5.Cu")
	)
	(gr_line
		(start 167.46474 -86.288118)
		(end 167.471344 -86.257384)
		(stroke
			(width 0.06985)
			(type default)
		)
		(layer "In5.Cu")
	)
	(gr_line
		(start 167.631364 -78.752192)
		(end 167.637968 -78.782926)
		(stroke
			(width 0.06985)
			(type default)
		)
		(layer "In5.Cu")
	)
	(gr_line
		(start 167.631618 -78.81239)
		(end 167.637968 -78.782926)
		(stroke
			(width 0.06985)
			(type default)
		)
		(layer "In5.Cu")
	)
	(gr_arc
		(start 167.650668 -137.444734)
		(mid 167.542718 -137.40002)
		(end 167.434768 -137.444734)
		(stroke
			(width 0.06985)
			(type default)
		)
		(layer "In5.Cu")
	)
	(gr_line
		(start 167.650668 -137.444734)
		(end 167.74033 -137.534396)
		(stroke
			(width 0.06985)
			(type default)
		)
		(layer "In5.Cu")
	)
	(gr_line
		(start 167.869616 -101.95433)
		(end 167.875966 -101.983794)
		(stroke
			(width 0.06985)
			(type default)
		)
		(layer "In5.Cu")
	)
	(gr_line
		(start 167.86987 -102.01275)
		(end 167.875966 -101.983794)
		(stroke
			(width 0.06985)
			(type default)
		)
		(layer "In5.Cu")
	)
	(gr_line
		(start 168.125648 -117.540278)
		(end 168.131998 -117.569742)
		(stroke
			(width 0.06985)
			(type default)
		)
		(layer "In5.Cu")
	)
	(gr_line
		(start 168.125648 -117.540278)
		(end 168.132252 -117.509544)
		(stroke
			(width 0.06985)
			(type default)
		)
		(layer "In5.Cu")
	)
	(gr_line
		(start 168.889934 -87.105236)
		(end 168.896284 -87.1347)
		(stroke
			(width 0.06985)
			(type default)
		)
		(layer "In5.Cu")
	)
	(gr_line
		(start 168.889934 -87.105236)
		(end 168.896538 -87.074502)
		(stroke
			(width 0.06985)
			(type default)
		)
		(layer "In5.Cu")
	)
	(gr_line
		(start 169.175938 -124.927868)
		(end 169.182288 -124.957332)
		(stroke
			(width 0.06985)
			(type default)
		)
		(layer "In5.Cu")
	)
	(gr_line
		(start 169.175938 -124.927868)
		(end 169.182288 -124.897642)
		(stroke
			(width 0.06985)
			(type default)
		)
		(layer "In5.Cu")
	)
	(gr_line
		(start 169.182288 -124.897388)
		(end 169.182542 -124.896372)
		(stroke
			(width 0.06985)
			(type default)
		)
		(layer "In5.Cu")
	)
	(gr_line
		(start 169.311066 -79.19085)
		(end 169.317416 -79.161386)
		(stroke
			(width 0.06985)
			(type default)
		)
		(layer "In5.Cu")
	)
	(gr_line
		(start 169.311066 -79.13116)
		(end 169.317416 -79.161386)
		(stroke
			(width 0.06985)
			(type default)
		)
		(layer "In5.Cu")
	)
	(gr_line
		(start 169.368724 -101.041454)
		(end 169.368978 -101.042216)
		(stroke
			(width 0.06985)
			(type default)
		)
		(layer "In5.Cu")
	)
	(gr_line
		(start 169.368978 -101.100128)
		(end 169.375074 -101.071426)
		(stroke
			(width 0.06985)
			(type default)
		)
		(layer "In5.Cu")
	)
	(gr_line
		(start 169.368978 -101.04247)
		(end 169.375074 -101.071426)
		(stroke
			(width 0.06985)
			(type default)
		)
		(layer "In5.Cu")
	)
	(gr_line
		(start 169.744644 -127.601726)
		(end 169.748708 -127.621538)
		(stroke
			(width 0.06985)
			(type default)
		)
		(layer "In5.Cu")
	)
	(gr_line
		(start 169.748708 -127.621538)
		(end 169.760138 -127.639318)
		(stroke
			(width 0.06985)
			(type default)
		)
		(layer "In5.Cu")
	)
	(gr_line
		(start 169.76725 -123.674378)
		(end 169.773854 -123.705112)
		(stroke
			(width 0.06985)
			(type default)
		)
		(layer "In5.Cu")
	)
	(gr_line
		(start 169.767504 -123.734576)
		(end 169.773854 -123.705112)
		(stroke
			(width 0.06985)
			(type default)
		)
		(layer "In5.Cu")
	)
	(gr_line
		(start 170.721528 -80.014826)
		(end 170.728132 -80.04556)
		(stroke
			(width 0.06985)
			(type default)
		)
		(layer "In5.Cu")
	)
	(gr_line
		(start 170.721782 -80.075024)
		(end 170.728132 -80.04556)
		(stroke
			(width 0.06985)
			(type default)
		)
		(layer "In5.Cu")
	)
	(gr_line
		(start 170.809412 -100.434394)
		(end 170.816016 -100.465128)
		(stroke
			(width 0.06985)
			(type default)
		)
		(layer "In5.Cu")
	)
	(gr_line
		(start 170.809666 -100.494592)
		(end 170.816016 -100.465128)
		(stroke
			(width 0.06985)
			(type default)
		)
		(layer "In5.Cu")
	)
	(gr_line
		(start 171.096178 -129.69621)
		(end 171.112434 -129.721102)
		(stroke
			(width 0.06985)
			(type default)
		)
		(layer "In5.Cu")
	)
	(gr_line
		(start 171.112434 -129.721102)
		(end 171.137326 -129.737358)
		(stroke
			(width 0.06985)
			(type default)
		)
		(layer "In5.Cu")
	)
	(gr_line
		(start 171.321476 -140.768832)
		(end 171.345606 -140.773404)
		(stroke
			(width 0.06985)
			(type default)
		)
		(layer "In5.Cu")
	)
	(gr_line
		(start 171.345606 -140.773404)
		(end 171.369736 -140.768832)
		(stroke
			(width 0.06985)
			(type default)
		)
		(layer "In5.Cu")
	)
	(gr_line
		(start 171.886118 -130.223768)
		(end 171.903898 -130.235198)
		(stroke
			(width 0.06985)
			(type default)
		)
		(layer "In5.Cu")
	)
	(gr_line
		(start 171.903898 -130.235198)
		(end 171.92371 -130.239262)
		(stroke
			(width 0.06985)
			(type default)
		)
		(layer "In5.Cu")
	)
	(gr_line
		(start 172.073316 -100.493576)
		(end 172.07992 -100.52431)
		(stroke
			(width 0.06985)
			(type default)
		)
		(layer "In5.Cu")
	)
	(gr_line
		(start 172.07357 -100.553774)
		(end 172.07992 -100.52431)
		(stroke
			(width 0.06985)
			(type default)
		)
		(layer "In5.Cu")
	)
	(gr_arc
		(start 172.283628 -140.585698)
		(mid 172.27202 -140.590271)
		(end 172.260514 -140.595096)
		(stroke
			(width 0.06985)
			(type default)
		)
		(layer "In5.Cu")
	)
	(gr_line
		(start 173.139354 -130.50012)
		(end 173.274482 -130.708146)
		(stroke
			(width 0.06985)
			(type default)
		)
		(layer "In5.Cu")
	)
	(gr_line
		(start 173.246796 -130.183128)
		(end 173.922944 -130.326638)
		(stroke
			(width 0.06985)
			(type default)
		)
		(layer "In5.Cu")
	)
	(gr_line
		(start 173.274482 -130.708146)
		(end 173.684438 -130.795014)
		(stroke
			(width 0.06985)
			(type default)
		)
		(layer "In5.Cu")
	)
	(gr_line
		(start 173.684438 -130.795014)
		(end 173.892464 -130.659886)
		(stroke
			(width 0.06985)
			(type default)
		)
		(layer "In5.Cu")
	)
	(gr_line
		(start 173.943772 -137.925048)
		(end 174.033434 -138.01471)
		(stroke
			(width 0.06985)
			(type default)
		)
		(layer "In5.Cu")
	)
	(gr_arc
		(start 174.033434 -138.229594)
		(mid 174.077906 -138.122166)
		(end 174.033434 -138.01471)
		(stroke
			(width 0.06985)
			(type default)
		)
		(layer "In5.Cu")
	)
	(gr_line
		(start 174.306992 -130.748024)
		(end 174.44212 -130.95605)
		(stroke
			(width 0.06985)
			(type default)
		)
		(layer "In5.Cu")
	)
	(gr_line
		(start 174.41418 -130.430778)
		(end 175.090836 -130.574542)
		(stroke
			(width 0.06985)
			(type default)
		)
		(layer "In5.Cu")
	)
	(gr_line
		(start 174.44212 -130.95605)
		(end 174.852076 -131.043172)
		(stroke
			(width 0.06985)
			(type default)
		)
		(layer "In5.Cu")
	)
	(gr_arc
		(start 174.482506 -138.463782)
		(mid 174.374556 -138.419068)
		(end 174.266606 -138.463782)
		(stroke
			(width 0.06985)
			(type default)
		)
		(layer "In5.Cu")
	)
	(gr_line
		(start 174.482506 -138.463782)
		(end 174.572168 -138.553444)
		(stroke
			(width 0.06985)
			(type default)
		)
		(layer "In5.Cu")
	)
	(gr_line
		(start 174.852076 -131.043172)
		(end 175.059848 -130.908044)
		(stroke
			(width 0.06985)
			(type default)
		)
		(layer "In5.Cu")
	)
	(gr_line
		(start 175.47463 -130.995928)
		(end 175.609758 -131.204208)
		(stroke
			(width 0.06985)
			(type default)
		)
		(layer "In5.Cu")
	)
	(gr_line
		(start 175.58131 -130.678428)
		(end 176.259998 -130.8227)
		(stroke
			(width 0.06985)
			(type default)
		)
		(layer "In5.Cu")
	)
	(gr_line
		(start 175.609758 -131.204208)
		(end 176.019714 -131.291076)
		(stroke
			(width 0.06985)
			(type default)
		)
		(layer "In5.Cu")
	)
	(gr_line
		(start 175.69688 -142.598394)
		(end 175.719486 -142.602966)
		(stroke
			(width 0.06985)
			(type default)
		)
		(layer "In5.Cu")
	)
	(gr_line
		(start 175.719486 -142.602966)
		(end 175.743108 -142.598394)
		(stroke
			(width 0.06985)
			(type default)
		)
		(layer "In5.Cu")
	)
	(gr_line
		(start 176.019714 -131.291076)
		(end 176.22774 -131.155948)
		(stroke
			(width 0.06985)
			(type default)
		)
		(layer "In5.Cu")
	)
	(gr_line
		(start 176.046892 -143.781526)
		(end 176.073054 -143.78686)
		(stroke
			(width 0.06985)
			(type default)
		)
		(layer "In5.Cu")
	)
	(gr_line
		(start 176.073054 -143.78686)
		(end 176.098962 -143.781526)
		(stroke
			(width 0.06985)
			(type default)
		)
		(layer "In5.Cu")
	)
	(gr_line
		(start 176.156112 -142.51813)
		(end 176.163732 -142.516606)
		(stroke
			(width 0.06985)
			(type default)
		)
		(layer "In5.Cu")
	)
	(gr_line
		(start 176.163732 -142.516606)
		(end 176.17059 -142.51305)
		(stroke
			(width 0.06985)
			(type default)
		)
		(layer "In5.Cu")
	)
	(gr_line
		(start 176.642268 -131.244086)
		(end 176.777396 -131.452112)
		(stroke
			(width 0.06985)
			(type default)
		)
		(layer "In5.Cu")
	)
	(gr_line
		(start 176.642522 -142.265654)
		(end 176.681892 -142.24508)
		(stroke
			(width 0.06985)
			(type default)
		)
		(layer "In5.Cu")
	)
	(gr_line
		(start 176.681892 -142.24508)
		(end 176.707038 -142.207996)
		(stroke
			(width 0.06985)
			(type default)
		)
		(layer "In5.Cu")
	)
	(gr_line
		(start 176.74717 -130.926078)
		(end 177.333148 -131.050538)
		(stroke
			(width 0.06985)
			(type default)
		)
		(layer "In5.Cu")
	)
	(gr_line
		(start 176.777396 -131.452112)
		(end 177.187352 -131.53898)
		(stroke
			(width 0.06985)
			(type default)
		)
		(layer "In5.Cu")
	)
	(gr_line
		(start 176.963324 -144.987264)
		(end 176.989486 -144.992598)
		(stroke
			(width 0.06985)
			(type default)
		)
		(layer "In5.Cu")
	)
	(gr_line
		(start 176.989486 -144.992598)
		(end 177.015394 -144.987264)
		(stroke
			(width 0.06985)
			(type default)
		)
		(layer "In5.Cu")
	)
	(gr_line
		(start 177.154586 -146.053048)
		(end 177.18151 -146.058636)
		(stroke
			(width 0.06985)
			(type default)
		)
		(layer "In5.Cu")
	)
	(gr_line
		(start 177.18151 -146.058636)
		(end 177.207672 -146.053556)
		(stroke
			(width 0.06985)
			(type default)
		)
		(layer "In5.Cu")
	)
	(gr_line
		(start 177.187352 -131.53898)
		(end 177.395378 -131.403852)
		(stroke
			(width 0.06985)
			(type default)
		)
		(layer "In5.Cu")
	)
	(gr_line
		(start 177.333148 -131.050538)
		(end 177.42789 -131.070604)
		(stroke
			(width 0.06985)
			(type default)
		)
		(layer "In5.Cu")
	)
	(gr_line
		(start 177.475896 -147.831302)
		(end 177.500026 -147.835874)
		(stroke
			(width 0.06985)
			(type default)
		)
		(layer "In5.Cu")
	)
	(gr_line
		(start 177.500026 -147.835874)
		(end 177.524156 -147.831302)
		(stroke
			(width 0.06985)
			(type default)
		)
		(layer "In5.Cu")
	)
	(gr_line
		(start 177.602896 -146.971258)
		(end 177.628296 -146.976592)
		(stroke
			(width 0.06985)
			(type default)
		)
		(layer "In5.Cu")
	)
	(gr_line
		(start 177.628296 -146.976592)
		(end 177.654204 -146.971258)
		(stroke
			(width 0.06985)
			(type default)
		)
		(layer "In5.Cu")
	)
	(gr_line
		(start 177.661062 -139.973812)
		(end 177.750724 -140.063474)
		(stroke
			(width 0.06985)
			(type default)
		)
		(layer "In5.Cu")
	)
	(gr_arc
		(start 177.750724 -140.278358)
		(mid 177.795245 -140.170911)
		(end 177.750724 -140.063474)
		(stroke
			(width 0.06985)
			(type default)
		)
		(layer "In5.Cu")
	)
	(gr_line
		(start 178.199796 -140.512546)
		(end 178.289458 -140.602208)
		(stroke
			(width 0.06985)
			(type default)
		)
		(layer "In5.Cu")
	)
	(gr_line
		(start 178.940968 -149.733254)
		(end 178.970432 -149.739604)
		(stroke
			(width 0.06985)
			(type default)
		)
		(layer "In5.Cu")
	)
	(gr_line
		(start 178.970432 -149.739604)
		(end 178.999896 -149.733254)
		(stroke
			(width 0.06985)
			(type default)
		)
		(layer "In5.Cu")
	)
	(gr_line
		(start 179.241958 -131.793742)
		(end 179.271422 -131.800092)
		(stroke
			(width 0.06985)
			(type default)
		)
		(layer "In5.Cu")
	)
	(gr_line
		(start 179.271422 -131.800092)
		(end 179.300886 -131.793742)
		(stroke
			(width 0.06985)
			(type default)
		)
		(layer "In5.Cu")
	)
	(gr_line
		(start 181.196742 -131.053332)
		(end 181.226206 -131.046982)
		(stroke
			(width 0.06985)
			(type default)
		)
		(layer "In5.Cu")
	)
	(gr_line
		(start 181.226206 -131.046982)
		(end 181.25567 -131.053332)
		(stroke
			(width 0.06985)
			(type default)
		)
		(layer "In5.Cu")
	)
	(gr_line
		(start 181.357778 -142.729712)
		(end 181.382924 -142.724632)
		(stroke
			(width 0.06985)
			(type default)
		)
		(layer "In5.Cu")
	)
	(gr_line
		(start 181.382924 -142.724632)
		(end 181.404006 -142.710408)
		(stroke
			(width 0.06985)
			(type default)
		)
		(layer "In5.Cu")
	)
	(gr_line
		(start 182.109872 -142.240254)
		(end 182.132732 -142.225014)
		(stroke
			(width 0.06985)
			(type default)
		)
		(layer "In5.Cu")
	)
	(gr_line
		(start 182.132732 -142.225014)
		(end 182.147972 -142.2019)
		(stroke
			(width 0.06985)
			(type default)
		)
		(layer "In5.Cu")
	)
	(gr_line
		(start 182.328566 -139.663424)
		(end 182.418228 -139.753086)
		(stroke
			(width 0.06985)
			(type default)
		)
		(layer "In5.Cu")
	)
	(gr_line
		(start 182.329328 -141.929612)
		(end 182.36184 -141.88059)
		(stroke
			(width 0.06985)
			(type default)
		)
		(layer "In5.Cu")
	)
	(gr_arc
		(start 182.418228 -139.96797)
		(mid 182.462756 -139.86052)
		(end 182.418228 -139.753086)
		(stroke
			(width 0.06985)
			(type default)
		)
		(layer "In5.Cu")
	)
	(gr_line
		(start 182.8419 -131.39039)
		(end 182.898034 -131.402328)
		(stroke
			(width 0.06985)
			(type default)
		)
		(layer "In5.Cu")
	)
	(gr_arc
		(start 182.8673 -140.202158)
		(mid 182.75935 -140.157444)
		(end 182.6514 -140.202158)
		(stroke
			(width 0.06985)
			(type default)
		)
		(layer "In5.Cu")
	)
	(gr_line
		(start 182.8673 -140.202158)
		(end 182.956962 -140.29182)
		(stroke
			(width 0.06985)
			(type default)
		)
		(layer "In5.Cu")
	)
	(gr_line
		(start 183.016144 -132.973826)
		(end 183.143144 -132.973826)
		(stroke
			(width 0.06985)
			(type default)
		)
		(layer "In5.Cu")
	)
	(gr_arc
		(start 183.143144 -132.973826)
		(mid 183.251048 -132.929097)
		(end 183.295798 -132.821172)
		(stroke
			(width 0.06985)
			(type default)
		)
		(layer "In5.Cu")
	)
	(gr_arc
		(start 183.626252 -132.821934)
		(mid 183.67074 -132.929338)
		(end 183.778144 -132.973826)
		(stroke
			(width 0.06985)
			(type default)
		)
		(layer "In5.Cu")
	)
	(gr_line
		(start 183.778144 -132.973826)
		(end 183.905144 -132.973826)
		(stroke
			(width 0.06985)
			(type default)
		)
		(layer "In5.Cu")
	)
	(gr_line
		(start 188.47054 -147.380452)
		(end 188.605668 -147.172172)
		(stroke
			(width 0.06985)
			(type default)
		)
		(layer "In5.Cu")
	)
	(gr_line
		(start 188.508386 -142.68958)
		(end 188.533532 -142.6845)
		(stroke
			(width 0.06985)
			(type default)
		)
		(layer "In5.Cu")
	)
	(gr_line
		(start 188.533532 -142.6845)
		(end 188.553598 -142.670784)
		(stroke
			(width 0.06985)
			(type default)
		)
		(layer "In5.Cu")
	)
	(gr_line
		(start 188.575442 -147.698206)
		(end 189.256416 -147.553426)
		(stroke
			(width 0.06985)
			(type default)
		)
		(layer "In5.Cu")
	)
	(gr_line
		(start 188.605668 -147.172172)
		(end 189.015624 -147.08505)
		(stroke
			(width 0.06985)
			(type default)
		)
		(layer "In5.Cu")
	)
	(gr_line
		(start 189.015624 -147.08505)
		(end 189.223904 -147.220178)
		(stroke
			(width 0.06985)
			(type default)
		)
		(layer "In5.Cu")
	)
	(gr_line
		(start 189.638178 -147.132294)
		(end 189.773306 -146.924014)
		(stroke
			(width 0.06985)
			(type default)
		)
		(layer "In5.Cu")
	)
	(gr_line
		(start 189.74308 -147.450048)
		(end 190.424054 -147.305268)
		(stroke
			(width 0.06985)
			(type default)
		)
		(layer "In5.Cu")
	)
	(gr_line
		(start 189.773306 -146.924014)
		(end 190.183262 -146.836892)
		(stroke
			(width 0.06985)
			(type default)
		)
		(layer "In5.Cu")
	)
	(gr_line
		(start 190.183262 -146.836892)
		(end 190.391542 -146.97202)
		(stroke
			(width 0.06985)
			(type default)
		)
		(layer "In5.Cu")
	)
	(gr_line
		(start 190.805816 -146.884136)
		(end 190.940944 -146.675856)
		(stroke
			(width 0.06985)
			(type default)
		)
		(layer "In5.Cu")
	)
	(gr_line
		(start 190.91148 -147.201636)
		(end 191.592454 -147.056856)
		(stroke
			(width 0.06985)
			(type default)
		)
		(layer "In5.Cu")
	)
	(gr_line
		(start 190.940944 -146.675856)
		(end 191.3509 -146.588734)
		(stroke
			(width 0.06985)
			(type default)
		)
		(layer "In5.Cu")
	)
	(gr_line
		(start 191.3509 -146.588734)
		(end 191.558672 -146.723862)
		(stroke
			(width 0.06985)
			(type default)
		)
		(layer "In5.Cu")
	)
	(gr_line
		(start 191.942212 -146.644868)
		(end 191.971676 -146.638518)
		(stroke
			(width 0.06985)
			(type default)
		)
		(layer "In5.Cu")
	)
	(gr_line
		(start 191.971676 -146.638518)
		(end 192.00114 -146.644868)
		(stroke
			(width 0.06985)
			(type default)
		)
		(layer "In5.Cu")
	)
	(gr_line
		(start 192.090802 -139.258802)
		(end 192.180464 -139.348464)
		(stroke
			(width 0.06985)
			(type default)
		)
		(layer "In5.Cu")
	)
	(gr_arc
		(start 192.180464 -139.563348)
		(mid 192.224966 -139.455904)
		(end 192.180464 -139.348464)
		(stroke
			(width 0.06985)
			(type default)
		)
		(layer "In5.Cu")
	)
	(gr_line
		(start 192.499234 -144.583658)
		(end 192.523364 -144.579086)
		(stroke
			(width 0.06985)
			(type default)
		)
		(layer "In5.Cu")
	)
	(gr_line
		(start 192.523364 -144.579086)
		(end 192.547494 -144.583658)
		(stroke
			(width 0.06985)
			(type default)
		)
		(layer "In5.Cu")
	)
	(gr_arc
		(start 192.629536 -139.797536)
		(mid 192.521586 -139.752822)
		(end 192.413636 -139.797536)
		(stroke
			(width 0.06985)
			(type default)
		)
		(layer "In5.Cu")
	)
	(gr_line
		(start 192.629536 -139.797536)
		(end 192.719198 -139.887198)
		(stroke
			(width 0.06985)
			(type default)
		)
		(layer "In5.Cu")
	)
	(gr_line
		(start 192.75552 -143.614648)
		(end 192.781174 -143.609568)
		(stroke
			(width 0.06985)
			(type default)
		)
		(layer "In5.Cu")
	)
	(gr_line
		(start 192.781174 -143.609568)
		(end 192.806066 -143.614394)
		(stroke
			(width 0.06985)
			(type default)
		)
		(layer "In5.Cu")
	)
	(gr_line
		(start 193.382138 -142.572232)
		(end 193.406268 -142.56766)
		(stroke
			(width 0.06985)
			(type default)
		)
		(layer "In5.Cu")
	)
	(gr_line
		(start 193.406268 -142.56766)
		(end 193.430398 -142.572232)
		(stroke
			(width 0.06985)
			(type default)
		)
		(layer "In5.Cu")
	)
	(gr_line
		(start 194.816984 -143.178784)
		(end 194.841114 -143.183356)
		(stroke
			(width 0.06985)
			(type default)
		)
		(layer "In5.Cu")
	)
	(gr_line
		(start 194.841114 -143.183356)
		(end 194.86499 -143.178784)
		(stroke
			(width 0.06985)
			(type default)
		)
		(layer "In5.Cu")
	)
	(gr_line
		(start 195.758054 -144.524476)
		(end 195.782184 -144.529048)
		(stroke
			(width 0.06985)
			(type default)
		)
		(layer "In5.Cu")
	)
	(gr_line
		(start 195.782184 -144.529048)
		(end 195.806314 -144.524476)
		(stroke
			(width 0.06985)
			(type default)
		)
		(layer "In5.Cu")
	)
	(gr_line
		(start 196.437758 -147.925536)
		(end 196.467222 -147.931886)
		(stroke
			(width 0.06985)
			(type default)
		)
		(layer "In5.Cu")
	)
	(gr_line
		(start 196.467222 -147.931886)
		(end 196.496686 -147.925536)
		(stroke
			(width 0.06985)
			(type default)
		)
		(layer "In5.Cu")
	)
	(gr_line
		(start 196.653404 -145.71853)
		(end 196.678296 -145.723356)
		(stroke
			(width 0.06985)
			(type default)
		)
		(layer "In5.Cu")
	)
	(gr_line
		(start 196.678296 -145.723356)
		(end 196.703188 -145.718276)
		(stroke
			(width 0.06985)
			(type default)
		)
		(layer "In5.Cu")
	)
	(gr_line
		(start 197.0786 -142.746476)
		(end 197.137782 -142.734792)
		(stroke
			(width 0.06985)
			(type default)
		)
		(layer "In5.Cu")
	)
	(gr_line
		(start 197.805802 -140.655802)
		(end 197.895464 -140.745464)
		(stroke
			(width 0.06985)
			(type default)
		)
		(layer "In5.Cu")
	)
	(gr_arc
		(start 197.895464 -140.960348)
		(mid 197.939966 -140.852904)
		(end 197.895464 -140.745464)
		(stroke
			(width 0.06985)
			(type default)
		)
		(layer "In5.Cu")
	)
	(gr_arc
		(start 198.344536 -141.194536)
		(mid 198.236586 -141.149822)
		(end 198.128636 -141.194536)
		(stroke
			(width 0.06985)
			(type default)
		)
		(layer "In5.Cu")
	)
	(gr_line
		(start 198.344536 -141.194536)
		(end 198.434198 -141.284198)
		(stroke
			(width 0.06985)
			(type default)
		)
		(layer "In5.Cu")
	)
	(gr_line
		(start 201.845418 -143.349472)
		(end 201.905362 -143.337788)
		(stroke
			(width 0.06985)
			(type default)
		)
		(layer "In5.Cu")
	)
	(gr_line
		(start 201.905362 -143.337788)
		(end 201.948288 -143.294862)
		(stroke
			(width 0.06985)
			(type default)
		)
		(layer "In5.Cu")
	)
	(gr_line
		(start 202.631802 -140.782802)
		(end 202.721464 -140.872464)
		(stroke
			(width 0.06985)
			(type default)
		)
		(layer "In5.Cu")
	)
	(gr_arc
		(start 202.721464 -141.087348)
		(mid 202.765966 -140.979904)
		(end 202.721464 -140.872464)
		(stroke
			(width 0.06985)
			(type default)
		)
		(layer "In5.Cu")
	)
	(gr_arc
		(start 203.170536 -141.321536)
		(mid 203.062586 -141.276822)
		(end 202.954636 -141.321536)
		(stroke
			(width 0.06985)
			(type default)
		)
		(layer "In5.Cu")
	)
	(gr_line
		(start 203.170536 -141.321536)
		(end 203.260198 -141.411198)
		(stroke
			(width 0.06985)
			(type default)
		)
		(layer "In5.Cu")
	)
	(gr_line
		(start 204.33792 -145.918428)
		(end 204.473302 -145.710148)
		(stroke
			(width 0.06985)
			(type default)
		)
		(layer "In5.Cu")
	)
	(gr_line
		(start 204.441806 -146.23669)
		(end 205.127352 -146.090894)
		(stroke
			(width 0.06985)
			(type default)
		)
		(layer "In5.Cu")
	)
	(gr_line
		(start 204.473302 -145.710148)
		(end 204.883258 -145.623026)
		(stroke
			(width 0.06985)
			(type default)
		)
		(layer "In5.Cu")
	)
	(gr_line
		(start 204.883258 -145.623026)
		(end 205.091538 -145.758154)
		(stroke
			(width 0.06985)
			(type default)
		)
		(layer "In5.Cu")
	)
	(gr_line
		(start 205.505812 -145.67027)
		(end 205.64094 -145.46199)
		(stroke
			(width 0.06985)
			(type default)
		)
		(layer "In5.Cu")
	)
	(gr_line
		(start 205.608682 -145.988786)
		(end 206.293974 -145.84299)
		(stroke
			(width 0.06985)
			(type default)
		)
		(layer "In5.Cu")
	)
	(gr_line
		(start 205.64094 -145.46199)
		(end 206.050896 -145.374868)
		(stroke
			(width 0.06985)
			(type default)
		)
		(layer "In5.Cu")
	)
	(gr_line
		(start 205.879446 -143.88338)
		(end 205.904846 -143.8783)
		(stroke
			(width 0.06985)
			(type default)
		)
		(layer "In5.Cu")
	)
	(gr_line
		(start 205.904846 -143.8783)
		(end 205.925674 -143.864076)
		(stroke
			(width 0.06985)
			(type default)
		)
		(layer "In5.Cu")
	)
	(gr_line
		(start 206.050896 -145.374868)
		(end 206.259176 -145.509996)
		(stroke
			(width 0.06985)
			(type default)
		)
		(layer "In5.Cu")
	)
	(gr_line
		(start 206.441802 -139.258802)
		(end 206.531464 -139.348464)
		(stroke
			(width 0.06985)
			(type default)
		)
		(layer "In5.Cu")
	)
	(gr_arc
		(start 206.531464 -139.563348)
		(mid 206.575966 -139.455904)
		(end 206.531464 -139.348464)
		(stroke
			(width 0.06985)
			(type default)
		)
		(layer "In5.Cu")
	)
	(gr_line
		(start 206.67345 -145.422112)
		(end 206.808578 -145.213832)
		(stroke
			(width 0.06985)
			(type default)
		)
		(layer "In5.Cu")
	)
	(gr_line
		(start 206.776828 -145.740374)
		(end 207.461358 -145.594832)
		(stroke
			(width 0.06985)
			(type default)
		)
		(layer "In5.Cu")
	)
	(gr_line
		(start 206.808578 -145.213832)
		(end 207.218534 -145.12671)
		(stroke
			(width 0.06985)
			(type default)
		)
		(layer "In5.Cu")
	)
	(gr_line
		(start 206.965804 -143.170656)
		(end 206.987902 -143.155924)
		(stroke
			(width 0.06985)
			(type default)
		)
		(layer "In5.Cu")
	)
	(gr_arc
		(start 206.980536 -139.797536)
		(mid 206.872586 -139.752822)
		(end 206.764636 -139.797536)
		(stroke
			(width 0.06985)
			(type default)
		)
		(layer "In5.Cu")
	)
	(gr_line
		(start 206.980536 -139.797536)
		(end 207.070198 -139.887198)
		(stroke
			(width 0.06985)
			(type default)
		)
		(layer "In5.Cu")
	)
	(gr_line
		(start 206.987902 -143.155924)
		(end 207.002634 -143.133826)
		(stroke
			(width 0.06985)
			(type default)
		)
		(layer "In5.Cu")
	)
	(gr_line
		(start 207.218534 -145.12671)
		(end 207.42656 -145.261838)
		(stroke
			(width 0.06985)
			(type default)
		)
		(layer "In5.Cu")
	)
	(gr_line
		(start 207.30337 -142.68196)
		(end 207.33639 -142.632684)
		(stroke
			(width 0.06985)
			(type default)
		)
		(layer "In5.Cu")
	)
	(gr_line
		(start 207.841088 -145.1737)
		(end 207.976216 -144.965674)
		(stroke
			(width 0.06985)
			(type default)
		)
		(layer "In5.Cu")
	)
	(gr_line
		(start 207.945482 -145.491962)
		(end 208.627472 -145.346928)
		(stroke
			(width 0.06985)
			(type default)
		)
		(layer "In5.Cu")
	)
	(gr_line
		(start 207.976216 -144.965674)
		(end 208.386172 -144.878552)
		(stroke
			(width 0.06985)
			(type default)
		)
		(layer "In5.Cu")
	)
	(gr_line
		(start 208.386172 -144.878552)
		(end 208.594198 -145.01368)
		(stroke
			(width 0.06985)
			(type default)
		)
		(layer "In5.Cu")
	)
	(gr_line
		(start 209.356706 -145.191734)
		(end 209.41284 -145.179796)
		(stroke
			(width 0.06985)
			(type default)
		)
		(layer "In5.Cu")
	)
	(gr_line
		(start 213.33333 -138.87704)
		(end 213.422992 -138.966702)
		(stroke
			(width 0.06985)
			(type default)
		)
		(layer "In5.Cu")
	)
	(gr_arc
		(start 213.422992 -139.181586)
		(mid 213.467542 -139.074131)
		(end 213.422992 -138.966702)
		(stroke
			(width 0.06985)
			(type default)
		)
		(layer "In5.Cu")
	)
	(gr_arc
		(start 213.872064 -139.415774)
		(mid 213.764114 -139.37106)
		(end 213.656164 -139.415774)
		(stroke
			(width 0.06985)
			(type default)
		)
		(layer "In5.Cu")
	)
	(gr_line
		(start 213.872064 -139.415774)
		(end 213.961726 -139.505436)
		(stroke
			(width 0.06985)
			(type default)
		)
		(layer "In5.Cu")
	)
	(gr_line
		(start 0 -183.76392)
		(end 0 -0.999998)
		(stroke
			(width 1.524)
			(type default)
		)
		(layer "In6.Cu")
	)
	(gr_arc
		(start 0 -183.76392)
		(mid 0.026807 -183.993715)
		(end 0.105664 -184.211214)
		(stroke
			(width 1.524)
			(type default)
		)
		(layer "In6.Cu")
	)
	(gr_arc
		(start 0.999998 0)
		(mid 0.292893 -0.292893)
		(end 0 -0.999998)
		(stroke
			(width 1.524)
			(type default)
		)
		(layer "In6.Cu")
	)
	(gr_line
		(start 0.999998 0)
		(end 29.53004 0)
		(stroke
			(width 1.524)
			(type default)
		)
		(layer "In6.Cu")
	)
	(gr_line
		(start 4.723638 -193.447162)
		(end 0.105664 -184.211214)
		(stroke
			(width 1.524)
			(type default)
		)
		(layer "In6.Cu")
	)
	(gr_arc
		(start 4.723638 -193.447162)
		(mid 5.092281 -193.850645)
		(end 5.617972 -194.00012)
		(stroke
			(width 1.524)
			(type default)
		)
		(layer "In6.Cu")
	)
	(gr_arc
		(start 30.530038 -109.050074)
		(mid 30.822931 -109.757179)
		(end 31.530036 -110.050072)
		(stroke
			(width 1.524)
			(type default)
		)
		(layer "In6.Cu")
	)
	(gr_arc
		(start 30.530038 -0.999998)
		(mid 30.237147 -0.29288)
		(end 29.53004 0)
		(stroke
			(width 1.524)
			(type default)
		)
		(layer "In6.Cu")
	)
	(gr_line
		(start 30.530038 -0.999998)
		(end 30.530038 -109.050074)
		(stroke
			(width 1.524)
			(type default)
		)
		(layer "In6.Cu")
	)
	(gr_line
		(start 31.530036 -110.050072)
		(end 72.030082 -110.050072)
		(stroke
			(width 1.524)
			(type default)
		)
		(layer "In6.Cu")
	)
	(gr_arc
		(start 72.030082 -110.050072)
		(mid 72.737187 -109.757179)
		(end 73.03008 -109.050074)
		(stroke
			(width 1.524)
			(type default)
		)
		(layer "In6.Cu")
	)
	(gr_line
		(start 73.03008 -109.050074)
		(end 73.03008 -0.999998)
		(stroke
			(width 1.524)
			(type default)
		)
		(layer "In6.Cu")
	)
	(gr_arc
		(start 74.030078 0)
		(mid 73.322986 -0.2929)
		(end 73.03008 -0.999998)
		(stroke
			(width 1.524)
			(type default)
		)
		(layer "In6.Cu")
	)
	(gr_line
		(start 74.030078 0)
		(end 234.00004 0)
		(stroke
			(width 1.524)
			(type default)
		)
		(layer "In6.Cu")
	)
	(gr_arc
		(start 76.902818 -93.800168)
		(mid 77.283818 -94.181168)
		(end 77.664818 -93.800168)
		(stroke
			(width 0.2)
			(type default)
		)
		(layer "In6.Cu")
	)
	(gr_line
		(start 76.902818 -92.911168)
		(end 76.902818 -93.800168)
		(stroke
			(width 0.2)
			(type default)
		)
		(layer "In6.Cu")
	)
	(gr_arc
		(start 76.902818 -87.399368)
		(mid 77.283818 -87.780368)
		(end 77.664818 -87.399368)
		(stroke
			(width 0.2)
			(type default)
		)
		(layer "In6.Cu")
	)
	(gr_line
		(start 76.902818 -86.510368)
		(end 76.902818 -87.399368)
		(stroke
			(width 0.2)
			(type default)
		)
		(layer "In6.Cu")
	)
	(gr_arc
		(start 76.902818 -80.998568)
		(mid 77.283818 -81.379568)
		(end 77.664818 -80.998568)
		(stroke
			(width 0.2)
			(type default)
		)
		(layer "In6.Cu")
	)
	(gr_line
		(start 76.902818 -80.109568)
		(end 76.902818 -80.998568)
		(stroke
			(width 0.2)
			(type default)
		)
		(layer "In6.Cu")
	)
	(gr_arc
		(start 76.902818 -74.597768)
		(mid 77.283818 -74.978768)
		(end 77.664818 -74.597768)
		(stroke
			(width 0.2)
			(type default)
		)
		(layer "In6.Cu")
	)
	(gr_line
		(start 76.902818 -73.708768)
		(end 76.902818 -74.597768)
		(stroke
			(width 0.2)
			(type default)
		)
		(layer "In6.Cu")
	)
	(gr_arc
		(start 76.974192 -68.201032)
		(mid 77.355192 -68.582032)
		(end 77.736192 -68.201032)
		(stroke
			(width 0.2)
			(type default)
		)
		(layer "In6.Cu")
	)
	(gr_line
		(start 76.974192 -67.312032)
		(end 76.974192 -68.201032)
		(stroke
			(width 0.2)
			(type default)
		)
		(layer "In6.Cu")
	)
	(gr_line
		(start 77.664818 -93.800168)
		(end 77.664818 -92.911422)
		(stroke
			(width 0.2)
			(type default)
		)
		(layer "In6.Cu")
	)
	(gr_arc
		(start 77.664818 -92.911422)
		(mid 77.283945 -92.530168)
		(end 76.902818 -92.911168)
		(stroke
			(width 0.2)
			(type default)
		)
		(layer "In6.Cu")
	)
	(gr_line
		(start 77.664818 -87.399368)
		(end 77.664818 -86.510622)
		(stroke
			(width 0.2)
			(type default)
		)
		(layer "In6.Cu")
	)
	(gr_arc
		(start 77.664818 -86.510622)
		(mid 77.283945 -86.129368)
		(end 76.902818 -86.510368)
		(stroke
			(width 0.2)
			(type default)
		)
		(layer "In6.Cu")
	)
	(gr_line
		(start 77.664818 -80.998568)
		(end 77.664818 -80.109822)
		(stroke
			(width 0.2)
			(type default)
		)
		(layer "In6.Cu")
	)
	(gr_arc
		(start 77.664818 -80.109822)
		(mid 77.283945 -79.728568)
		(end 76.902818 -80.109568)
		(stroke
			(width 0.2)
			(type default)
		)
		(layer "In6.Cu")
	)
	(gr_line
		(start 77.664818 -74.597768)
		(end 77.664818 -73.709022)
		(stroke
			(width 0.2)
			(type default)
		)
		(layer "In6.Cu")
	)
	(gr_arc
		(start 77.664818 -73.709022)
		(mid 77.283945 -73.327768)
		(end 76.902818 -73.708768)
		(stroke
			(width 0.2)
			(type default)
		)
		(layer "In6.Cu")
	)
	(gr_line
		(start 77.736192 -68.201032)
		(end 77.736192 -67.312286)
		(stroke
			(width 0.2)
			(type default)
		)
		(layer "In6.Cu")
	)
	(gr_arc
		(start 77.736192 -67.312286)
		(mid 77.355319 -66.931032)
		(end 76.974192 -67.312032)
		(stroke
			(width 0.2)
			(type default)
		)
		(layer "In6.Cu")
	)
	(gr_arc
		(start 77.741018 -90.599768)
		(mid 78.122018 -90.980768)
		(end 78.503018 -90.599768)
		(stroke
			(width 0.2)
			(type default)
		)
		(layer "In6.Cu")
	)
	(gr_line
		(start 77.741018 -89.710768)
		(end 77.741018 -90.599768)
		(stroke
			(width 0.2)
			(type default)
		)
		(layer "In6.Cu")
	)
	(gr_arc
		(start 77.741018 -84.198968)
		(mid 78.122018 -84.579968)
		(end 78.503018 -84.198968)
		(stroke
			(width 0.2)
			(type default)
		)
		(layer "In6.Cu")
	)
	(gr_line
		(start 77.741018 -83.309968)
		(end 77.741018 -84.198968)
		(stroke
			(width 0.2)
			(type default)
		)
		(layer "In6.Cu")
	)
	(gr_arc
		(start 77.741018 -77.798168)
		(mid 78.122018 -78.179168)
		(end 78.503018 -77.798168)
		(stroke
			(width 0.2)
			(type default)
		)
		(layer "In6.Cu")
	)
	(gr_line
		(start 77.741018 -76.909168)
		(end 77.741018 -77.798168)
		(stroke
			(width 0.2)
			(type default)
		)
		(layer "In6.Cu")
	)
	(gr_arc
		(start 77.741018 -71.397368)
		(mid 78.122018 -71.778368)
		(end 78.503018 -71.397368)
		(stroke
			(width 0.2)
			(type default)
		)
		(layer "In6.Cu")
	)
	(gr_line
		(start 77.741018 -70.508368)
		(end 77.741018 -71.397368)
		(stroke
			(width 0.2)
			(type default)
		)
		(layer "In6.Cu")
	)
	(gr_line
		(start 78.503018 -90.599768)
		(end 78.503018 -89.711022)
		(stroke
			(width 0.2)
			(type default)
		)
		(layer "In6.Cu")
	)
	(gr_arc
		(start 78.503018 -89.711022)
		(mid 78.122145 -89.329768)
		(end 77.741018 -89.710768)
		(stroke
			(width 0.2)
			(type default)
		)
		(layer "In6.Cu")
	)
	(gr_line
		(start 78.503018 -84.198968)
		(end 78.503018 -83.310222)
		(stroke
			(width 0.2)
			(type default)
		)
		(layer "In6.Cu")
	)
	(gr_arc
		(start 78.503018 -83.310222)
		(mid 78.122145 -82.928968)
		(end 77.741018 -83.309968)
		(stroke
			(width 0.2)
			(type default)
		)
		(layer "In6.Cu")
	)
	(gr_line
		(start 78.503018 -77.798168)
		(end 78.503018 -76.909422)
		(stroke
			(width 0.2)
			(type default)
		)
		(layer "In6.Cu")
	)
	(gr_arc
		(start 78.503018 -76.909422)
		(mid 78.122145 -76.528168)
		(end 77.741018 -76.909168)
		(stroke
			(width 0.2)
			(type default)
		)
		(layer "In6.Cu")
	)
	(gr_line
		(start 78.503018 -71.397368)
		(end 78.503018 -70.508622)
		(stroke
			(width 0.2)
			(type default)
		)
		(layer "In6.Cu")
	)
	(gr_arc
		(start 78.503018 -70.508622)
		(mid 78.122145 -70.127368)
		(end 77.741018 -70.508368)
		(stroke
			(width 0.2)
			(type default)
		)
		(layer "In6.Cu")
	)
	(gr_arc
		(start 82.977228 -95.381572)
		(mid 83.358228 -95.762572)
		(end 83.739228 -95.381572)
		(stroke
			(width 0.2)
			(type default)
		)
		(layer "In6.Cu")
	)
	(gr_line
		(start 82.977228 -94.492572)
		(end 82.977228 -95.381572)
		(stroke
			(width 0.2)
			(type default)
		)
		(layer "In6.Cu")
	)
	(gr_arc
		(start 82.977228 -82.581496)
		(mid 83.358228 -82.962496)
		(end 83.739228 -82.581496)
		(stroke
			(width 0.2)
			(type default)
		)
		(layer "In6.Cu")
	)
	(gr_line
		(start 82.977228 -81.692496)
		(end 82.977228 -82.581496)
		(stroke
			(width 0.2)
			(type default)
		)
		(layer "In6.Cu")
	)
	(gr_arc
		(start 82.977228 -76.194158)
		(mid 83.358228 -76.575158)
		(end 83.739228 -76.194158)
		(stroke
			(width 0.2)
			(type default)
		)
		(layer "In6.Cu")
	)
	(gr_line
		(start 82.977228 -75.305158)
		(end 82.977228 -76.194158)
		(stroke
			(width 0.2)
			(type default)
		)
		(layer "In6.Cu")
	)
	(gr_arc
		(start 82.978498 -88.980264)
		(mid 83.359498 -89.361264)
		(end 83.740498 -88.980264)
		(stroke
			(width 0.2)
			(type default)
		)
		(layer "In6.Cu")
	)
	(gr_line
		(start 82.978498 -88.091264)
		(end 82.978498 -88.980264)
		(stroke
			(width 0.2)
			(type default)
		)
		(layer "In6.Cu")
	)
	(gr_line
		(start 83.739228 -95.381572)
		(end 83.739228 -94.492826)
		(stroke
			(width 0.2)
			(type default)
		)
		(layer "In6.Cu")
	)
	(gr_arc
		(start 83.739228 -94.492826)
		(mid 83.358355 -94.111572)
		(end 82.977228 -94.492572)
		(stroke
			(width 0.2)
			(type default)
		)
		(layer "In6.Cu")
	)
	(gr_line
		(start 83.739228 -82.581496)
		(end 83.739228 -81.69275)
		(stroke
			(width 0.2)
			(type default)
		)
		(layer "In6.Cu")
	)
	(gr_arc
		(start 83.739228 -81.69275)
		(mid 83.358355 -81.311496)
		(end 82.977228 -81.692496)
		(stroke
			(width 0.2)
			(type default)
		)
		(layer "In6.Cu")
	)
	(gr_line
		(start 83.739228 -76.194158)
		(end 83.739228 -75.305412)
		(stroke
			(width 0.2)
			(type default)
		)
		(layer "In6.Cu")
	)
	(gr_arc
		(start 83.739228 -75.305412)
		(mid 83.358355 -74.924158)
		(end 82.977228 -75.305158)
		(stroke
			(width 0.2)
			(type default)
		)
		(layer "In6.Cu")
	)
	(gr_line
		(start 83.740498 -88.980264)
		(end 83.740498 -88.091518)
		(stroke
			(width 0.2)
			(type default)
		)
		(layer "In6.Cu")
	)
	(gr_arc
		(start 83.740498 -88.091518)
		(mid 83.359625 -87.710264)
		(end 82.978498 -88.091264)
		(stroke
			(width 0.2)
			(type default)
		)
		(layer "In6.Cu")
	)
	(gr_arc
		(start 84.482178 -72.987916)
		(mid 84.863178 -73.368916)
		(end 85.244178 -72.987916)
		(stroke
			(width 0.2)
			(type default)
		)
		(layer "In6.Cu")
	)
	(gr_line
		(start 84.482178 -72.098916)
		(end 84.482178 -72.987916)
		(stroke
			(width 0.2)
			(type default)
		)
		(layer "In6.Cu")
	)
	(gr_arc
		(start 84.602828 -92.195396)
		(mid 84.983828 -92.576396)
		(end 85.364828 -92.195396)
		(stroke
			(width 0.2)
			(type default)
		)
		(layer "In6.Cu")
	)
	(gr_line
		(start 84.602828 -91.306396)
		(end 84.602828 -92.195396)
		(stroke
			(width 0.2)
			(type default)
		)
		(layer "In6.Cu")
	)
	(gr_arc
		(start 84.602828 -85.781134)
		(mid 84.983828 -86.162134)
		(end 85.364828 -85.781134)
		(stroke
			(width 0.2)
			(type default)
		)
		(layer "In6.Cu")
	)
	(gr_line
		(start 84.602828 -84.892134)
		(end 84.602828 -85.781134)
		(stroke
			(width 0.2)
			(type default)
		)
		(layer "In6.Cu")
	)
	(gr_arc
		(start 84.605622 -79.396336)
		(mid 84.986622 -79.777336)
		(end 85.367622 -79.396336)
		(stroke
			(width 0.2)
			(type default)
		)
		(layer "In6.Cu")
	)
	(gr_line
		(start 84.605622 -78.507336)
		(end 84.605622 -79.396336)
		(stroke
			(width 0.2)
			(type default)
		)
		(layer "In6.Cu")
	)
	(gr_line
		(start 85.244178 -72.987916)
		(end 85.244178 -72.09917)
		(stroke
			(width 0.2)
			(type default)
		)
		(layer "In6.Cu")
	)
	(gr_arc
		(start 85.244178 -72.09917)
		(mid 84.863305 -71.717916)
		(end 84.482178 -72.098916)
		(stroke
			(width 0.2)
			(type default)
		)
		(layer "In6.Cu")
	)
	(gr_line
		(start 85.364828 -92.195396)
		(end 85.364828 -91.30665)
		(stroke
			(width 0.2)
			(type default)
		)
		(layer "In6.Cu")
	)
	(gr_arc
		(start 85.364828 -91.30665)
		(mid 84.983955 -90.925396)
		(end 84.602828 -91.306396)
		(stroke
			(width 0.2)
			(type default)
		)
		(layer "In6.Cu")
	)
	(gr_line
		(start 85.364828 -85.781134)
		(end 85.364828 -84.892388)
		(stroke
			(width 0.2)
			(type default)
		)
		(layer "In6.Cu")
	)
	(gr_arc
		(start 85.364828 -84.892388)
		(mid 84.983955 -84.511134)
		(end 84.602828 -84.892134)
		(stroke
			(width 0.2)
			(type default)
		)
		(layer "In6.Cu")
	)
	(gr_line
		(start 85.367622 -79.396336)
		(end 85.367622 -78.50759)
		(stroke
			(width 0.2)
			(type default)
		)
		(layer "In6.Cu")
	)
	(gr_arc
		(start 85.367622 -78.50759)
		(mid 84.986749 -78.126336)
		(end 84.605622 -78.507336)
		(stroke
			(width 0.2)
			(type default)
		)
		(layer "In6.Cu")
	)
	(gr_line
		(start 98.081846 -194.00012)
		(end 5.617972 -194.00012)
		(stroke
			(width 1.524)
			(type default)
		)
		(layer "In6.Cu")
	)
	(gr_arc
		(start 98.081846 -194.00012)
		(mid 98.607706 -193.850755)
		(end 98.976434 -193.447162)
		(stroke
			(width 1.524)
			(type default)
		)
		(layer "In6.Cu")
	)
	(gr_line
		(start 103.594408 -184.211214)
		(end 98.976434 -193.447162)
		(stroke
			(width 1.524)
			(type default)
		)
		(layer "In6.Cu")
	)
	(gr_arc
		(start 103.594408 -184.211214)
		(mid 103.673311 -183.993725)
		(end 103.700072 -183.76392)
		(stroke
			(width 1.524)
			(type default)
		)
		(layer "In6.Cu")
	)
	(gr_line
		(start 103.700072 -47.999904)
		(end 103.700072 -183.76392)
		(stroke
			(width 1.524)
			(type default)
		)
		(layer "In6.Cu")
	)
	(gr_arc
		(start 104.70007 -47.999904)
		(mid 104.200198 -47.500032)
		(end 103.700072 -47.999904)
		(stroke
			(width 1.524)
			(type default)
		)
		(layer "In6.Cu")
	)
	(gr_arc
		(start 106.614722 -38.199822)
		(mid 107.099735 -38.685216)
		(end 107.585002 -38.200076)
		(stroke
			(width 0.2)
			(type default)
		)
		(layer "In6.Cu")
	)
	(gr_line
		(start 106.614722 -36.800028)
		(end 106.614722 -38.199822)
		(stroke
			(width 0.2)
			(type default)
		)
		(layer "In6.Cu")
	)
	(gr_arc
		(start 106.614722 -34.600134)
		(mid 107.099862 -35.085274)
		(end 107.585002 -34.600134)
		(stroke
			(width 0.2)
			(type default)
		)
		(layer "In6.Cu")
	)
	(gr_line
		(start 106.614722 -33.200086)
		(end 106.614722 -34.600134)
		(stroke
			(width 0.2)
			(type default)
		)
		(layer "In6.Cu")
	)
	(gr_line
		(start 107.585002 -38.200076)
		(end 107.585002 -36.800028)
		(stroke
			(width 0.2)
			(type default)
		)
		(layer "In6.Cu")
	)
	(gr_arc
		(start 107.585002 -36.800028)
		(mid 107.099862 -36.314888)
		(end 106.614722 -36.800028)
		(stroke
			(width 0.2)
			(type default)
		)
		(layer "In6.Cu")
	)
	(gr_line
		(start 107.585002 -34.600134)
		(end 107.585002 -33.20034)
		(stroke
			(width 0.2)
			(type default)
		)
		(layer "In6.Cu")
	)
	(gr_arc
		(start 107.585002 -33.20034)
		(mid 107.099989 -32.714946)
		(end 106.614722 -33.200086)
		(stroke
			(width 0.2)
			(type default)
		)
		(layer "In6.Cu")
	)
	(gr_arc
		(start 108.41482 -36.999926)
		(mid 108.899833 -37.48532)
		(end 109.3851 -37.00018)
		(stroke
			(width 0.2)
			(type default)
		)
		(layer "In6.Cu")
	)
	(gr_line
		(start 108.41482 -35.600132)
		(end 108.41482 -36.999926)
		(stroke
			(width 0.2)
			(type default)
		)
		(layer "In6.Cu")
	)
	(gr_arc
		(start 108.41482 -33.39973)
		(mid 108.899833 -33.885124)
		(end 109.3851 -33.399984)
		(stroke
			(width 0.2)
			(type default)
		)
		(layer "In6.Cu")
	)
	(gr_line
		(start 108.41482 -32.00019)
		(end 108.41482 -33.39973)
		(stroke
			(width 0.2)
			(type default)
		)
		(layer "In6.Cu")
	)
	(gr_line
		(start 109.3851 -37.00018)
		(end 109.3851 -35.600132)
		(stroke
			(width 0.2)
			(type default)
		)
		(layer "In6.Cu")
	)
	(gr_arc
		(start 109.3851 -35.600132)
		(mid 108.89996 -35.114992)
		(end 108.41482 -35.600132)
		(stroke
			(width 0.2)
			(type default)
		)
		(layer "In6.Cu")
	)
	(gr_line
		(start 109.3851 -33.399984)
		(end 109.3851 -32.00019)
		(stroke
			(width 0.2)
			(type default)
		)
		(layer "In6.Cu")
	)
	(gr_arc
		(start 109.3851 -32.00019)
		(mid 108.89996 -31.51505)
		(end 108.41482 -32.00019)
		(stroke
			(width 0.2)
			(type default)
		)
		(layer "In6.Cu")
	)
	(gr_arc
		(start 110.214918 -38.199822)
		(mid 110.699931 -38.685216)
		(end 111.185198 -38.200076)
		(stroke
			(width 0.2)
			(type default)
		)
		(layer "In6.Cu")
	)
	(gr_line
		(start 110.214918 -36.800028)
		(end 110.214918 -38.199822)
		(stroke
			(width 0.2)
			(type default)
		)
		(layer "In6.Cu")
	)
	(gr_arc
		(start 110.214918 -34.600134)
		(mid 110.700058 -35.085274)
		(end 111.185198 -34.600134)
		(stroke
			(width 0.2)
			(type default)
		)
		(layer "In6.Cu")
	)
	(gr_line
		(start 110.214918 -33.200086)
		(end 110.214918 -34.600134)
		(stroke
			(width 0.2)
			(type default)
		)
		(layer "In6.Cu")
	)
	(gr_line
		(start 111.185198 -38.200076)
		(end 111.185198 -36.800028)
		(stroke
			(width 0.2)
			(type default)
		)
		(layer "In6.Cu")
	)
	(gr_arc
		(start 111.185198 -36.800028)
		(mid 110.700058 -36.314888)
		(end 110.214918 -36.800028)
		(stroke
			(width 0.2)
			(type default)
		)
		(layer "In6.Cu")
	)
	(gr_line
		(start 111.185198 -34.600134)
		(end 111.185198 -33.20034)
		(stroke
			(width 0.2)
			(type default)
		)
		(layer "In6.Cu")
	)
	(gr_arc
		(start 111.185198 -33.20034)
		(mid 110.700185 -32.714946)
		(end 110.214918 -33.200086)
		(stroke
			(width 0.2)
			(type default)
		)
		(layer "In6.Cu")
	)
	(gr_arc
		(start 112.014762 -36.999926)
		(mid 112.499775 -37.48532)
		(end 112.985042 -37.00018)
		(stroke
			(width 0.2)
			(type default)
		)
		(layer "In6.Cu")
	)
	(gr_line
		(start 112.014762 -35.600132)
		(end 112.014762 -36.999926)
		(stroke
			(width 0.2)
			(type default)
		)
		(layer "In6.Cu")
	)
	(gr_arc
		(start 112.014762 -33.39973)
		(mid 112.499775 -33.885124)
		(end 112.985042 -33.399984)
		(stroke
			(width 0.2)
			(type default)
		)
		(layer "In6.Cu")
	)
	(gr_line
		(start 112.014762 -32.00019)
		(end 112.014762 -33.39973)
		(stroke
			(width 0.2)
			(type default)
		)
		(layer "In6.Cu")
	)
	(gr_line
		(start 112.985042 -37.00018)
		(end 112.985042 -35.600132)
		(stroke
			(width 0.2)
			(type default)
		)
		(layer "In6.Cu")
	)
	(gr_arc
		(start 112.985042 -35.600132)
		(mid 112.499902 -35.114992)
		(end 112.014762 -35.600132)
		(stroke
			(width 0.2)
			(type default)
		)
		(layer "In6.Cu")
	)
	(gr_line
		(start 112.985042 -33.399984)
		(end 112.985042 -32.00019)
		(stroke
			(width 0.2)
			(type default)
		)
		(layer "In6.Cu")
	)
	(gr_arc
		(start 112.985042 -32.00019)
		(mid 112.499902 -31.51505)
		(end 112.014762 -32.00019)
		(stroke
			(width 0.2)
			(type default)
		)
		(layer "In6.Cu")
	)
	(gr_arc
		(start 113.81486 -38.199822)
		(mid 114.299873 -38.685216)
		(end 114.78514 -38.200076)
		(stroke
			(width 0.2)
			(type default)
		)
		(layer "In6.Cu")
	)
	(gr_line
		(start 113.81486 -36.800028)
		(end 113.81486 -38.199822)
		(stroke
			(width 0.2)
			(type default)
		)
		(layer "In6.Cu")
	)
	(gr_arc
		(start 113.81486 -34.600134)
		(mid 114.3 -35.085274)
		(end 114.78514 -34.600134)
		(stroke
			(width 0.2)
			(type default)
		)
		(layer "In6.Cu")
	)
	(gr_line
		(start 113.81486 -33.200086)
		(end 113.81486 -34.600134)
		(stroke
			(width 0.2)
			(type default)
		)
		(layer "In6.Cu")
	)
	(gr_line
		(start 114.78514 -38.200076)
		(end 114.78514 -36.800028)
		(stroke
			(width 0.2)
			(type default)
		)
		(layer "In6.Cu")
	)
	(gr_arc
		(start 114.78514 -36.800028)
		(mid 114.3 -36.314888)
		(end 113.81486 -36.800028)
		(stroke
			(width 0.2)
			(type default)
		)
		(layer "In6.Cu")
	)
	(gr_line
		(start 114.78514 -34.600134)
		(end 114.78514 -33.20034)
		(stroke
			(width 0.2)
			(type default)
		)
		(layer "In6.Cu")
	)
	(gr_arc
		(start 114.78514 -33.20034)
		(mid 114.300127 -32.714946)
		(end 113.81486 -33.200086)
		(stroke
			(width 0.2)
			(type default)
		)
		(layer "In6.Cu")
	)
	(gr_arc
		(start 115.614704 -36.999926)
		(mid 116.099717 -37.48532)
		(end 116.584984 -37.00018)
		(stroke
			(width 0.2)
			(type default)
		)
		(layer "In6.Cu")
	)
	(gr_line
		(start 115.614704 -35.600132)
		(end 115.614704 -36.999926)
		(stroke
			(width 0.2)
			(type default)
		)
		(layer "In6.Cu")
	)
	(gr_arc
		(start 115.614704 -33.39973)
		(mid 116.099717 -33.885124)
		(end 116.584984 -33.399984)
		(stroke
			(width 0.2)
			(type default)
		)
		(layer "In6.Cu")
	)
	(gr_line
		(start 115.614704 -32.00019)
		(end 115.614704 -33.39973)
		(stroke
			(width 0.2)
			(type default)
		)
		(layer "In6.Cu")
	)
	(gr_line
		(start 116.584984 -37.00018)
		(end 116.584984 -35.600132)
		(stroke
			(width 0.2)
			(type default)
		)
		(layer "In6.Cu")
	)
	(gr_arc
		(start 116.584984 -35.600132)
		(mid 116.099844 -35.114992)
		(end 115.614704 -35.600132)
		(stroke
			(width 0.2)
			(type default)
		)
		(layer "In6.Cu")
	)
	(gr_line
		(start 116.584984 -33.399984)
		(end 116.584984 -32.00019)
		(stroke
			(width 0.2)
			(type default)
		)
		(layer "In6.Cu")
	)
	(gr_arc
		(start 116.584984 -32.00019)
		(mid 116.099844 -31.51505)
		(end 115.614704 -32.00019)
		(stroke
			(width 0.2)
			(type default)
		)
		(layer "In6.Cu")
	)
	(gr_arc
		(start 117.414802 -38.199822)
		(mid 117.899815 -38.685216)
		(end 118.385082 -38.200076)
		(stroke
			(width 0.2)
			(type default)
		)
		(layer "In6.Cu")
	)
	(gr_line
		(start 117.414802 -36.800028)
		(end 117.414802 -38.199822)
		(stroke
			(width 0.2)
			(type default)
		)
		(layer "In6.Cu")
	)
	(gr_arc
		(start 117.414802 -34.600134)
		(mid 117.899942 -35.085274)
		(end 118.385082 -34.600134)
		(stroke
			(width 0.2)
			(type default)
		)
		(layer "In6.Cu")
	)
	(gr_line
		(start 117.414802 -33.200086)
		(end 117.414802 -34.600134)
		(stroke
			(width 0.2)
			(type default)
		)
		(layer "In6.Cu")
	)
	(gr_line
		(start 118.385082 -38.200076)
		(end 118.385082 -36.800028)
		(stroke
			(width 0.2)
			(type default)
		)
		(layer "In6.Cu")
	)
	(gr_arc
		(start 118.385082 -36.800028)
		(mid 117.899942 -36.314888)
		(end 117.414802 -36.800028)
		(stroke
			(width 0.2)
			(type default)
		)
		(layer "In6.Cu")
	)
	(gr_line
		(start 118.385082 -34.600134)
		(end 118.385082 -33.20034)
		(stroke
			(width 0.2)
			(type default)
		)
		(layer "In6.Cu")
	)
	(gr_arc
		(start 118.385082 -33.20034)
		(mid 117.900069 -32.714946)
		(end 117.414802 -33.200086)
		(stroke
			(width 0.2)
			(type default)
		)
		(layer "In6.Cu")
	)
	(gr_arc
		(start 119.2149 -44.19981)
		(mid 119.699913 -44.685204)
		(end 120.18518 -44.200064)
		(stroke
			(width 0.2)
			(type default)
		)
		(layer "In6.Cu")
	)
	(gr_line
		(start 119.2149 -42.800016)
		(end 119.2149 -44.19981)
		(stroke
			(width 0.2)
			(type default)
		)
		(layer "In6.Cu")
	)
	(gr_arc
		(start 119.2149 -36.999926)
		(mid 119.699913 -37.48532)
		(end 120.18518 -37.00018)
		(stroke
			(width 0.2)
			(type default)
		)
		(layer "In6.Cu")
	)
	(gr_line
		(start 119.2149 -35.600132)
		(end 119.2149 -36.999926)
		(stroke
			(width 0.2)
			(type default)
		)
		(layer "In6.Cu")
	)
	(gr_arc
		(start 119.2149 -33.39973)
		(mid 119.699913 -33.885124)
		(end 120.18518 -33.399984)
		(stroke
			(width 0.2)
			(type default)
		)
		(layer "In6.Cu")
	)
	(gr_line
		(start 119.2149 -32.00019)
		(end 119.2149 -33.39973)
		(stroke
			(width 0.2)
			(type default)
		)
		(layer "In6.Cu")
	)
	(gr_line
		(start 120.18518 -44.200064)
		(end 120.18518 -42.800016)
		(stroke
			(width 0.2)
			(type default)
		)
		(layer "In6.Cu")
	)
	(gr_arc
		(start 120.18518 -42.800016)
		(mid 119.70004 -42.314876)
		(end 119.2149 -42.800016)
		(stroke
			(width 0.2)
			(type default)
		)
		(layer "In6.Cu")
	)
	(gr_line
		(start 120.18518 -37.00018)
		(end 120.18518 -35.600132)
		(stroke
			(width 0.2)
			(type default)
		)
		(layer "In6.Cu")
	)
	(gr_arc
		(start 120.18518 -35.600132)
		(mid 119.70004 -35.114992)
		(end 119.2149 -35.600132)
		(stroke
			(width 0.2)
			(type default)
		)
		(layer "In6.Cu")
	)
	(gr_line
		(start 120.18518 -33.399984)
		(end 120.18518 -32.00019)
		(stroke
			(width 0.2)
			(type default)
		)
		(layer "In6.Cu")
	)
	(gr_arc
		(start 120.18518 -32.00019)
		(mid 119.70004 -31.51505)
		(end 119.2149 -32.00019)
		(stroke
			(width 0.2)
			(type default)
		)
		(layer "In6.Cu")
	)
	(gr_arc
		(start 128.214882 -38.199822)
		(mid 128.699895 -38.685216)
		(end 129.185162 -38.200076)
		(stroke
			(width 0.2)
			(type default)
		)
		(layer "In6.Cu")
	)
	(gr_line
		(start 128.214882 -36.800028)
		(end 128.214882 -38.199822)
		(stroke
			(width 0.2)
			(type default)
		)
		(layer "In6.Cu")
	)
	(gr_arc
		(start 128.214882 -34.600134)
		(mid 128.700022 -35.085274)
		(end 129.185162 -34.600134)
		(stroke
			(width 0.2)
			(type default)
		)
		(layer "In6.Cu")
	)
	(gr_line
		(start 128.214882 -33.200086)
		(end 128.214882 -34.600134)
		(stroke
			(width 0.2)
			(type default)
		)
		(layer "In6.Cu")
	)
	(gr_line
		(start 128.467866 -26.592276)
		(end 129.53492 -26.592276)
		(stroke
			(width 0.2)
			(type default)
		)
		(layer "In6.Cu")
	)
	(gr_arc
		(start 128.467866 -25.830276)
		(mid 128.086866 -26.211276)
		(end 128.467866 -26.592276)
		(stroke
			(width 0.2)
			(type default)
		)
		(layer "In6.Cu")
	)
	(gr_line
		(start 129.185162 -38.200076)
		(end 129.185162 -36.800028)
		(stroke
			(width 0.2)
			(type default)
		)
		(layer "In6.Cu")
	)
	(gr_arc
		(start 129.185162 -36.800028)
		(mid 128.700022 -36.314888)
		(end 128.214882 -36.800028)
		(stroke
			(width 0.2)
			(type default)
		)
		(layer "In6.Cu")
	)
	(gr_line
		(start 129.185162 -34.600134)
		(end 129.185162 -33.20034)
		(stroke
			(width 0.2)
			(type default)
		)
		(layer "In6.Cu")
	)
	(gr_arc
		(start 129.185162 -33.20034)
		(mid 128.700149 -32.714946)
		(end 128.214882 -33.200086)
		(stroke
			(width 0.2)
			(type default)
		)
		(layer "In6.Cu")
	)
	(gr_arc
		(start 129.53492 -26.592276)
		(mid 129.916174 -26.211403)
		(end 129.535174 -25.830276)
		(stroke
			(width 0.2)
			(type default)
		)
		(layer "In6.Cu")
	)
	(gr_line
		(start 129.535174 -25.830276)
		(end 128.467866 -25.830276)
		(stroke
			(width 0.2)
			(type default)
		)
		(layer "In6.Cu")
	)
	(gr_arc
		(start 130.014726 -36.999926)
		(mid 130.499739 -37.48532)
		(end 130.985006 -37.00018)
		(stroke
			(width 0.2)
			(type default)
		)
		(layer "In6.Cu")
	)
	(gr_line
		(start 130.014726 -35.600132)
		(end 130.014726 -36.999926)
		(stroke
			(width 0.2)
			(type default)
		)
		(layer "In6.Cu")
	)
	(gr_arc
		(start 130.014726 -33.39973)
		(mid 130.499739 -33.885124)
		(end 130.985006 -33.399984)
		(stroke
			(width 0.2)
			(type default)
		)
		(layer "In6.Cu")
	)
	(gr_line
		(start 130.014726 -32.00019)
		(end 130.014726 -33.39973)
		(stroke
			(width 0.2)
			(type default)
		)
		(layer "In6.Cu")
	)
	(gr_line
		(start 130.985006 -37.00018)
		(end 130.985006 -35.600132)
		(stroke
			(width 0.2)
			(type default)
		)
		(layer "In6.Cu")
	)
	(gr_arc
		(start 130.985006 -35.600132)
		(mid 130.499866 -35.114992)
		(end 130.014726 -35.600132)
		(stroke
			(width 0.2)
			(type default)
		)
		(layer "In6.Cu")
	)
	(gr_line
		(start 130.985006 -33.399984)
		(end 130.985006 -32.00019)
		(stroke
			(width 0.2)
			(type default)
		)
		(layer "In6.Cu")
	)
	(gr_arc
		(start 130.985006 -32.00019)
		(mid 130.499866 -31.51505)
		(end 130.014726 -32.00019)
		(stroke
			(width 0.2)
			(type default)
		)
		(layer "In6.Cu")
	)
	(gr_arc
		(start 131.814824 -38.199822)
		(mid 132.299837 -38.685216)
		(end 132.785104 -38.200076)
		(stroke
			(width 0.2)
			(type default)
		)
		(layer "In6.Cu")
	)
	(gr_line
		(start 131.814824 -36.800028)
		(end 131.814824 -38.199822)
		(stroke
			(width 0.2)
			(type default)
		)
		(layer "In6.Cu")
	)
	(gr_arc
		(start 131.814824 -34.600134)
		(mid 132.299964 -35.085274)
		(end 132.785104 -34.600134)
		(stroke
			(width 0.2)
			(type default)
		)
		(layer "In6.Cu")
	)
	(gr_line
		(start 131.814824 -33.200086)
		(end 131.814824 -34.600134)
		(stroke
			(width 0.2)
			(type default)
		)
		(layer "In6.Cu")
	)
	(gr_line
		(start 132.785104 -38.200076)
		(end 132.785104 -36.800028)
		(stroke
			(width 0.2)
			(type default)
		)
		(layer "In6.Cu")
	)
	(gr_arc
		(start 132.785104 -36.800028)
		(mid 132.299964 -36.314888)
		(end 131.814824 -36.800028)
		(stroke
			(width 0.2)
			(type default)
		)
		(layer "In6.Cu")
	)
	(gr_line
		(start 132.785104 -34.600134)
		(end 132.785104 -33.20034)
		(stroke
			(width 0.2)
			(type default)
		)
		(layer "In6.Cu")
	)
	(gr_arc
		(start 132.785104 -33.20034)
		(mid 132.300091 -32.714946)
		(end 131.814824 -33.200086)
		(stroke
			(width 0.2)
			(type default)
		)
		(layer "In6.Cu")
	)
	(gr_arc
		(start 133.614922 -44.19981)
		(mid 134.099935 -44.685204)
		(end 134.585202 -44.200064)
		(stroke
			(width 0.2)
			(type default)
		)
		(layer "In6.Cu")
	)
	(gr_line
		(start 133.614922 -42.800016)
		(end 133.614922 -44.19981)
		(stroke
			(width 0.2)
			(type default)
		)
		(layer "In6.Cu")
	)
	(gr_arc
		(start 133.614922 -36.999926)
		(mid 134.099935 -37.48532)
		(end 134.585202 -37.00018)
		(stroke
			(width 0.2)
			(type default)
		)
		(layer "In6.Cu")
	)
	(gr_line
		(start 133.614922 -35.600132)
		(end 133.614922 -36.999926)
		(stroke
			(width 0.2)
			(type default)
		)
		(layer "In6.Cu")
	)
	(gr_arc
		(start 133.614922 -33.39973)
		(mid 134.099935 -33.885124)
		(end 134.585202 -33.399984)
		(stroke
			(width 0.2)
			(type default)
		)
		(layer "In6.Cu")
	)
	(gr_line
		(start 133.614922 -32.00019)
		(end 133.614922 -33.39973)
		(stroke
			(width 0.2)
			(type default)
		)
		(layer "In6.Cu")
	)
	(gr_line
		(start 134.585202 -44.200064)
		(end 134.585202 -42.800016)
		(stroke
			(width 0.2)
			(type default)
		)
		(layer "In6.Cu")
	)
	(gr_arc
		(start 134.585202 -42.800016)
		(mid 134.100062 -42.314876)
		(end 133.614922 -42.800016)
		(stroke
			(width 0.2)
			(type default)
		)
		(layer "In6.Cu")
	)
	(gr_line
		(start 134.585202 -37.00018)
		(end 134.585202 -35.600132)
		(stroke
			(width 0.2)
			(type default)
		)
		(layer "In6.Cu")
	)
	(gr_arc
		(start 134.585202 -35.600132)
		(mid 134.100062 -35.114992)
		(end 133.614922 -35.600132)
		(stroke
			(width 0.2)
			(type default)
		)
		(layer "In6.Cu")
	)
	(gr_line
		(start 134.585202 -33.399984)
		(end 134.585202 -32.00019)
		(stroke
			(width 0.2)
			(type default)
		)
		(layer "In6.Cu")
	)
	(gr_arc
		(start 134.585202 -32.00019)
		(mid 134.100062 -31.51505)
		(end 133.614922 -32.00019)
		(stroke
			(width 0.2)
			(type default)
		)
		(layer "In6.Cu")
	)
	(gr_arc
		(start 135.414766 -38.199822)
		(mid 135.899779 -38.685216)
		(end 136.385046 -38.200076)
		(stroke
			(width 0.2)
			(type default)
		)
		(layer "In6.Cu")
	)
	(gr_line
		(start 135.414766 -36.800028)
		(end 135.414766 -38.199822)
		(stroke
			(width 0.2)
			(type default)
		)
		(layer "In6.Cu")
	)
	(gr_arc
		(start 135.414766 -34.600134)
		(mid 135.899906 -35.085274)
		(end 136.385046 -34.600134)
		(stroke
			(width 0.2)
			(type default)
		)
		(layer "In6.Cu")
	)
	(gr_line
		(start 135.414766 -33.200086)
		(end 135.414766 -34.600134)
		(stroke
			(width 0.2)
			(type default)
		)
		(layer "In6.Cu")
	)
	(gr_line
		(start 136.385046 -38.200076)
		(end 136.385046 -36.800028)
		(stroke
			(width 0.2)
			(type default)
		)
		(layer "In6.Cu")
	)
	(gr_arc
		(start 136.385046 -36.800028)
		(mid 135.899906 -36.314888)
		(end 135.414766 -36.800028)
		(stroke
			(width 0.2)
			(type default)
		)
		(layer "In6.Cu")
	)
	(gr_line
		(start 136.385046 -34.600134)
		(end 136.385046 -33.20034)
		(stroke
			(width 0.2)
			(type default)
		)
		(layer "In6.Cu")
	)
	(gr_arc
		(start 136.385046 -33.20034)
		(mid 135.900033 -32.714946)
		(end 135.414766 -33.200086)
		(stroke
			(width 0.2)
			(type default)
		)
		(layer "In6.Cu")
	)
	(gr_arc
		(start 137.214864 -36.999926)
		(mid 137.699877 -37.48532)
		(end 138.185144 -37.00018)
		(stroke
			(width 0.2)
			(type default)
		)
		(layer "In6.Cu")
	)
	(gr_line
		(start 137.214864 -35.600132)
		(end 137.214864 -36.999926)
		(stroke
			(width 0.2)
			(type default)
		)
		(layer "In6.Cu")
	)
	(gr_arc
		(start 137.214864 -33.39973)
		(mid 137.699877 -33.885124)
		(end 138.185144 -33.399984)
		(stroke
			(width 0.2)
			(type default)
		)
		(layer "In6.Cu")
	)
	(gr_line
		(start 137.214864 -32.00019)
		(end 137.214864 -33.39973)
		(stroke
			(width 0.2)
			(type default)
		)
		(layer "In6.Cu")
	)
	(gr_line
		(start 138.185144 -37.00018)
		(end 138.185144 -35.600132)
		(stroke
			(width 0.2)
			(type default)
		)
		(layer "In6.Cu")
	)
	(gr_arc
		(start 138.185144 -35.600132)
		(mid 137.700004 -35.114992)
		(end 137.214864 -35.600132)
		(stroke
			(width 0.2)
			(type default)
		)
		(layer "In6.Cu")
	)
	(gr_line
		(start 138.185144 -33.399984)
		(end 138.185144 -32.00019)
		(stroke
			(width 0.2)
			(type default)
		)
		(layer "In6.Cu")
	)
	(gr_arc
		(start 138.185144 -32.00019)
		(mid 137.700004 -31.51505)
		(end 137.214864 -32.00019)
		(stroke
			(width 0.2)
			(type default)
		)
		(layer "In6.Cu")
	)
	(gr_arc
		(start 139.014708 -38.199822)
		(mid 139.499721 -38.685216)
		(end 139.984988 -38.200076)
		(stroke
			(width 0.2)
			(type default)
		)
		(layer "In6.Cu")
	)
	(gr_line
		(start 139.014708 -36.800028)
		(end 139.014708 -38.199822)
		(stroke
			(width 0.2)
			(type default)
		)
		(layer "In6.Cu")
	)
	(gr_arc
		(start 139.014708 -34.600134)
		(mid 139.499848 -35.085274)
		(end 139.984988 -34.600134)
		(stroke
			(width 0.2)
			(type default)
		)
		(layer "In6.Cu")
	)
	(gr_line
		(start 139.014708 -33.200086)
		(end 139.014708 -34.600134)
		(stroke
			(width 0.2)
			(type default)
		)
		(layer "In6.Cu")
	)
	(gr_line
		(start 139.984988 -38.200076)
		(end 139.984988 -36.800028)
		(stroke
			(width 0.2)
			(type default)
		)
		(layer "In6.Cu")
	)
	(gr_arc
		(start 139.984988 -36.800028)
		(mid 139.499848 -36.314888)
		(end 139.014708 -36.800028)
		(stroke
			(width 0.2)
			(type default)
		)
		(layer "In6.Cu")
	)
	(gr_line
		(start 139.984988 -34.600134)
		(end 139.984988 -33.20034)
		(stroke
			(width 0.2)
			(type default)
		)
		(layer "In6.Cu")
	)
	(gr_arc
		(start 139.984988 -33.20034)
		(mid 139.499975 -32.714946)
		(end 139.014708 -33.200086)
		(stroke
			(width 0.2)
			(type default)
		)
		(layer "In6.Cu")
	)
	(gr_arc
		(start 140.814806 -44.19981)
		(mid 141.299819 -44.685204)
		(end 141.785086 -44.200064)
		(stroke
			(width 0.2)
			(type default)
		)
		(layer "In6.Cu")
	)
	(gr_line
		(start 140.814806 -42.800016)
		(end 140.814806 -44.19981)
		(stroke
			(width 0.2)
			(type default)
		)
		(layer "In6.Cu")
	)
	(gr_arc
		(start 140.814806 -36.999926)
		(mid 141.299819 -37.48532)
		(end 141.785086 -37.00018)
		(stroke
			(width 0.2)
			(type default)
		)
		(layer "In6.Cu")
	)
	(gr_line
		(start 140.814806 -35.600132)
		(end 140.814806 -36.999926)
		(stroke
			(width 0.2)
			(type default)
		)
		(layer "In6.Cu")
	)
	(gr_arc
		(start 140.814806 -33.39973)
		(mid 141.299819 -33.885124)
		(end 141.785086 -33.399984)
		(stroke
			(width 0.2)
			(type default)
		)
		(layer "In6.Cu")
	)
	(gr_line
		(start 140.814806 -32.00019)
		(end 140.814806 -33.39973)
		(stroke
			(width 0.2)
			(type default)
		)
		(layer "In6.Cu")
	)
	(gr_line
		(start 141.785086 -44.200064)
		(end 141.785086 -42.800016)
		(stroke
			(width 0.2)
			(type default)
		)
		(layer "In6.Cu")
	)
	(gr_arc
		(start 141.785086 -42.800016)
		(mid 141.299946 -42.314876)
		(end 140.814806 -42.800016)
		(stroke
			(width 0.2)
			(type default)
		)
		(layer "In6.Cu")
	)
	(gr_line
		(start 141.785086 -37.00018)
		(end 141.785086 -35.600132)
		(stroke
			(width 0.2)
			(type default)
		)
		(layer "In6.Cu")
	)
	(gr_arc
		(start 141.785086 -35.600132)
		(mid 141.299946 -35.114992)
		(end 140.814806 -35.600132)
		(stroke
			(width 0.2)
			(type default)
		)
		(layer "In6.Cu")
	)
	(gr_line
		(start 141.785086 -33.399984)
		(end 141.785086 -32.00019)
		(stroke
			(width 0.2)
			(type default)
		)
		(layer "In6.Cu")
	)
	(gr_arc
		(start 141.785086 -32.00019)
		(mid 141.299946 -31.51505)
		(end 140.814806 -32.00019)
		(stroke
			(width 0.2)
			(type default)
		)
		(layer "In6.Cu")
	)
	(gr_line
		(start 143.299942 -47.999904)
		(end 104.70007 -47.999904)
		(stroke
			(width 1.524)
			(type default)
		)
		(layer "In6.Cu")
	)
	(gr_line
		(start 144.29994 -149.763988)
		(end 144.29994 -47.999904)
		(stroke
			(width 1.524)
			(type default)
		)
		(layer "In6.Cu")
	)
	(gr_arc
		(start 144.29994 -149.763988)
		(mid 144.326787 -149.993649)
		(end 144.405604 -150.211028)
		(stroke
			(width 1.524)
			(type default)
		)
		(layer "In6.Cu")
	)
	(gr_arc
		(start 144.29994 -47.999904)
		(mid 143.800068 -47.500032)
		(end 143.299942 -47.999904)
		(stroke
			(width 1.524)
			(type default)
		)
		(layer "In6.Cu")
	)
	(gr_line
		(start 149.023578 -159.44723)
		(end 144.405604 -150.211028)
		(stroke
			(width 1.524)
			(type default)
		)
		(layer "In6.Cu")
	)
	(gr_arc
		(start 149.023578 -159.44723)
		(mid 149.392231 -159.850635)
		(end 149.917912 -159.999934)
		(stroke
			(width 1.524)
			(type default)
		)
		(layer "In6.Cu")
	)
	(gr_line
		(start 166.84244 -137.175494)
		(end 167.47109 -137.80389)
		(stroke
			(width 0.2)
			(type default)
		)
		(layer "In6.Cu")
	)
	(gr_arc
		(start 167.381428 -136.636506)
		(mid 166.84244 -136.636506)
		(end 166.84244 -137.175494)
		(stroke
			(width 0.2)
			(type default)
		)
		(layer "In6.Cu")
	)
	(gr_arc
		(start 167.47109 -137.80389)
		(mid 168.009888 -137.804081)
		(end 168.010078 -137.265156)
		(stroke
			(width 0.2)
			(type default)
		)
		(layer "In6.Cu")
	)
	(gr_line
		(start 168.010078 -137.265156)
		(end 167.381428 -136.636506)
		(stroke
			(width 0.2)
			(type default)
		)
		(layer "In6.Cu")
	)
	(gr_line
		(start 170.170602 -138.590528)
		(end 170.799252 -139.218924)
		(stroke
			(width 0.2)
			(type default)
		)
		(layer "In6.Cu")
	)
	(gr_arc
		(start 170.70959 -138.05154)
		(mid 170.170602 -138.05154)
		(end 170.170602 -138.590528)
		(stroke
			(width 0.2)
			(type default)
		)
		(layer "In6.Cu")
	)
	(gr_arc
		(start 170.799252 -139.218924)
		(mid 171.33805 -139.219115)
		(end 171.33824 -138.68019)
		(stroke
			(width 0.2)
			(type default)
		)
		(layer "In6.Cu")
	)
	(gr_line
		(start 171.33824 -138.68019)
		(end 170.70959 -138.05154)
		(stroke
			(width 0.2)
			(type default)
		)
		(layer "In6.Cu")
	)
	(gr_line
		(start 173.674278 -138.194542)
		(end 174.302928 -138.822938)
		(stroke
			(width 0.2)
			(type default)
		)
		(layer "In6.Cu")
	)
	(gr_line
		(start 174.024798 -140.502386)
		(end 174.653448 -141.130782)
		(stroke
			(width 0.2)
			(type default)
		)
		(layer "In6.Cu")
	)
	(gr_arc
		(start 174.213266 -137.655554)
		(mid 173.674278 -137.655554)
		(end 173.674278 -138.194542)
		(stroke
			(width 0.2)
			(type default)
		)
		(layer "In6.Cu")
	)
	(gr_arc
		(start 174.302928 -138.822938)
		(mid 174.841726 -138.823129)
		(end 174.841916 -138.284204)
		(stroke
			(width 0.2)
			(type default)
		)
		(layer "In6.Cu")
	)
	(gr_arc
		(start 174.563786 -139.963398)
		(mid 174.024798 -139.963398)
		(end 174.024798 -140.502386)
		(stroke
			(width 0.2)
			(type default)
		)
		(layer "In6.Cu")
	)
	(gr_arc
		(start 174.653448 -141.130782)
		(mid 175.192246 -141.130973)
		(end 175.192436 -140.592048)
		(stroke
			(width 0.2)
			(type default)
		)
		(layer "In6.Cu")
	)
	(gr_line
		(start 174.841916 -138.284204)
		(end 174.213266 -137.655554)
		(stroke
			(width 0.2)
			(type default)
		)
		(layer "In6.Cu")
	)
	(gr_line
		(start 175.192436 -140.592048)
		(end 174.563786 -139.963398)
		(stroke
			(width 0.2)
			(type default)
		)
		(layer "In6.Cu")
	)
	(gr_line
		(start 177.391568 -140.243306)
		(end 178.020218 -140.871702)
		(stroke
			(width 0.2)
			(type default)
		)
		(layer "In6.Cu")
	)
	(gr_arc
		(start 177.930556 -139.704318)
		(mid 177.391568 -139.704318)
		(end 177.391568 -140.243306)
		(stroke
			(width 0.2)
			(type default)
		)
		(layer "In6.Cu")
	)
	(gr_arc
		(start 178.020218 -140.871702)
		(mid 178.559016 -140.871893)
		(end 178.559206 -140.332968)
		(stroke
			(width 0.2)
			(type default)
		)
		(layer "In6.Cu")
	)
	(gr_line
		(start 178.559206 -140.332968)
		(end 177.930556 -139.704318)
		(stroke
			(width 0.2)
			(type default)
		)
		(layer "In6.Cu")
	)
	(gr_line
		(start 179.735734 -140.438378)
		(end 180.364384 -141.066774)
		(stroke
			(width 0.2)
			(type default)
		)
		(layer "In6.Cu")
	)
	(gr_arc
		(start 180.274722 -139.89939)
		(mid 179.735734 -139.89939)
		(end 179.735734 -140.438378)
		(stroke
			(width 0.2)
			(type default)
		)
		(layer "In6.Cu")
	)
	(gr_arc
		(start 180.364384 -141.066774)
		(mid 180.903182 -141.066965)
		(end 180.903372 -140.52804)
		(stroke
			(width 0.2)
			(type default)
		)
		(layer "In6.Cu")
	)
	(gr_line
		(start 180.903372 -140.52804)
		(end 180.274722 -139.89939)
		(stroke
			(width 0.2)
			(type default)
		)
		(layer "In6.Cu")
	)
	(gr_line
		(start 182.059072 -139.932918)
		(end 182.687722 -140.561314)
		(stroke
			(width 0.2)
			(type default)
		)
		(layer "In6.Cu")
	)
	(gr_arc
		(start 182.59806 -139.39393)
		(mid 182.059072 -139.39393)
		(end 182.059072 -139.932918)
		(stroke
			(width 0.2)
			(type default)
		)
		(layer "In6.Cu")
	)
	(gr_arc
		(start 182.687722 -140.561314)
		(mid 183.22652 -140.561505)
		(end 183.22671 -140.02258)
		(stroke
			(width 0.2)
			(type default)
		)
		(layer "In6.Cu")
	)
	(gr_line
		(start 183.016144 -133.354826)
		(end 183.90489 -133.354826)
		(stroke
			(width 0.2)
			(type default)
		)
		(layer "In6.Cu")
	)
	(gr_arc
		(start 183.016144 -132.592826)
		(mid 182.635144 -132.973826)
		(end 183.016144 -133.354826)
		(stroke
			(width 0.2)
			(type default)
		)
		(layer "In6.Cu")
	)
	(gr_line
		(start 183.22671 -140.02258)
		(end 182.59806 -139.39393)
		(stroke
			(width 0.2)
			(type default)
		)
		(layer "In6.Cu")
	)
	(gr_arc
		(start 183.90489 -133.354826)
		(mid 184.286144 -132.973953)
		(end 183.905144 -132.592826)
		(stroke
			(width 0.2)
			(type default)
		)
		(layer "In6.Cu")
	)
	(gr_line
		(start 183.905144 -132.592826)
		(end 183.016144 -132.592826)
		(stroke
			(width 0.2)
			(type default)
		)
		(layer "In6.Cu")
	)
	(gr_line
		(start 184.815734 -139.955778)
		(end 185.444384 -140.584174)
		(stroke
			(width 0.2)
			(type default)
		)
		(layer "In6.Cu")
	)
	(gr_arc
		(start 185.354722 -139.41679)
		(mid 184.815734 -139.41679)
		(end 184.815734 -139.955778)
		(stroke
			(width 0.2)
			(type default)
		)
		(layer "In6.Cu")
	)
	(gr_arc
		(start 185.444384 -140.584174)
		(mid 185.983182 -140.584365)
		(end 185.983372 -140.04544)
		(stroke
			(width 0.2)
			(type default)
		)
		(layer "In6.Cu")
	)
	(gr_line
		(start 185.983372 -140.04544)
		(end 185.354722 -139.41679)
		(stroke
			(width 0.2)
			(type default)
		)
		(layer "In6.Cu")
	)
	(gr_line
		(start 191.821308 -139.528296)
		(end 192.449958 -140.156692)
		(stroke
			(width 0.2)
			(type default)
		)
		(layer "In6.Cu")
	)
	(gr_arc
		(start 192.360296 -138.989308)
		(mid 191.821308 -138.989308)
		(end 191.821308 -139.528296)
		(stroke
			(width 0.2)
			(type default)
		)
		(layer "In6.Cu")
	)
	(gr_arc
		(start 192.449958 -140.156692)
		(mid 192.988756 -140.156883)
		(end 192.988946 -139.617958)
		(stroke
			(width 0.2)
			(type default)
		)
		(layer "In6.Cu")
	)
	(gr_line
		(start 192.988946 -139.617958)
		(end 192.360296 -138.989308)
		(stroke
			(width 0.2)
			(type default)
		)
		(layer "In6.Cu")
	)
	(gr_line
		(start 194.869308 -140.671296)
		(end 195.497958 -141.299692)
		(stroke
			(width 0.2)
			(type default)
		)
		(layer "In6.Cu")
	)
	(gr_arc
		(start 195.408296 -140.132308)
		(mid 194.869308 -140.132308)
		(end 194.869308 -140.671296)
		(stroke
			(width 0.2)
			(type default)
		)
		(layer "In6.Cu")
	)
	(gr_arc
		(start 195.497958 -141.299692)
		(mid 196.036756 -141.299883)
		(end 196.036946 -140.760958)
		(stroke
			(width 0.2)
			(type default)
		)
		(layer "In6.Cu")
	)
	(gr_line
		(start 196.036946 -140.760958)
		(end 195.408296 -140.132308)
		(stroke
			(width 0.2)
			(type default)
		)
		(layer "In6.Cu")
	)
	(gr_line
		(start 197.536308 -140.925296)
		(end 198.164958 -141.553692)
		(stroke
			(width 0.2)
			(type default)
		)
		(layer "In6.Cu")
	)
	(gr_arc
		(start 198.075296 -140.386308)
		(mid 197.536308 -140.386308)
		(end 197.536308 -140.925296)
		(stroke
			(width 0.2)
			(type default)
		)
		(layer "In6.Cu")
	)
	(gr_arc
		(start 198.164958 -141.553692)
		(mid 198.703756 -141.553883)
		(end 198.703946 -141.014958)
		(stroke
			(width 0.2)
			(type default)
		)
		(layer "In6.Cu")
	)
	(gr_line
		(start 198.703946 -141.014958)
		(end 198.075296 -140.386308)
		(stroke
			(width 0.2)
			(type default)
		)
		(layer "In6.Cu")
	)
	(gr_line
		(start 199.949308 -141.179296)
		(end 200.577958 -141.807692)
		(stroke
			(width 0.2)
			(type default)
		)
		(layer "In6.Cu")
	)
	(gr_arc
		(start 200.488296 -140.640308)
		(mid 199.949308 -140.640308)
		(end 199.949308 -141.179296)
		(stroke
			(width 0.2)
			(type default)
		)
		(layer "In6.Cu")
	)
	(gr_arc
		(start 200.577958 -141.807692)
		(mid 201.116756 -141.807883)
		(end 201.116946 -141.268958)
		(stroke
			(width 0.2)
			(type default)
		)
		(layer "In6.Cu")
	)
	(gr_line
		(start 201.116946 -141.268958)
		(end 200.488296 -140.640308)
		(stroke
			(width 0.2)
			(type default)
		)
		(layer "In6.Cu")
	)
	(gr_line
		(start 202.362308 -141.052296)
		(end 202.990958 -141.680692)
		(stroke
			(width 0.2)
			(type default)
		)
		(layer "In6.Cu")
	)
	(gr_arc
		(start 202.901296 -140.513308)
		(mid 202.362308 -140.513308)
		(end 202.362308 -141.052296)
		(stroke
			(width 0.2)
			(type default)
		)
		(layer "In6.Cu")
	)
	(gr_arc
		(start 202.990958 -141.680692)
		(mid 203.529756 -141.680883)
		(end 203.529946 -141.141958)
		(stroke
			(width 0.2)
			(type default)
		)
		(layer "In6.Cu")
	)
	(gr_line
		(start 203.529946 -141.141958)
		(end 202.901296 -140.513308)
		(stroke
			(width 0.2)
			(type default)
		)
		(layer "In6.Cu")
	)
	(gr_line
		(start 204.648308 -141.179296)
		(end 205.276958 -141.807692)
		(stroke
			(width 0.2)
			(type default)
		)
		(layer "In6.Cu")
	)
	(gr_arc
		(start 205.187296 -140.640308)
		(mid 204.648308 -140.640308)
		(end 204.648308 -141.179296)
		(stroke
			(width 0.2)
			(type default)
		)
		(layer "In6.Cu")
	)
	(gr_arc
		(start 205.276958 -141.807692)
		(mid 205.815756 -141.807883)
		(end 205.815946 -141.268958)
		(stroke
			(width 0.2)
			(type default)
		)
		(layer "In6.Cu")
	)
	(gr_line
		(start 205.815946 -141.268958)
		(end 205.187296 -140.640308)
		(stroke
			(width 0.2)
			(type default)
		)
		(layer "In6.Cu")
	)
	(gr_line
		(start 206.172308 -139.528296)
		(end 206.800958 -140.156692)
		(stroke
			(width 0.2)
			(type default)
		)
		(layer "In6.Cu")
	)
	(gr_arc
		(start 206.711296 -138.989308)
		(mid 206.172308 -138.989308)
		(end 206.172308 -139.528296)
		(stroke
			(width 0.2)
			(type default)
		)
		(layer "In6.Cu")
	)
	(gr_arc
		(start 206.800958 -140.156692)
		(mid 207.339756 -140.156883)
		(end 207.339946 -139.617958)
		(stroke
			(width 0.2)
			(type default)
		)
		(layer "In6.Cu")
	)
	(gr_line
		(start 207.339946 -139.617958)
		(end 206.711296 -138.989308)
		(stroke
			(width 0.2)
			(type default)
		)
		(layer "In6.Cu")
	)
	(gr_line
		(start 209.347308 -140.798296)
		(end 209.975958 -141.426692)
		(stroke
			(width 0.2)
			(type default)
		)
		(layer "In6.Cu")
	)
	(gr_arc
		(start 209.886296 -140.259308)
		(mid 209.347308 -140.259308)
		(end 209.347308 -140.798296)
		(stroke
			(width 0.2)
			(type default)
		)
		(layer "In6.Cu")
	)
	(gr_arc
		(start 209.975958 -141.426692)
		(mid 210.514756 -141.426883)
		(end 210.514946 -140.887958)
		(stroke
			(width 0.2)
			(type default)
		)
		(layer "In6.Cu")
	)
	(gr_line
		(start 210.514946 -140.887958)
		(end 209.886296 -140.259308)
		(stroke
			(width 0.2)
			(type default)
		)
		(layer "In6.Cu")
	)
	(gr_line
		(start 213.063836 -139.146534)
		(end 213.692486 -139.77493)
		(stroke
			(width 0.2)
			(type default)
		)
		(layer "In6.Cu")
	)
	(gr_arc
		(start 213.602824 -138.607546)
		(mid 213.063836 -138.607546)
		(end 213.063836 -139.146534)
		(stroke
			(width 0.2)
			(type default)
		)
		(layer "In6.Cu")
	)
	(gr_arc
		(start 213.692486 -139.77493)
		(mid 214.231284 -139.775121)
		(end 214.231474 -139.236196)
		(stroke
			(width 0.2)
			(type default)
		)
		(layer "In6.Cu")
	)
	(gr_line
		(start 214.00008 -159.999934)
		(end 149.917912 -159.999934)
		(stroke
			(width 1.524)
			(type default)
		)
		(layer "In6.Cu")
	)
	(gr_line
		(start 214.231474 -139.236196)
		(end 213.602824 -138.607546)
		(stroke
			(width 0.2)
			(type default)
		)
		(layer "In6.Cu")
	)
	(gr_line
		(start 215.000078 -193.000122)
		(end 215.000078 -160.999932)
		(stroke
			(width 1.524)
			(type default)
		)
		(layer "In6.Cu")
	)
	(gr_arc
		(start 215.000078 -193.000122)
		(mid 215.292977 -193.707222)
		(end 216.000076 -194.00012)
		(stroke
			(width 1.524)
			(type default)
		)
		(layer "In6.Cu")
	)
	(gr_arc
		(start 215.000078 -160.999932)
		(mid 214.707185 -160.292827)
		(end 214.00008 -159.999934)
		(stroke
			(width 1.524)
			(type default)
		)
		(layer "In6.Cu")
	)
	(gr_line
		(start 229.382066 -194.00012)
		(end 216.000076 -194.00012)
		(stroke
			(width 1.524)
			(type default)
		)
		(layer "In6.Cu")
	)
	(gr_arc
		(start 229.382066 -194.00012)
		(mid 229.907793 -193.850701)
		(end 230.2764 -193.447162)
		(stroke
			(width 1.524)
			(type default)
		)
		(layer "In6.Cu")
	)
	(gr_line
		(start 234.894374 -184.211214)
		(end 230.2764 -193.447162)
		(stroke
			(width 1.524)
			(type default)
		)
		(layer "In6.Cu")
	)
	(gr_arc
		(start 234.894374 -184.211214)
		(mid 234.97328 -183.993726)
		(end 235.000038 -183.76392)
		(stroke
			(width 1.524)
			(type default)
		)
		(layer "In6.Cu")
	)
	(gr_arc
		(start 235.000038 -0.999998)
		(mid 234.707147 -0.29288)
		(end 234.00004 0)
		(stroke
			(width 1.524)
			(type default)
		)
		(layer "In6.Cu")
	)
	(gr_line
		(start 235.000038 -0.999998)
		(end 235.000038 -183.76392)
		(stroke
			(width 1.524)
			(type default)
		)
		(layer "In6.Cu")
	)
	(gr_line
		(start 0 -183.76392)
		(end 0 -0.999998)
		(stroke
			(width 0.05)
			(type default)
		)
		(layer "Edge.Cuts")
	)
	(gr_arc
		(start 0 -183.76392)
		(mid 0.026807 -183.993715)
		(end 0.105664 -184.211214)
		(stroke
			(width 0.05)
			(type default)
		)
		(layer "Edge.Cuts")
	)
	(gr_arc
		(start 0.999998 0)
		(mid 0.292893 -0.292893)
		(end 0 -0.999998)
		(stroke
			(width 0.05)
			(type default)
		)
		(layer "Edge.Cuts")
	)
	(gr_line
		(start 0.999998 0)
		(end 29.53004 0)
		(stroke
			(width 0.05)
			(type default)
		)
		(layer "Edge.Cuts")
	)
	(gr_line
		(start 4.723638 -193.447162)
		(end 0.105664 -184.211214)
		(stroke
			(width 0.05)
			(type default)
		)
		(layer "Edge.Cuts")
	)
	(gr_arc
		(start 4.723638 -193.447162)
		(mid 5.092281 -193.850645)
		(end 5.617972 -194.00012)
		(stroke
			(width 0.05)
			(type default)
		)
		(layer "Edge.Cuts")
	)
	(gr_arc
		(start 10.500106 -187.999878)
		(mid 12.500102 -189.999874)
		(end 14.500098 -187.999878)
		(stroke
			(width 0.05)
			(type default)
		)
		(layer "Edge.Cuts")
	)
	(gr_arc
		(start 14.500098 -187.999878)
		(mid 12.500102 -185.999882)
		(end 10.500106 -187.999878)
		(stroke
			(width 0.05)
			(type default)
		)
		(layer "Edge.Cuts")
	)
	(gr_arc
		(start 16.249904 -120.000014)
		(mid 17.999964 -121.750074)
		(end 19.750024 -120.000014)
		(stroke
			(width 0.05)
			(type default)
		)
		(layer "Edge.Cuts")
	)
	(gr_arc
		(start 16.249904 -24.99995)
		(mid 17.999964 -26.75001)
		(end 19.750024 -24.99995)
		(stroke
			(width 0.05)
			(type default)
		)
		(layer "Edge.Cuts")
	)
	(gr_arc
		(start 19.750024 -120.000014)
		(mid 17.999964 -118.249954)
		(end 16.249904 -120.000014)
		(stroke
			(width 0.05)
			(type default)
		)
		(layer "Edge.Cuts")
	)
	(gr_arc
		(start 19.750024 -24.99995)
		(mid 17.999964 -23.24989)
		(end 16.249904 -24.99995)
		(stroke
			(width 0.05)
			(type default)
		)
		(layer "Edge.Cuts")
	)
	(gr_line
		(start 21.100034 -62.250066)
		(end 24.500078 -62.250066)
		(stroke
			(width 0.05)
			(type default)
		)
		(layer "Edge.Cuts")
	)
	(gr_arc
		(start 21.100034 -58.850022)
		(mid 19.400012 -60.550044)
		(end 21.100034 -62.250066)
		(stroke
			(width 0.05)
			(type default)
		)
		(layer "Edge.Cuts")
	)
	(gr_arc
		(start 21.249894 -105.050082)
		(mid 22.900132 -106.70032)
		(end 24.550116 -105.050082)
		(stroke
			(width 0.05)
			(type default)
		)
		(layer "Edge.Cuts")
	)
	(gr_arc
		(start 24.500078 -62.250066)
		(mid 26.2001 -60.550044)
		(end 24.500078 -58.850022)
		(stroke
			(width 0.05)
			(type default)
		)
		(layer "Edge.Cuts")
	)
	(gr_line
		(start 24.500078 -58.850022)
		(end 21.100034 -58.850022)
		(stroke
			(width 0.05)
			(type default)
		)
		(layer "Edge.Cuts")
	)
	(gr_arc
		(start 24.550116 -105.050082)
		(mid 22.900132 -103.400098)
		(end 21.249894 -105.050082)
		(stroke
			(width 0.05)
			(type default)
		)
		(layer "Edge.Cuts")
	)
	(gr_arc
		(start 30.530038 -109.050074)
		(mid 30.822931 -109.757179)
		(end 31.530036 -110.050072)
		(stroke
			(width 0.05)
			(type default)
		)
		(layer "Edge.Cuts")
	)
	(gr_arc
		(start 30.530038 -0.999998)
		(mid 30.237147 -0.29288)
		(end 29.53004 0)
		(stroke
			(width 0.05)
			(type default)
		)
		(layer "Edge.Cuts")
	)
	(gr_line
		(start 30.530038 -0.999998)
		(end 30.530038 -109.050074)
		(stroke
			(width 0.05)
			(type default)
		)
		(layer "Edge.Cuts")
	)
	(gr_line
		(start 31.530036 -110.050072)
		(end 72.030082 -110.050072)
		(stroke
			(width 0.05)
			(type default)
		)
		(layer "Edge.Cuts")
	)
	(gr_arc
		(start 39.349934 -169.999914)
		(mid 41.450006 -172.099986)
		(end 43.550078 -169.999914)
		(stroke
			(width 0.05)
			(type default)
		)
		(layer "Edge.Cuts")
	)
	(gr_arc
		(start 43.550078 -169.999914)
		(mid 41.450006 -167.899842)
		(end 39.349934 -169.999914)
		(stroke
			(width 0.05)
			(type default)
		)
		(layer "Edge.Cuts")
	)
	(gr_arc
		(start 72.030082 -110.050072)
		(mid 72.737187 -109.757179)
		(end 73.03008 -109.050074)
		(stroke
			(width 0.05)
			(type default)
		)
		(layer "Edge.Cuts")
	)
	(gr_line
		(start 73.03008 -109.050074)
		(end 73.03008 -0.999998)
		(stroke
			(width 0.05)
			(type default)
		)
		(layer "Edge.Cuts")
	)
	(gr_arc
		(start 74.030078 0)
		(mid 73.322986 -0.2929)
		(end 73.03008 -0.999998)
		(stroke
			(width 0.05)
			(type default)
		)
		(layer "Edge.Cuts")
	)
	(gr_line
		(start 74.030078 0)
		(end 234.00004 0)
		(stroke
			(width 0.05)
			(type default)
		)
		(layer "Edge.Cuts")
	)
	(gr_line
		(start 76.849986 -106.750104)
		(end 80.25003 -106.750104)
		(stroke
			(width 0.05)
			(type default)
		)
		(layer "Edge.Cuts")
	)
	(gr_arc
		(start 76.849986 -103.35006)
		(mid 75.149964 -105.050082)
		(end 76.849986 -106.750104)
		(stroke
			(width 0.05)
			(type default)
		)
		(layer "Edge.Cuts")
	)
	(gr_arc
		(start 76.849986 -40.049958)
		(mid 78.49997 -41.699942)
		(end 80.149954 -40.049958)
		(stroke
			(width 0.05)
			(type default)
		)
		(layer "Edge.Cuts")
	)
	(gr_arc
		(start 78.250034 -120.000014)
		(mid 80.000094 -121.750074)
		(end 81.7499 -120.000014)
		(stroke
			(width 0.05)
			(type default)
		)
		(layer "Edge.Cuts")
	)
	(gr_arc
		(start 80.149954 -40.049958)
		(mid 78.49997 -38.399974)
		(end 76.849986 -40.049958)
		(stroke
			(width 0.05)
			(type default)
		)
		(layer "Edge.Cuts")
	)
	(gr_arc
		(start 80.25003 -106.750104)
		(mid 81.950052 -105.050082)
		(end 80.25003 -103.35006)
		(stroke
			(width 0.05)
			(type default)
		)
		(layer "Edge.Cuts")
	)
	(gr_line
		(start 80.25003 -103.35006)
		(end 76.849986 -103.35006)
		(stroke
			(width 0.05)
			(type default)
		)
		(layer "Edge.Cuts")
	)
	(gr_arc
		(start 81.7499 -120.000014)
		(mid 80.000094 -118.250208)
		(end 78.250034 -120.000014)
		(stroke
			(width 0.05)
			(type default)
		)
		(layer "Edge.Cuts")
	)
	(gr_arc
		(start 90.749882 -187.999878)
		(mid 92.499942 -189.749938)
		(end 94.250002 -187.999878)
		(stroke
			(width 0.05)
			(type default)
		)
		(layer "Edge.Cuts")
	)
	(gr_arc
		(start 94.250002 -187.999878)
		(mid 92.499942 -186.249818)
		(end 90.749882 -187.999878)
		(stroke
			(width 0.05)
			(type default)
		)
		(layer "Edge.Cuts")
	)
	(gr_line
		(start 98.081846 -194.00012)
		(end 5.617972 -194.00012)
		(stroke
			(width 0.05)
			(type default)
		)
		(layer "Edge.Cuts")
	)
	(gr_arc
		(start 98.081846 -194.00012)
		(mid 98.607706 -193.850755)
		(end 98.976434 -193.447162)
		(stroke
			(width 0.05)
			(type default)
		)
		(layer "Edge.Cuts")
	)
	(gr_arc
		(start 101.249988 -9.99998)
		(mid 103.000048 -11.75004)
		(end 104.750108 -9.99998)
		(stroke
			(width 0.05)
			(type default)
		)
		(layer "Edge.Cuts")
	)
	(gr_line
		(start 103.594408 -184.211214)
		(end 98.976434 -193.447162)
		(stroke
			(width 0.05)
			(type default)
		)
		(layer "Edge.Cuts")
	)
	(gr_arc
		(start 103.594408 -184.211214)
		(mid 103.673311 -183.993725)
		(end 103.700072 -183.76392)
		(stroke
			(width 0.05)
			(type default)
		)
		(layer "Edge.Cuts")
	)
	(gr_line
		(start 103.700072 -47.999904)
		(end 103.700072 -183.76392)
		(stroke
			(width 0.05)
			(type default)
		)
		(layer "Edge.Cuts")
	)
	(gr_arc
		(start 104.70007 -47.999904)
		(mid 104.200198 -47.500032)
		(end 103.700072 -47.999904)
		(stroke
			(width 0.05)
			(type default)
		)
		(layer "Edge.Cuts")
	)
	(gr_arc
		(start 104.750108 -9.99998)
		(mid 103.000048 -8.24992)
		(end 101.249988 -9.99998)
		(stroke
			(width 0.05)
			(type default)
		)
		(layer "Edge.Cuts")
	)
	(gr_arc
		(start 122.884946 -34.85007)
		(mid 124.160026 -36.12515)
		(end 125.435106 -34.85007)
		(stroke
			(width 0.05)
			(type default)
		)
		(layer "Edge.Cuts")
	)
	(gr_arc
		(start 122.95505 -41.839896)
		(mid 124.160026 -43.044872)
		(end 125.365002 -41.839896)
		(stroke
			(width 0.05)
			(type default)
		)
		(layer "Edge.Cuts")
	)
	(gr_arc
		(start 125.365002 -41.839896)
		(mid 124.160026 -40.63492)
		(end 122.95505 -41.839896)
		(stroke
			(width 0.05)
			(type default)
		)
		(layer "Edge.Cuts")
	)
	(gr_arc
		(start 125.435106 -34.85007)
		(mid 124.160026 -33.57499)
		(end 122.884946 -34.85007)
		(stroke
			(width 0.05)
			(type default)
		)
		(layer "Edge.Cuts")
	)
	(gr_line
		(start 143.299942 -47.999904)
		(end 104.70007 -47.999904)
		(stroke
			(width 0.05)
			(type default)
		)
		(layer "Edge.Cuts")
	)
	(gr_line
		(start 144.29994 -149.763988)
		(end 144.29994 -47.999904)
		(stroke
			(width 0.05)
			(type default)
		)
		(layer "Edge.Cuts")
	)
	(gr_arc
		(start 144.29994 -149.763988)
		(mid 144.326787 -149.993649)
		(end 144.405604 -150.211028)
		(stroke
			(width 0.05)
			(type default)
		)
		(layer "Edge.Cuts")
	)
	(gr_arc
		(start 144.29994 -47.999904)
		(mid 143.800068 -47.500032)
		(end 143.299942 -47.999904)
		(stroke
			(width 0.05)
			(type default)
		)
		(layer "Edge.Cuts")
	)
	(gr_arc
		(start 147.550124 -78.000098)
		(mid 149.300184 -79.750158)
		(end 151.04999 -78.000098)
		(stroke
			(width 0.05)
			(type default)
		)
		(layer "Edge.Cuts")
	)
	(gr_arc
		(start 148.249894 -120.000014)
		(mid 149.999954 -121.750074)
		(end 151.750014 -120.000014)
		(stroke
			(width 0.05)
			(type default)
		)
		(layer "Edge.Cuts")
	)
	(gr_line
		(start 149.023578 -159.44723)
		(end 144.405604 -150.211028)
		(stroke
			(width 0.05)
			(type default)
		)
		(layer "Edge.Cuts")
	)
	(gr_arc
		(start 149.023578 -159.44723)
		(mid 149.392231 -159.850635)
		(end 149.917912 -159.999934)
		(stroke
			(width 0.05)
			(type default)
		)
		(layer "Edge.Cuts")
	)
	(gr_arc
		(start 151.04999 -78.000098)
		(mid 149.300184 -76.250292)
		(end 147.550124 -78.000098)
		(stroke
			(width 0.05)
			(type default)
		)
		(layer "Edge.Cuts")
	)
	(gr_arc
		(start 151.750014 -120.000014)
		(mid 149.999954 -118.249954)
		(end 148.249894 -120.000014)
		(stroke
			(width 0.05)
			(type default)
		)
		(layer "Edge.Cuts")
	)
	(gr_arc
		(start 153.75001 -153.999946)
		(mid 155.50007 -155.750006)
		(end 157.249876 -153.999946)
		(stroke
			(width 0.05)
			(type default)
		)
		(layer "Edge.Cuts")
	)
	(gr_arc
		(start 157.249876 -153.999946)
		(mid 155.50007 -152.25014)
		(end 153.75001 -153.999946)
		(stroke
			(width 0.05)
			(type default)
		)
		(layer "Edge.Cuts")
	)
	(gr_arc
		(start 177.8 -52.049934)
		(mid 179.399946 -53.64988)
		(end 180.999892 -52.049934)
		(stroke
			(width 0.05)
			(type default)
		)
		(layer "Edge.Cuts")
	)
	(gr_line
		(start 177.8 -50.449988)
		(end 177.8 -52.049934)
		(stroke
			(width 0.05)
			(type default)
		)
		(layer "Edge.Cuts")
	)
	(gr_arc
		(start 177.8 -22.049994)
		(mid 179.399946 -23.64994)
		(end 180.999892 -22.049994)
		(stroke
			(width 0.05)
			(type default)
		)
		(layer "Edge.Cuts")
	)
	(gr_line
		(start 177.8 -20.450048)
		(end 177.8 -22.049994)
		(stroke
			(width 0.05)
			(type default)
		)
		(layer "Edge.Cuts")
	)
	(gr_line
		(start 180.999892 -52.049934)
		(end 180.999892 -50.449988)
		(stroke
			(width 0.05)
			(type default)
		)
		(layer "Edge.Cuts")
	)
	(gr_arc
		(start 180.999892 -50.449988)
		(mid 179.399946 -48.850042)
		(end 177.8 -50.449988)
		(stroke
			(width 0.05)
			(type default)
		)
		(layer "Edge.Cuts")
	)
	(gr_line
		(start 180.999892 -22.049994)
		(end 180.999892 -20.450048)
		(stroke
			(width 0.05)
			(type default)
		)
		(layer "Edge.Cuts")
	)
	(gr_arc
		(start 180.999892 -20.450048)
		(mid 179.399946 -18.850102)
		(end 177.8 -20.450048)
		(stroke
			(width 0.05)
			(type default)
		)
		(layer "Edge.Cuts")
	)
	(gr_arc
		(start 202.79995 -52.049934)
		(mid 204.40015 -53.650134)
		(end 206.000096 -52.049934)
		(stroke
			(width 0.05)
			(type default)
		)
		(layer "Edge.Cuts")
	)
	(gr_line
		(start 202.79995 -50.449988)
		(end 202.79995 -52.049934)
		(stroke
			(width 0.05)
			(type default)
		)
		(layer "Edge.Cuts")
	)
	(gr_arc
		(start 202.79995 -22.049994)
		(mid 204.40015 -23.650194)
		(end 206.000096 -22.049994)
		(stroke
			(width 0.05)
			(type default)
		)
		(layer "Edge.Cuts")
	)
	(gr_line
		(start 202.79995 -20.450048)
		(end 202.79995 -22.049994)
		(stroke
			(width 0.05)
			(type default)
		)
		(layer "Edge.Cuts")
	)
	(gr_line
		(start 206.000096 -52.049934)
		(end 206.000096 -50.449988)
		(stroke
			(width 0.05)
			(type default)
		)
		(layer "Edge.Cuts")
	)
	(gr_arc
		(start 206.000096 -50.449988)
		(mid 204.40015 -48.850042)
		(end 202.79995 -50.449988)
		(stroke
			(width 0.05)
			(type default)
		)
		(layer "Edge.Cuts")
	)
	(gr_line
		(start 206.000096 -22.049994)
		(end 206.000096 -20.450048)
		(stroke
			(width 0.05)
			(type default)
		)
		(layer "Edge.Cuts")
	)
	(gr_arc
		(start 206.000096 -20.450048)
		(mid 204.40015 -18.850102)
		(end 202.79995 -20.450048)
		(stroke
			(width 0.05)
			(type default)
		)
		(layer "Edge.Cuts")
	)
	(gr_line
		(start 214.00008 -159.999934)
		(end 149.917912 -159.999934)
		(stroke
			(width 0.05)
			(type default)
		)
		(layer "Edge.Cuts")
	)
	(gr_line
		(start 215.000078 -193.000122)
		(end 215.000078 -160.999932)
		(stroke
			(width 0.05)
			(type default)
		)
		(layer "Edge.Cuts")
	)
	(gr_arc
		(start 215.000078 -193.000122)
		(mid 215.292977 -193.707222)
		(end 216.000076 -194.00012)
		(stroke
			(width 0.05)
			(type default)
		)
		(layer "Edge.Cuts")
	)
	(gr_arc
		(start 215.000078 -160.999932)
		(mid 214.707185 -160.292827)
		(end 214.00008 -159.999934)
		(stroke
			(width 0.05)
			(type default)
		)
		(layer "Edge.Cuts")
	)
	(gr_arc
		(start 220.49994 -7.999984)
		(mid 222.499936 -9.99998)
		(end 224.499932 -7.999984)
		(stroke
			(width 0.05)
			(type default)
		)
		(layer "Edge.Cuts")
	)
	(gr_arc
		(start 220.749876 -187.999878)
		(mid 222.499936 -189.749938)
		(end 224.249996 -187.999878)
		(stroke
			(width 0.05)
			(type default)
		)
		(layer "Edge.Cuts")
	)
	(gr_arc
		(start 220.749876 -153.999946)
		(mid 222.499936 -155.750006)
		(end 224.249996 -153.999946)
		(stroke
			(width 0.05)
			(type default)
		)
		(layer "Edge.Cuts")
	)
	(gr_arc
		(start 220.749876 -120.000014)
		(mid 222.499936 -121.750074)
		(end 224.249996 -120.000014)
		(stroke
			(width 0.05)
			(type default)
		)
		(layer "Edge.Cuts")
	)
	(gr_arc
		(start 224.249996 -187.999878)
		(mid 222.499936 -186.249818)
		(end 220.749876 -187.999878)
		(stroke
			(width 0.05)
			(type default)
		)
		(layer "Edge.Cuts")
	)
	(gr_arc
		(start 224.249996 -153.999946)
		(mid 222.499936 -152.249886)
		(end 220.749876 -153.999946)
		(stroke
			(width 0.05)
			(type default)
		)
		(layer "Edge.Cuts")
	)
	(gr_arc
		(start 224.249996 -120.000014)
		(mid 222.499936 -118.249954)
		(end 220.749876 -120.000014)
		(stroke
			(width 0.05)
			(type default)
		)
		(layer "Edge.Cuts")
	)
	(gr_arc
		(start 224.499932 -7.999984)
		(mid 222.499936 -5.999988)
		(end 220.49994 -7.999984)
		(stroke
			(width 0.05)
			(type default)
		)
		(layer "Edge.Cuts")
	)
	(gr_line
		(start 229.382066 -194.00012)
		(end 216.000076 -194.00012)
		(stroke
			(width 0.05)
			(type default)
		)
		(layer "Edge.Cuts")
	)
	(gr_arc
		(start 229.382066 -194.00012)
		(mid 229.907793 -193.850701)
		(end 230.2764 -193.447162)
		(stroke
			(width 0.05)
			(type default)
		)
		(layer "Edge.Cuts")
	)
	(gr_line
		(start 234.894374 -184.211214)
		(end 230.2764 -193.447162)
		(stroke
			(width 0.05)
			(type default)
		)
		(layer "Edge.Cuts")
	)
	(gr_arc
		(start 234.894374 -184.211214)
		(mid 234.97328 -183.993726)
		(end 235.000038 -183.76392)
		(stroke
			(width 0.05)
			(type default)
		)
		(layer "Edge.Cuts")
	)
	(gr_arc
		(start 235.000038 -0.999998)
		(mid 234.707147 -0.29288)
		(end 234.00004 0)
		(stroke
			(width 0.05)
			(type default)
		)
		(layer "Edge.Cuts")
	)
	(gr_line
		(start 235.000038 -0.999998)
		(end 235.000038 -183.76392)
		(stroke
			(width 0.05)
			(type default)
		)
		(layer "Edge.Cuts")
	)
	(segment
		(start 193.657982 -5.569712)
		(end 185.784998 -5.569712)
		(width 0.127)
		(layer "F.Cu")
		(net "BMC_ML_PWR_BLUE_LED_L")
	)
	(segment
		(start 196.2404 -6.64464)
		(end 196.10324 -6.7818)
		(width 0.127)
		(layer "F.Cu")
		(net "BMC_ML_PWR_BLUE_LED_L")
	)
	(segment
		(start 194.87007 -6.7818)
		(end 193.657982 -5.569712)
		(width 0.127)
		(layer "F.Cu")
		(net "BMC_ML_PWR_BLUE_LED_L")
	)
	(segment
		(start 196.10324 -6.7818)
		(end 194.87007 -6.7818)
		(width 0.127)
		(layer "F.Cu")
		(net "BMC_ML_PWR_BLUE_LED_L")
	)
	(segment
		(start 185.784998 -5.569712)
		(end 184.739788 -5.569712)
		(width 0.127)
		(layer "F.Cu")
		(net "BMC_ML_PWR_BLUE_LED_L")
	)
	(segment
		(start 182.3847 -6.8326)
		(end 183.4769 -6.8326)
		(width 0.127)
		(layer "F.Cu")
		(net "BMC_ML_PWR_BLUE_LED_L")
	)
	(segment
		(start 184.739788 -5.569712)
		(end 183.8452 -6.4643)
		(width 0.127)
		(layer "F.Cu")
		(net "BMC_ML_PWR_BLUE_LED_L")
	)
	(segment
		(start 196.2404 -5.96011)
		(end 196.2404 -6.64464)
		(width 0.127)
		(layer "F.Cu")
		(net "BMC_ML_PWR_BLUE_LED_L")
	)
	(segment
		(start 183.4769 -6.8326)
		(end 183.8452 -6.4643)
		(width 0.127)
		(layer "F.Cu")
		(net "BMC_ML_PWR_BLUE_LED_L")
	)
	(via
		(at 185.784998 -5.569712)
		(size 0.6604)
		(drill 0.3302)
		(layers "F.Cu" "B.Cu")
		(net "BMC_ML_PWR_BLUE_LED_L")
	)
	(segment
		(start 44.2976 -131.1021)
		(end 44.2976 -131.897882)
		(width 0.127)
		(layer "F.Cu")
		(net "PLTRST_R")
	)
	(segment
		(start 40.099996 -137.40003)
		(end 39.7002 -137.000234)
		(width 0.127)
		(layer "F.Cu")
		(net "PLTRST_R")
	)
	(via
		(at 44.2976 -131.897882)
		(size 0.508)
		(drill 0.254)
		(layers "F.Cu" "B.Cu")
		(net "PLTRST_R")
	)
	(via
		(at 39.7002 -137.000234)
		(size 0.4572)
		(drill 0.2032)
		(layers "F.Cu" "B.Cu")
		(net "PLTRST_R")
	)
	(segment
		(start 41.94937 -139.806172)
		(end 41.706546 -139.563348)
		(width 0.127)
		(layer "In2.Cu")
		(net "PLTRST_R")
	)
	(segment
		(start 44.5008 -137.9728)
		(end 44.893738 -138.365738)
		(width 0.127)
		(layer "In2.Cu")
		(net "PLTRST_R")
	)
	(segment
		(start 43.81881 -133.60781)
		(end 44.5008 -134.2898)
		(width 0.127)
		(layer "In2.Cu")
		(net "PLTRST_R")
	)
	(segment
		(start 42.506392 -140.363448)
		(end 42.506392 -140.04925)
		(width 0.127)
		(layer "In2.Cu")
		(net "PLTRST_R")
	)
	(segment
		(start 42.263314 -139.806172)
		(end 41.94937 -139.806172)
		(width 0.127)
		(layer "In2.Cu")
		(net "PLTRST_R")
	)
	(segment
		(start 39.7002 -137.243566)
		(end 39.7002 -137.000234)
		(width 0.127)
		(layer "In2.Cu")
		(net "PLTRST_R")
	)
	(segment
		(start 44.893738 -140.363702)
		(end 44.66336 -140.59408)
		(width 0.127)
		(layer "In2.Cu")
		(net "PLTRST_R")
	)
	(segment
		(start 41.136824 -138.993626)
		(end 40.906446 -138.763248)
		(width 0.127)
		(layer "In2.Cu")
		(net "PLTRST_R")
	)
	(segment
		(start 44.2976 -131.897882)
		(end 43.81881 -132.376672)
		(width 0.127)
		(layer "In2.Cu")
		(net "PLTRST_R")
	)
	(segment
		(start 41.706546 -139.236704)
		(end 41.463468 -138.993626)
		(width 0.127)
		(layer "In2.Cu")
		(net "PLTRST_R")
	)
	(segment
		(start 44.893738 -138.365738)
		(end 44.893738 -140.363702)
		(width 0.127)
		(layer "In2.Cu")
		(net "PLTRST_R")
	)
	(segment
		(start 40.106346 -137.649712)
		(end 39.7002 -137.243566)
		(width 0.127)
		(layer "In2.Cu")
		(net "PLTRST_R")
	)
	(segment
		(start 40.906446 -138.763248)
		(end 40.906446 -138.449812)
		(width 0.127)
		(layer "In2.Cu")
		(net "PLTRST_R")
	)
	(segment
		(start 40.106346 -137.963656)
		(end 40.106346 -137.649712)
		(width 0.127)
		(layer "In2.Cu")
		(net "PLTRST_R")
	)
	(segment
		(start 40.663368 -138.206734)
		(end 40.349424 -138.206734)
		(width 0.127)
		(layer "In2.Cu")
		(net "PLTRST_R")
	)
	(segment
		(start 41.463468 -138.993626)
		(end 41.136824 -138.993626)
		(width 0.127)
		(layer "In2.Cu")
		(net "PLTRST_R")
	)
	(segment
		(start 44.5008 -134.2898)
		(end 44.5008 -137.9728)
		(width 0.127)
		(layer "In2.Cu")
		(net "PLTRST_R")
	)
	(segment
		(start 42.737024 -140.59408)
		(end 42.506392 -140.363448)
		(width 0.127)
		(layer "In2.Cu")
		(net "PLTRST_R")
	)
	(segment
		(start 43.81881 -132.376672)
		(end 43.81881 -133.60781)
		(width 0.127)
		(layer "In2.Cu")
		(net "PLTRST_R")
	)
	(segment
		(start 42.506392 -140.04925)
		(end 42.263314 -139.806172)
		(width 0.127)
		(layer "In2.Cu")
		(net "PLTRST_R")
	)
	(segment
		(start 40.906446 -138.449812)
		(end 40.663368 -138.206734)
		(width 0.127)
		(layer "In2.Cu")
		(net "PLTRST_R")
	)
	(segment
		(start 41.706546 -139.563348)
		(end 41.706546 -139.236704)
		(width 0.127)
		(layer "In2.Cu")
		(net "PLTRST_R")
	)
	(segment
		(start 40.349424 -138.206734)
		(end 40.106346 -137.963656)
		(width 0.127)
		(layer "In2.Cu")
		(net "PLTRST_R")
	)
	(segment
		(start 44.66336 -140.59408)
		(end 42.737024 -140.59408)
		(width 0.127)
		(layer "In2.Cu")
		(net "PLTRST_R")
	)
	(segment
		(start 207.36941 -5.0292)
		(end 202.438 -5.0292)
		(width 0.254)
		(layer "F.Cu")
		(net "ML_PWR_YELLOW_LED_R")
	)
	(segment
		(start 202.438 -5.0292)
		(end 201.1172 -6.35)
		(width 0.254)
		(layer "F.Cu")
		(net "ML_PWR_YELLOW_LED_R")
	)
	(segment
		(start 208.540096 -6.199886)
		(end 207.36941 -5.0292)
		(width 0.254)
		(layer "F.Cu")
		(net "ML_PWR_YELLOW_LED_R")
	)
	(segment
		(start 201.1172 -6.35)
		(end 199.9234 -6.35)
		(width 0.254)
		(layer "F.Cu")
		(net "ML_PWR_YELLOW_LED_R")
	)
	(segment
		(start 196.89064 -5.1562)
		(end 196.89064 -5.96011)
		(width 0.254)
		(layer "F.Cu")
		(net "ML_PWR_YELLOW_LED")
	)
	(segment
		(start 198.3994 -4.9276)
		(end 197.11924 -4.9276)
		(width 0.254)
		(layer "F.Cu")
		(net "ML_PWR_YELLOW_LED")
	)
	(segment
		(start 198.3994 -6.35)
		(end 198.3994 -4.9276)
		(width 0.254)
		(layer "F.Cu")
		(net "ML_PWR_YELLOW_LED")
	)
	(segment
		(start 197.11924 -4.9276)
		(end 196.89064 -5.1562)
		(width 0.254)
		(layer "F.Cu")
		(net "ML_PWR_YELLOW_LED")
	)
	(via
		(at 198.3994 -4.9276)
		(size 0.6604)
		(drill 0.3302)
		(layers "F.Cu" "B.Cu")
		(net "ML_PWR_YELLOW_LED")
	)
	(segment
		(start 199.9488 -7.5692)
		(end 202.090782 -7.5692)
		(width 0.254)
		(layer "F.Cu")
		(net "ML_PWR_BLUE_LED_R")
	)
	(segment
		(start 202.090782 -7.5692)
		(end 203.460096 -6.199886)
		(width 0.254)
		(layer "F.Cu")
		(net "ML_PWR_BLUE_LED_R")
	)
	(segment
		(start 198.4248 -7.5692)
		(end 198.4248 -8.8392)
		(width 0.254)
		(layer "F.Cu")
		(net "ML_PWR_BLUE_LED")
	)
	(segment
		(start 196.6468 -9.4488)
		(end 196.1134 -9.4488)
		(width 0.254)
		(layer "F.Cu")
		(net "ML_PWR_BLUE_LED")
	)
	(segment
		(start 198.4248 -8.8392)
		(end 197.8152 -9.4488)
		(width 0.254)
		(layer "F.Cu")
		(net "ML_PWR_BLUE_LED")
	)
	(segment
		(start 197.8152 -9.4488)
		(end 196.6468 -9.4488)
		(width 0.254)
		(layer "F.Cu")
		(net "ML_PWR_BLUE_LED")
	)
	(segment
		(start 195.59016 -8.92556)
		(end 195.59016 -8.00989)
		(width 0.254)
		(layer "F.Cu")
		(net "ML_PWR_BLUE_LED")
	)
	(segment
		(start 196.1134 -9.4488)
		(end 195.59016 -8.92556)
		(width 0.254)
		(layer "F.Cu")
		(net "ML_PWR_BLUE_LED")
	)
	(via
		(at 196.6468 -9.4488)
		(size 0.6604)
		(drill 0.3302)
		(layers "F.Cu" "B.Cu")
		(net "ML_PWR_BLUE_LED")
	)
	(segment
		(start 50.499772 -137.40003)
		(end 50.099976 -137.799826)
		(width 0.127)
		(layer "F.Cu")
		(net "M2_2_ALERT#_R")
	)
	(segment
		(start 50.500026 -137.40003)
		(end 50.499772 -137.40003)
		(width 0.127)
		(layer "F.Cu")
		(net "M2_2_ALERT#_R")
	)
	(via
		(at 50.099976 -137.799826)
		(size 0.4572)
		(drill 0.2032)
		(layers "F.Cu" "B.Cu")
		(net "M2_2_ALERT#_R")
	)
	(via
		(at 49.0728 -126.238)
		(size 0.508)
		(drill 0.254)
		(layers "F.Cu" "B.Cu")
		(net "M2_2_ALERT#_R")
	)
	(via
		(at 50.253138 -125.581918)
		(size 0.6096)
		(drill 0.3048)
		(layers "F.Cu" "B.Cu")
		(net "M2_2_ALERT#_R")
	)
	(segment
		(start 49.0728 -126.238)
		(end 49.3649 -125.9459)
		(width 0.127)
		(layer "B.Cu")
		(net "M2_2_ALERT#_R")
	)
	(segment
		(start 49.889156 -125.9459)
		(end 50.253138 -125.581918)
		(width 0.127)
		(layer "B.Cu")
		(net "M2_2_ALERT#_R")
	)
	(segment
		(start 49.3649 -125.9459)
		(end 49.889156 -125.9459)
		(width 0.127)
		(layer "B.Cu")
		(net "M2_2_ALERT#_R")
	)
	(segment
		(start 50.253138 -125.581918)
		(end 50.253138 -124.611638)
		(width 0.127)
		(layer "B.Cu")
		(net "M2_2_ALERT#_R")
	)
	(segment
		(start 50.253138 -124.611638)
		(end 49.9745 -124.333)
		(width 0.127)
		(layer "B.Cu")
		(net "M2_2_ALERT#_R")
	)
	(segment
		(start 49.0728 -126.238)
		(end 49.0728 -129.07899)
		(width 0.127)
		(layer "In2.Cu")
		(net "M2_2_ALERT#_R")
	)
	(segment
		(start 49.0728 -129.49301)
		(end 49.0728 -131.5212)
		(width 0.127)
		(layer "In2.Cu")
		(net "M2_2_ALERT#_R")
	)
	(segment
		(start 49.0728 -131.5212)
		(end 49.7078 -132.1562)
		(width 0.127)
		(layer "In2.Cu")
		(net "M2_2_ALERT#_R")
	)
	(segment
		(start 49.084992 -129.480818)
		(end 49.0728 -129.49301)
		(width 0.127)
		(layer "In2.Cu")
		(net "M2_2_ALERT#_R")
	)
	(segment
		(start 50.546 -135.8646)
		(end 50.546 -137.353802)
		(width 0.127)
		(layer "In2.Cu")
		(net "M2_2_ALERT#_R")
	)
	(segment
		(start 50.546 -137.353802)
		(end 50.099976 -137.799826)
		(width 0.127)
		(layer "In2.Cu")
		(net "M2_2_ALERT#_R")
	)
	(segment
		(start 49.7078 -132.1562)
		(end 49.7078 -135.0264)
		(width 0.127)
		(layer "In2.Cu")
		(net "M2_2_ALERT#_R")
	)
	(segment
		(start 49.084992 -129.091182)
		(end 49.084992 -129.480818)
		(width 0.127)
		(layer "In2.Cu")
		(net "M2_2_ALERT#_R")
	)
	(segment
		(start 49.7078 -135.0264)
		(end 50.546 -135.8646)
		(width 0.127)
		(layer "In2.Cu")
		(net "M2_2_ALERT#_R")
	)
	(segment
		(start 49.0728 -129.07899)
		(end 49.084992 -129.091182)
		(width 0.127)
		(layer "In2.Cu")
		(net "M2_2_ALERT#_R")
	)
	(segment
		(start 49.699926 -138.199876)
		(end 50.099976 -138.599926)
		(width 0.127)
		(layer "F.Cu")
		(net "M2_1_ALERT#_R")
	)
	(via
		(at 49.9872 -126.456948)
		(size 0.508)
		(drill 0.254)
		(layers "F.Cu" "B.Cu")
		(net "M2_1_ALERT#_R")
	)
	(via
		(at 51.652424 -125.853698)
		(size 0.6096)
		(drill 0.3048)
		(layers "F.Cu" "B.Cu")
		(net "M2_1_ALERT#_R")
	)
	(via
		(at 50.099976 -138.599926)
		(size 0.4572)
		(drill 0.2032)
		(layers "F.Cu" "B.Cu")
		(net "M2_1_ALERT#_R")
	)
	(segment
		(start 51.652424 -125.853698)
		(end 50.879502 -125.853698)
		(width 0.127)
		(layer "B.Cu")
		(net "M2_1_ALERT#_R")
	)
	(segment
		(start 51.652424 -125.853698)
		(end 52.0192 -125.486922)
		(width 0.127)
		(layer "B.Cu")
		(net "M2_1_ALERT#_R")
	)
	(segment
		(start 52.0192 -125.486922)
		(end 52.0192 -124.5997)
		(width 0.127)
		(layer "B.Cu")
		(net "M2_1_ALERT#_R")
	)
	(segment
		(start 50.276252 -126.456948)
		(end 49.9872 -126.456948)
		(width 0.127)
		(layer "B.Cu")
		(net "M2_1_ALERT#_R")
	)
	(segment
		(start 50.879502 -125.853698)
		(end 50.276252 -126.456948)
		(width 0.127)
		(layer "B.Cu")
		(net "M2_1_ALERT#_R")
	)
	(segment
		(start 50.099976 -138.495024)
		(end 50.9016 -137.6934)
		(width 0.127)
		(layer "In2.Cu")
		(net "M2_1_ALERT#_R")
	)
	(segment
		(start 50.9016 -135.6106)
		(end 50.2666 -134.9756)
		(width 0.127)
		(layer "In2.Cu")
		(net "M2_1_ALERT#_R")
	)
	(segment
		(start 49.8094 -126.634748)
		(end 49.9872 -126.456948)
		(width 0.127)
		(layer "In2.Cu")
		(net "M2_1_ALERT#_R")
	)
	(segment
		(start 50.099976 -138.599926)
		(end 50.099976 -138.495024)
		(width 0.127)
		(layer "In2.Cu")
		(net "M2_1_ALERT#_R")
	)
	(segment
		(start 50.9397 -130.234182)
		(end 50.664618 -129.9591)
		(width 0.127)
		(layer "In2.Cu")
		(net "M2_1_ALERT#_R")
	)
	(segment
		(start 50.4063 -129.9591)
		(end 49.8094 -129.3622)
		(width 0.127)
		(layer "In2.Cu")
		(net "M2_1_ALERT#_R")
	)
	(segment
		(start 50.664618 -129.9591)
		(end 50.4063 -129.9591)
		(width 0.127)
		(layer "In2.Cu")
		(net "M2_1_ALERT#_R")
	)
	(segment
		(start 50.2666 -134.9756)
		(end 50.2666 -132.334)
		(width 0.127)
		(layer "In2.Cu")
		(net "M2_1_ALERT#_R")
	)
	(segment
		(start 50.9397 -131.6609)
		(end 50.9397 -130.234182)
		(width 0.127)
		(layer "In2.Cu")
		(net "M2_1_ALERT#_R")
	)
	(segment
		(start 50.9016 -137.6934)
		(end 50.9016 -135.6106)
		(width 0.127)
		(layer "In2.Cu")
		(net "M2_1_ALERT#_R")
	)
	(segment
		(start 49.8094 -129.3622)
		(end 49.8094 -126.634748)
		(width 0.127)
		(layer "In2.Cu")
		(net "M2_1_ALERT#_R")
	)
	(segment
		(start 50.2666 -132.334)
		(end 50.9397 -131.6609)
		(width 0.127)
		(layer "In2.Cu")
		(net "M2_1_ALERT#_R")
	)
	(segment
		(start 185.3946 -6.8326)
		(end 186.011312 -6.8326)
		(width 0.127)
		(layer "F.Cu")
		(net "BMC_ML_PWR_YELLOW_LED_R")
	)
	(segment
		(start 196.2404 -7.366)
		(end 196.2404 -8.00989)
		(width 0.127)
		(layer "F.Cu")
		(net "BMC_ML_PWR_YELLOW_LED_R")
	)
	(segment
		(start 186.8932 -5.950712)
		(end 193.499994 -5.950712)
		(width 0.127)
		(layer "F.Cu")
		(net "BMC_ML_PWR_YELLOW_LED_R")
	)
	(segment
		(start 196.0626 -7.1882)
		(end 196.2404 -7.366)
		(width 0.127)
		(layer "F.Cu")
		(net "BMC_ML_PWR_YELLOW_LED_R")
	)
	(segment
		(start 193.499994 -5.950712)
		(end 194.737482 -7.1882)
		(width 0.127)
		(layer "F.Cu")
		(net "BMC_ML_PWR_YELLOW_LED_R")
	)
	(segment
		(start 194.737482 -7.1882)
		(end 196.0626 -7.1882)
		(width 0.127)
		(layer "F.Cu")
		(net "BMC_ML_PWR_YELLOW_LED_R")
	)
	(segment
		(start 186.011312 -6.8326)
		(end 186.8932 -5.950712)
		(width 0.127)
		(layer "F.Cu")
		(net "BMC_ML_PWR_YELLOW_LED_R")
	)
	(segment
		(start 184.5437 -6.8326)
		(end 183.8452 -7.5311)
		(width 0.127)
		(layer "F.Cu")
		(net "BMC_ML_PWR_YELLOW_LED_R")
	)
	(segment
		(start 185.3946 -6.8326)
		(end 184.5437 -6.8326)
		(width 0.127)
		(layer "F.Cu")
		(net "BMC_ML_PWR_YELLOW_LED_R")
	)
	(via
		(at 185.3946 -6.8326)
		(size 0.6604)
		(drill 0.3302)
		(layers "F.Cu" "B.Cu")
		(net "BMC_ML_PWR_YELLOW_LED_R")
	)
	(segment
		(start 97.2312 -89.7382)
		(end 98.2091 -90.7161)
		(width 0.127)
		(layer "F.Cu")
		(net "BMC_ML_PWR_YELLOW_LED")
	)
	(segment
		(start 94.040706 -112.806988)
		(end 90.920824 -112.806988)
		(width 0.127)
		(layer "F.Cu")
		(net "BMC_ML_PWR_YELLOW_LED")
	)
	(segment
		(start 95.631 -82.423)
		(end 95.8342 -82.6262)
		(width 0.127)
		(layer "F.Cu")
		(net "BMC_ML_PWR_YELLOW_LED")
	)
	(segment
		(start 96.646746 -25.374854)
		(end 96.646746 -62.331854)
		(width 0.127)
		(layer "F.Cu")
		(net "BMC_ML_PWR_YELLOW_LED")
	)
	(segment
		(start 177.11547 -7.356602)
		(end 173.645068 -3.8862)
		(width 0.127)
		(layer "F.Cu")
		(net "BMC_ML_PWR_YELLOW_LED")
	)
	(segment
		(start 98.2091 -90.7161)
		(end 98.2091 -108.638594)
		(width 0.127)
		(layer "F.Cu")
		(net "BMC_ML_PWR_YELLOW_LED")
	)
	(segment
		(start 178.178968 -8.4201)
		(end 177.11547 -7.356602)
		(width 0.127)
		(layer "F.Cu")
		(net "BMC_ML_PWR_YELLOW_LED")
	)
	(segment
		(start 104.8512 -17.1704)
		(end 96.646746 -25.374854)
		(width 0.127)
		(layer "F.Cu")
		(net "BMC_ML_PWR_YELLOW_LED")
	)
	(segment
		(start 95.8342 -88.3412)
		(end 97.2312 -89.7382)
		(width 0.127)
		(layer "F.Cu")
		(net "BMC_ML_PWR_YELLOW_LED")
	)
	(segment
		(start 136.357614 -3.8862)
		(end 135.745982 -3.274568)
		(width 0.127)
		(layer "F.Cu")
		(net "BMC_ML_PWR_YELLOW_LED")
	)
	(segment
		(start 135.745982 -3.274568)
		(end 109.68482 -3.274568)
		(width 0.127)
		(layer "F.Cu")
		(net "BMC_ML_PWR_YELLOW_LED")
	)
	(segment
		(start 104.8512 -16.6878)
		(end 104.8512 -17.1704)
		(width 0.127)
		(layer "F.Cu")
		(net "BMC_ML_PWR_YELLOW_LED")
	)
	(segment
		(start 38.899846 -137.800334)
		(end 38.900354 -137.800334)
		(width 0.127)
		(layer "F.Cu")
		(net "BMC_ML_PWR_YELLOW_LED")
	)
	(segment
		(start 96.646746 -62.331854)
		(end 95.631 -63.3476)
		(width 0.127)
		(layer "F.Cu")
		(net "BMC_ML_PWR_YELLOW_LED")
	)
	(segment
		(start 90.920824 -112.806988)
		(end 88.996012 -114.7318)
		(width 0.127)
		(layer "F.Cu")
		(net "BMC_ML_PWR_YELLOW_LED")
	)
	(segment
		(start 98.2091 -108.638594)
		(end 94.040706 -112.806988)
		(width 0.127)
		(layer "F.Cu")
		(net "BMC_ML_PWR_YELLOW_LED")
	)
	(segment
		(start 78.263242 -114.7318)
		(end 74.974704 -118.020338)
		(width 0.127)
		(layer "F.Cu")
		(net "BMC_ML_PWR_YELLOW_LED")
	)
	(segment
		(start 95.631 -63.3476)
		(end 95.631 -82.423)
		(width 0.127)
		(layer "F.Cu")
		(net "BMC_ML_PWR_YELLOW_LED")
	)
	(segment
		(start 38.900354 -137.800334)
		(end 39.299896 -138.199876)
		(width 0.127)
		(layer "F.Cu")
		(net "BMC_ML_PWR_YELLOW_LED")
	)
	(segment
		(start 74.974704 -118.020338)
		(end 74.974704 -127.488696)
		(width 0.127)
		(layer "F.Cu")
		(net "BMC_ML_PWR_YELLOW_LED")
	)
	(segment
		(start 108.372148 -13.166852)
		(end 104.8512 -16.6878)
		(width 0.127)
		(layer "F.Cu")
		(net "BMC_ML_PWR_YELLOW_LED")
	)
	(segment
		(start 74.974704 -127.488696)
		(end 74.6252 -127.8382)
		(width 0.127)
		(layer "F.Cu")
		(net "BMC_ML_PWR_YELLOW_LED")
	)
	(segment
		(start 108.372148 -4.58724)
		(end 108.372148 -13.166852)
		(width 0.127)
		(layer "F.Cu")
		(net "BMC_ML_PWR_YELLOW_LED")
	)
	(segment
		(start 109.68482 -3.274568)
		(end 108.372148 -4.58724)
		(width 0.127)
		(layer "F.Cu")
		(net "BMC_ML_PWR_YELLOW_LED")
	)
	(segment
		(start 95.8342 -82.6262)
		(end 95.8342 -88.3412)
		(width 0.127)
		(layer "F.Cu")
		(net "BMC_ML_PWR_YELLOW_LED")
	)
	(segment
		(start 173.645068 -3.8862)
		(end 136.357614 -3.8862)
		(width 0.127)
		(layer "F.Cu")
		(net "BMC_ML_PWR_YELLOW_LED")
	)
	(segment
		(start 183.8452 -8.4201)
		(end 178.178968 -8.4201)
		(width 0.127)
		(layer "F.Cu")
		(net "BMC_ML_PWR_YELLOW_LED")
	)
	(segment
		(start 88.996012 -114.7318)
		(end 78.263242 -114.7318)
		(width 0.127)
		(layer "F.Cu")
		(net "BMC_ML_PWR_YELLOW_LED")
	)
	(via
		(at 97.2312 -89.7382)
		(size 0.6604)
		(drill 0.3302)
		(layers "F.Cu" "B.Cu")
		(net "BMC_ML_PWR_YELLOW_LED")
	)
	(via
		(at 38.899846 -137.800334)
		(size 0.4572)
		(drill 0.2032)
		(layers "F.Cu" "B.Cu")
		(net "BMC_ML_PWR_YELLOW_LED")
	)
	(via
		(at 74.6252 -127.8382)
		(size 0.508)
		(drill 0.254)
		(layers "F.Cu" "B.Cu")
		(net "BMC_ML_PWR_YELLOW_LED")
	)
	(via
		(at 37.6047 -133.02996)
		(size 0.508)
		(drill 0.254)
		(layers "F.Cu" "B.Cu")
		(net "BMC_ML_PWR_YELLOW_LED")
	)
	(via
		(at 177.11547 -7.356602)
		(size 0.6604)
		(drill 0.3302)
		(layers "F.Cu" "B.Cu")
		(net "BMC_ML_PWR_YELLOW_LED")
	)
	(segment
		(start 37.2364 -132.66166)
		(end 37.6047 -133.02996)
		(width 0.127)
		(layer "B.Cu")
		(net "BMC_ML_PWR_YELLOW_LED")
	)
	(segment
		(start 37.2364 -132.2705)
		(end 37.2364 -132.66166)
		(width 0.127)
		(layer "B.Cu")
		(net "BMC_ML_PWR_YELLOW_LED")
	)
	(segment
		(start 37.6047 -133.02996)
		(end 37.338 -133.29666)
		(width 0.127)
		(layer "In2.Cu")
		(net "BMC_ML_PWR_YELLOW_LED")
	)
	(segment
		(start 37.338 -136.271)
		(end 38.867334 -137.800334)
		(width 0.127)
		(layer "In2.Cu")
		(net "BMC_ML_PWR_YELLOW_LED")
	)
	(segment
		(start 37.338 -133.29666)
		(end 37.338 -136.271)
		(width 0.127)
		(layer "In2.Cu")
		(net "BMC_ML_PWR_YELLOW_LED")
	)
	(segment
		(start 38.867334 -137.800334)
		(end 38.899846 -137.800334)
		(width 0.127)
		(layer "In2.Cu")
		(net "BMC_ML_PWR_YELLOW_LED")
	)
	(segment
		(start 37.6047 -133.02996)
		(end 38.134036 -133.02996)
		(width 0.127)
		(layer "In5.Cu")
		(net "BMC_ML_PWR_YELLOW_LED")
	)
	(segment
		(start 58.6486 -128.4732)
		(end 73.9902 -128.4732)
		(width 0.127)
		(layer "In5.Cu")
		(net "BMC_ML_PWR_YELLOW_LED")
	)
	(segment
		(start 73.9902 -128.4732)
		(end 74.6252 -127.8382)
		(width 0.127)
		(layer "In5.Cu")
		(net "BMC_ML_PWR_YELLOW_LED")
	)
	(segment
		(start 45.593 -131.8006)
		(end 55.3212 -131.8006)
		(width 0.127)
		(layer "In5.Cu")
		(net "BMC_ML_PWR_YELLOW_LED")
	)
	(segment
		(start 38.728396 -132.4356)
		(end 44.958 -132.4356)
		(width 0.127)
		(layer "In5.Cu")
		(net "BMC_ML_PWR_YELLOW_LED")
	)
	(segment
		(start 44.958 -132.4356)
		(end 45.593 -131.8006)
		(width 0.127)
		(layer "In5.Cu")
		(net "BMC_ML_PWR_YELLOW_LED")
	)
	(segment
		(start 55.3212 -131.8006)
		(end 58.6486 -128.4732)
		(width 0.127)
		(layer "In5.Cu")
		(net "BMC_ML_PWR_YELLOW_LED")
	)
	(segment
		(start 38.134036 -133.02996)
		(end 38.728396 -132.4356)
		(width 0.127)
		(layer "In5.Cu")
		(net "BMC_ML_PWR_YELLOW_LED")
	)
	(segment
		(start 178.6382 -6.4135)
		(end 178.6382 -7.6454)
		(width 0.127)
		(layer "F.Cu")
		(net "BMC_ML_PWR_BLUE_LED_R")
	)
	(segment
		(start 180.4797 -7.81685)
		(end 178.80965 -7.81685)
		(width 0.127)
		(layer "F.Cu")
		(net "BMC_ML_PWR_BLUE_LED_R")
	)
	(segment
		(start 178.80965 -7.81685)
		(end 178.6382 -7.6454)
		(width 0.127)
		(layer "F.Cu")
		(net "BMC_ML_PWR_BLUE_LED_R")
	)
	(via
		(at 178.6382 -7.6454)
		(size 0.6604)
		(drill 0.3302)
		(layers "F.Cu" "B.Cu")
		(net "BMC_ML_PWR_BLUE_LED_R")
	)
	(segment
		(start 109.526832 -2.893568)
		(end 107.991148 -4.429252)
		(width 0.127)
		(layer "F.Cu")
		(net "BMC_ML_PWR_BLUE_LED")
	)
	(segment
		(start 95.25 -82.580988)
		(end 95.4024 -82.733388)
		(width 0.127)
		(layer "F.Cu")
		(net "BMC_ML_PWR_BLUE_LED")
	)
	(segment
		(start 78.105254 -114.3508)
		(end 73.914 -118.542054)
		(width 0.127)
		(layer "F.Cu")
		(net "BMC_ML_PWR_BLUE_LED")
	)
	(segment
		(start 73.914 -118.542054)
		(end 73.914 -127.5588)
		(width 0.127)
		(layer "F.Cu")
		(net "BMC_ML_PWR_BLUE_LED")
	)
	(segment
		(start 136.515602 -3.5052)
		(end 135.90397 -2.893568)
		(width 0.127)
		(layer "F.Cu")
		(net "BMC_ML_PWR_BLUE_LED")
	)
	(segment
		(start 175.822356 -5.5245)
		(end 173.803056 -3.5052)
		(width 0.127)
		(layer "F.Cu")
		(net "BMC_ML_PWR_BLUE_LED")
	)
	(segment
		(start 173.803056 -3.5052)
		(end 136.515602 -3.5052)
		(width 0.127)
		(layer "F.Cu")
		(net "BMC_ML_PWR_BLUE_LED")
	)
	(segment
		(start 97.8281 -91.147646)
		(end 97.8281 -108.480606)
		(width 0.127)
		(layer "F.Cu")
		(net "BMC_ML_PWR_BLUE_LED")
	)
	(segment
		(start 95.25 -63.189612)
		(end 95.25 -82.580988)
		(width 0.127)
		(layer "F.Cu")
		(net "BMC_ML_PWR_BLUE_LED")
	)
	(segment
		(start 93.882718 -112.425988)
		(end 90.762836 -112.425988)
		(width 0.127)
		(layer "F.Cu")
		(net "BMC_ML_PWR_BLUE_LED")
	)
	(segment
		(start 39.299896 -137.40003)
		(end 38.9001 -137.000234)
		(width 0.127)
		(layer "F.Cu")
		(net "BMC_ML_PWR_BLUE_LED")
	)
	(segment
		(start 96.265746 -25.216612)
		(end 96.265746 -62.173866)
		(width 0.127)
		(layer "F.Cu")
		(net "BMC_ML_PWR_BLUE_LED")
	)
	(segment
		(start 90.762836 -112.425988)
		(end 88.838024 -114.3508)
		(width 0.127)
		(layer "F.Cu")
		(net "BMC_ML_PWR_BLUE_LED")
	)
	(segment
		(start 178.6382 -5.5245)
		(end 176.668176 -5.5245)
		(width 0.127)
		(layer "F.Cu")
		(net "BMC_ML_PWR_BLUE_LED")
	)
	(segment
		(start 107.991148 -4.429252)
		(end 107.991148 -13.008864)
		(width 0.127)
		(layer "F.Cu")
		(net "BMC_ML_PWR_BLUE_LED")
	)
	(segment
		(start 97.8281 -108.480606)
		(end 93.882718 -112.425988)
		(width 0.127)
		(layer "F.Cu")
		(net "BMC_ML_PWR_BLUE_LED")
	)
	(segment
		(start 176.668176 -5.5245)
		(end 175.822356 -5.5245)
		(width 0.127)
		(layer "F.Cu")
		(net "BMC_ML_PWR_BLUE_LED")
	)
	(segment
		(start 95.4024 -88.721946)
		(end 97.8281 -91.147646)
		(width 0.127)
		(layer "F.Cu")
		(net "BMC_ML_PWR_BLUE_LED")
	)
	(segment
		(start 104.403906 -17.078452)
		(end 96.265746 -25.216612)
		(width 0.127)
		(layer "F.Cu")
		(net "BMC_ML_PWR_BLUE_LED")
	)
	(segment
		(start 104.403906 -16.596106)
		(end 104.403906 -17.078452)
		(width 0.127)
		(layer "F.Cu")
		(net "BMC_ML_PWR_BLUE_LED")
	)
	(segment
		(start 107.991148 -13.008864)
		(end 104.403906 -16.596106)
		(width 0.127)
		(layer "F.Cu")
		(net "BMC_ML_PWR_BLUE_LED")
	)
	(segment
		(start 73.914 -127.5588)
		(end 73.66 -127.8128)
		(width 0.127)
		(layer "F.Cu")
		(net "BMC_ML_PWR_BLUE_LED")
	)
	(segment
		(start 96.265746 -62.173866)
		(end 95.25 -63.189612)
		(width 0.127)
		(layer "F.Cu")
		(net "BMC_ML_PWR_BLUE_LED")
	)
	(segment
		(start 135.90397 -2.893568)
		(end 109.526832 -2.893568)
		(width 0.127)
		(layer "F.Cu")
		(net "BMC_ML_PWR_BLUE_LED")
	)
	(segment
		(start 95.4024 -82.733388)
		(end 95.4024 -88.721946)
		(width 0.127)
		(layer "F.Cu")
		(net "BMC_ML_PWR_BLUE_LED")
	)
	(segment
		(start 88.838024 -114.3508)
		(end 78.105254 -114.3508)
		(width 0.127)
		(layer "F.Cu")
		(net "BMC_ML_PWR_BLUE_LED")
	)
	(via
		(at 38.240462 -130.175)
		(size 0.508)
		(drill 0.254)
		(layers "F.Cu" "B.Cu")
		(net "BMC_ML_PWR_BLUE_LED")
	)
	(via
		(at 73.66 -127.8128)
		(size 0.508)
		(drill 0.254)
		(layers "F.Cu" "B.Cu")
		(net "BMC_ML_PWR_BLUE_LED")
	)
	(via
		(at 176.668176 -5.5245)
		(size 0.6604)
		(drill 0.3302)
		(layers "F.Cu" "B.Cu")
		(net "BMC_ML_PWR_BLUE_LED")
	)
	(via
		(at 38.9001 -137.000234)
		(size 0.4572)
		(drill 0.2032)
		(layers "F.Cu" "B.Cu")
		(net "BMC_ML_PWR_BLUE_LED")
	)
	(segment
		(start 38.240462 -129.384806)
		(end 38.240462 -130.175)
		(width 0.127)
		(layer "B.Cu")
		(net "BMC_ML_PWR_BLUE_LED")
	)
	(segment
		(start 38.5064 -131.354576)
		(end 38.5064 -133.985)
		(width 0.127)
		(layer "In2.Cu")
		(net "BMC_ML_PWR_BLUE_LED")
	)
	(segment
		(start 37.719 -134.7724)
		(end 37.719 -135.819134)
		(width 0.127)
		(layer "In2.Cu")
		(net "BMC_ML_PWR_BLUE_LED")
	)
	(segment
		(start 38.240462 -130.175)
		(end 38.240462 -131.088638)
		(width 0.127)
		(layer "In2.Cu")
		(net "BMC_ML_PWR_BLUE_LED")
	)
	(segment
		(start 37.719 -135.819134)
		(end 38.9001 -137.000234)
		(width 0.127)
		(layer "In2.Cu")
		(net "BMC_ML_PWR_BLUE_LED")
	)
	(segment
		(start 38.5064 -133.985)
		(end 37.719 -134.7724)
		(width 0.127)
		(layer "In2.Cu")
		(net "BMC_ML_PWR_BLUE_LED")
	)
	(segment
		(start 38.240462 -131.088638)
		(end 38.5064 -131.354576)
		(width 0.127)
		(layer "In2.Cu")
		(net "BMC_ML_PWR_BLUE_LED")
	)
	(segment
		(start 73.3806 -128.0922)
		(end 73.66 -127.8128)
		(width 0.127)
		(layer "In5.Cu")
		(net "BMC_ML_PWR_BLUE_LED")
	)
	(segment
		(start 38.240462 -130.175)
		(end 38.240462 -130.460242)
		(width 0.127)
		(layer "In5.Cu")
		(net "BMC_ML_PWR_BLUE_LED")
	)
	(segment
		(start 45.3644 -131.1402)
		(end 45.6438 -131.4196)
		(width 0.127)
		(layer "In5.Cu")
		(net "BMC_ML_PWR_BLUE_LED")
	)
	(segment
		(start 57.4548 -128.905)
		(end 58.2676 -128.0922)
		(width 0.127)
		(layer "In5.Cu")
		(net "BMC_ML_PWR_BLUE_LED")
	)
	(segment
		(start 58.2676 -128.0922)
		(end 73.3806 -128.0922)
		(width 0.127)
		(layer "In5.Cu")
		(net "BMC_ML_PWR_BLUE_LED")
	)
	(segment
		(start 53.721 -131.4196)
		(end 56.2356 -128.905)
		(width 0.127)
		(layer "In5.Cu")
		(net "BMC_ML_PWR_BLUE_LED")
	)
	(segment
		(start 56.2356 -128.905)
		(end 57.4548 -128.905)
		(width 0.127)
		(layer "In5.Cu")
		(net "BMC_ML_PWR_BLUE_LED")
	)
	(segment
		(start 38.240462 -130.460242)
		(end 38.92042 -131.1402)
		(width 0.127)
		(layer "In5.Cu")
		(net "BMC_ML_PWR_BLUE_LED")
	)
	(segment
		(start 45.6438 -131.4196)
		(end 53.721 -131.4196)
		(width 0.127)
		(layer "In5.Cu")
		(net "BMC_ML_PWR_BLUE_LED")
	)
	(segment
		(start 38.92042 -131.1402)
		(end 45.3644 -131.1402)
		(width 0.127)
		(layer "In5.Cu")
		(net "BMC_ML_PWR_BLUE_LED")
	)
	(segment
		(start 76.969874 -150.706074)
		(end 76.593954 -150.330154)
		(width 0.127)
		(layer "F.Cu")
		(net "COMP_TO_BMC_RESET_R")
	)
	(segment
		(start 77.372718 -150.706074)
		(end 77.716126 -150.706074)
		(width 0.127)
		(layer "F.Cu")
		(net "COMP_TO_BMC_RESET_R")
	)
	(segment
		(start 77.372718 -150.706074)
		(end 76.969874 -150.706074)
		(width 0.127)
		(layer "F.Cu")
		(net "COMP_TO_BMC_RESET_R")
	)
	(segment
		(start 77.918564 -147.947126)
		(end 77.970888 -147.894802)
		(width 0.127)
		(layer "F.Cu")
		(net "COMP_TO_BMC_RESET_R")
	)
	(segment
		(start 77.970888 -147.894802)
		(end 79.043276 -147.894802)
		(width 0.127)
		(layer "F.Cu")
		(net "COMP_TO_BMC_RESET_R")
	)
	(segment
		(start 76.3524 -148.6916)
		(end 76.5175 -148.5265)
		(width 0.127)
		(layer "F.Cu")
		(net "COMP_TO_BMC_RESET_R")
	)
	(segment
		(start 77.33919 -148.5265)
		(end 77.918564 -147.947126)
		(width 0.127)
		(layer "F.Cu")
		(net "COMP_TO_BMC_RESET_R")
	)
	(segment
		(start 76.593954 -149.399244)
		(end 76.3524 -149.15769)
		(width 0.127)
		(layer "F.Cu")
		(net "COMP_TO_BMC_RESET_R")
	)
	(segment
		(start 77.716126 -150.706074)
		(end 78.361286 -150.060914)
		(width 0.127)
		(layer "F.Cu")
		(net "COMP_TO_BMC_RESET_R")
	)
	(segment
		(start 78.361286 -150.060914)
		(end 79.314548 -150.060914)
		(width 0.127)
		(layer "F.Cu")
		(net "COMP_TO_BMC_RESET_R")
	)
	(segment
		(start 76.593954 -150.330154)
		(end 76.593954 -149.399244)
		(width 0.127)
		(layer "F.Cu")
		(net "COMP_TO_BMC_RESET_R")
	)
	(segment
		(start 76.3524 -149.15769)
		(end 76.3524 -148.6916)
		(width 0.127)
		(layer "F.Cu")
		(net "COMP_TO_BMC_RESET_R")
	)
	(segment
		(start 76.5175 -148.5265)
		(end 77.33919 -148.5265)
		(width 0.127)
		(layer "F.Cu")
		(net "COMP_TO_BMC_RESET_R")
	)
	(via
		(at 77.918564 -147.947126)
		(size 0.6604)
		(drill 0.3302)
		(layers "F.Cu" "B.Cu")
		(net "COMP_TO_BMC_RESET_R")
	)
	(segment
		(start 81.8261 -148.302472)
		(end 81.517998 -147.99437)
		(width 0.127)
		(layer "F.Cu")
		(net "COMP_TO_BMC_RESET")
	)
	(segment
		(start 81.8261 -148.700998)
		(end 81.8261 -148.302472)
		(width 0.127)
		(layer "F.Cu")
		(net "COMP_TO_BMC_RESET")
	)
	(segment
		(start 80.529684 -147.909026)
		(end 80.51546 -147.894802)
		(width 0.127)
		(layer "F.Cu")
		(net "COMP_TO_BMC_RESET")
	)
	(segment
		(start 81.432654 -147.909026)
		(end 80.529684 -147.909026)
		(width 0.127)
		(layer "F.Cu")
		(net "COMP_TO_BMC_RESET")
	)
	(segment
		(start 81.517998 -147.99437)
		(end 81.432654 -147.909026)
		(width 0.127)
		(layer "F.Cu")
		(net "COMP_TO_BMC_RESET")
	)
	(segment
		(start 80.51546 -147.894802)
		(end 79.932276 -147.894802)
		(width 0.127)
		(layer "F.Cu")
		(net "COMP_TO_BMC_RESET")
	)
	(segment
		(start 82.778346 -149.653244)
		(end 81.8261 -148.700998)
		(width 0.127)
		(layer "F.Cu")
		(net "COMP_TO_BMC_RESET")
	)
	(via
		(at 82.778346 -149.653244)
		(size 0.508)
		(drill 0.254)
		(layers "F.Cu" "B.Cu")
		(net "COMP_TO_BMC_RESET")
	)
	(via
		(at 81.517998 -147.99437)
		(size 0.6604)
		(drill 0.3302)
		(layers "F.Cu" "B.Cu")
		(net "COMP_TO_BMC_RESET")
	)
	(via
		(at 100.047806 -137.974578)
		(size 0.508)
		(drill 0.254)
		(layers "F.Cu" "B.Cu")
		(net "COMP_TO_BMC_RESET")
	)
	(via
		(at 83.163918 -139.279376)
		(size 0.508)
		(drill 0.254)
		(layers "F.Cu" "B.Cu")
		(net "COMP_TO_BMC_RESET")
	)
	(segment
		(start 99.822 -46.188376)
		(end 99.822 -120.709436)
		(width 0.127)
		(layer "In2.Cu")
		(net "COMP_TO_BMC_RESET")
	)
	(segment
		(start 105.042462 -40.967914)
		(end 99.822 -46.188376)
		(width 0.127)
		(layer "In2.Cu")
		(net "COMP_TO_BMC_RESET")
	)
	(segment
		(start 83.027266 -139.416028)
		(end 83.163918 -139.279376)
		(width 0.127)
		(layer "In2.Cu")
		(net "COMP_TO_BMC_RESET")
	)
	(segment
		(start 99.0092 -121.522236)
		(end 99.0092 -123.760992)
		(width 0.127)
		(layer "In2.Cu")
		(net "COMP_TO_BMC_RESET")
	)
	(segment
		(start 112.35563 -29.947616)
		(end 106.827066 -29.947616)
		(width 0.127)
		(layer "In2.Cu")
		(net "COMP_TO_BMC_RESET")
	)
	(segment
		(start 113.071402 -43.628564)
		(end 113.071402 -30.663388)
		(width 0.127)
		(layer "In2.Cu")
		(net "COMP_TO_BMC_RESET")
	)
	(segment
		(start 99.127818 -128.20777)
		(end 99.127818 -130.448812)
		(width 0.127)
		(layer "In2.Cu")
		(net "COMP_TO_BMC_RESET")
	)
	(segment
		(start 99.127818 -130.448812)
		(end 99.4156 -130.736594)
		(width 0.127)
		(layer "In2.Cu")
		(net "COMP_TO_BMC_RESET")
	)
	(segment
		(start 112.499902 -44.200064)
		(end 113.071402 -43.628564)
		(width 0.127)
		(layer "In2.Cu")
		(net "COMP_TO_BMC_RESET")
	)
	(segment
		(start 82.778346 -149.653244)
		(end 83.027266 -149.404324)
		(width 0.127)
		(layer "In2.Cu")
		(net "COMP_TO_BMC_RESET")
	)
	(segment
		(start 99.822 -120.709436)
		(end 99.0092 -121.522236)
		(width 0.127)
		(layer "In2.Cu")
		(net "COMP_TO_BMC_RESET")
	)
	(segment
		(start 99.4156 -130.736594)
		(end 99.4156 -135.006588)
		(width 0.127)
		(layer "In2.Cu")
		(net "COMP_TO_BMC_RESET")
	)
	(segment
		(start 99.0092 -123.760992)
		(end 100.106988 -124.85878)
		(width 0.127)
		(layer "In2.Cu")
		(net "COMP_TO_BMC_RESET")
	)
	(segment
		(start 99.0854 -135.336788)
		(end 99.0854 -137.012172)
		(width 0.127)
		(layer "In2.Cu")
		(net "COMP_TO_BMC_RESET")
	)
	(segment
		(start 99.0854 -137.012172)
		(end 100.047806 -137.974578)
		(width 0.127)
		(layer "In2.Cu")
		(net "COMP_TO_BMC_RESET")
	)
	(segment
		(start 83.027266 -149.404324)
		(end 83.027266 -139.416028)
		(width 0.127)
		(layer "In2.Cu")
		(net "COMP_TO_BMC_RESET")
	)
	(segment
		(start 99.4156 -135.006588)
		(end 99.0854 -135.336788)
		(width 0.127)
		(layer "In2.Cu")
		(net "COMP_TO_BMC_RESET")
	)
	(segment
		(start 113.071402 -30.663388)
		(end 112.35563 -29.947616)
		(width 0.127)
		(layer "In2.Cu")
		(net "COMP_TO_BMC_RESET")
	)
	(segment
		(start 106.827066 -29.947616)
		(end 105.042462 -31.73222)
		(width 0.127)
		(layer "In2.Cu")
		(net "COMP_TO_BMC_RESET")
	)
	(segment
		(start 100.106988 -124.85878)
		(end 100.106988 -127.2286)
		(width 0.127)
		(layer "In2.Cu")
		(net "COMP_TO_BMC_RESET")
	)
	(segment
		(start 100.106988 -127.2286)
		(end 99.127818 -128.20777)
		(width 0.127)
		(layer "In2.Cu")
		(net "COMP_TO_BMC_RESET")
	)
	(segment
		(start 105.042462 -31.73222)
		(end 105.042462 -40.967914)
		(width 0.127)
		(layer "In2.Cu")
		(net "COMP_TO_BMC_RESET")
	)
	(segment
		(start 87.489284 -139.36091)
		(end 85.71611 -139.36091)
		(width 0.127)
		(layer "In5.Cu")
		(net "COMP_TO_BMC_RESET")
	)
	(segment
		(start 83.289394 -139.1539)
		(end 83.163918 -139.279376)
		(width 0.127)
		(layer "In5.Cu")
		(net "COMP_TO_BMC_RESET")
	)
	(segment
		(start 85.5091 -139.1539)
		(end 83.289394 -139.1539)
		(width 0.127)
		(layer "In5.Cu")
		(net "COMP_TO_BMC_RESET")
	)
	(segment
		(start 100.047806 -137.974578)
		(end 100.047806 -138.35634)
		(width 0.127)
		(layer "In5.Cu")
		(net "COMP_TO_BMC_RESET")
	)
	(segment
		(start 88.64727 -139.360656)
		(end 87.489538 -139.360656)
		(width 0.127)
		(layer "In5.Cu")
		(net "COMP_TO_BMC_RESET")
	)
	(segment
		(start 98.831146 -139.573)
		(end 96.618806 -139.573)
		(width 0.127)
		(layer "In5.Cu")
		(net "COMP_TO_BMC_RESET")
	)
	(segment
		(start 92.452952 -141.096746)
		(end 92.213938 -141.33576)
		(width 0.127)
		(layer "In5.Cu")
		(net "COMP_TO_BMC_RESET")
	)
	(segment
		(start 90.622374 -141.33576)
		(end 88.64727 -139.360656)
		(width 0.127)
		(layer "In5.Cu")
		(net "COMP_TO_BMC_RESET")
	)
	(segment
		(start 87.489538 -139.360656)
		(end 87.489284 -139.36091)
		(width 0.127)
		(layer "In5.Cu")
		(net "COMP_TO_BMC_RESET")
	)
	(segment
		(start 96.618806 -139.573)
		(end 94.828106 -141.3637)
		(width 0.127)
		(layer "In5.Cu")
		(net "COMP_TO_BMC_RESET")
	)
	(segment
		(start 85.71611 -139.36091)
		(end 85.5091 -139.1539)
		(width 0.127)
		(layer "In5.Cu")
		(net "COMP_TO_BMC_RESET")
	)
	(segment
		(start 100.047806 -138.35634)
		(end 98.831146 -139.573)
		(width 0.127)
		(layer "In5.Cu")
		(net "COMP_TO_BMC_RESET")
	)
	(segment
		(start 94.828106 -141.3637)
		(end 93.988382 -141.3637)
		(width 0.127)
		(layer "In5.Cu")
		(net "COMP_TO_BMC_RESET")
	)
	(segment
		(start 92.213938 -141.33576)
		(end 90.622374 -141.33576)
		(width 0.127)
		(layer "In5.Cu")
		(net "COMP_TO_BMC_RESET")
	)
	(segment
		(start 93.721428 -141.096746)
		(end 92.452952 -141.096746)
		(width 0.127)
		(layer "In5.Cu")
		(net "COMP_TO_BMC_RESET")
	)
	(segment
		(start 93.988382 -141.3637)
		(end 93.721428 -141.096746)
		(width 0.127)
		(layer "In5.Cu")
		(net "COMP_TO_BMC_RESET")
	)
	(segment
		(start 90.678 -131.191)
		(end 89.9668 -131.191)
		(width 0.127)
		(layer "F.Cu")
		(net "UART_SEL_MUX")
	)
	(segment
		(start 85.037422 -128.424178)
		(end 85.037422 -129.211578)
		(width 0.127)
		(layer "F.Cu")
		(net "UART_SEL_MUX")
	)
	(segment
		(start 92.9386 -130.7338)
		(end 92.861384 -130.811016)
		(width 0.127)
		(layer "F.Cu")
		(net "UART_SEL_MUX")
	)
	(segment
		(start 88.1507 -128.1176)
		(end 85.344 -128.1176)
		(width 0.127)
		(layer "F.Cu")
		(net "UART_SEL_MUX")
	)
	(segment
		(start 92.861384 -130.811016)
		(end 91.805506 -130.811016)
		(width 0.127)
		(layer "F.Cu")
		(net "UART_SEL_MUX")
	)
	(segment
		(start 82.423 -135.5725)
		(end 82.423 -135.1788)
		(width 0.127)
		(layer "F.Cu")
		(net "UART_SEL_MUX")
	)
	(segment
		(start 89.2175 -129.004568)
		(end 89.232994 -128.989074)
		(width 0.127)
		(layer "F.Cu")
		(net "UART_SEL_MUX")
	)
	(segment
		(start 85.037422 -129.211578)
		(end 84.0359 -130.2131)
		(width 0.127)
		(layer "F.Cu")
		(net "UART_SEL_MUX")
	)
	(segment
		(start 71.7296 -130.7338)
		(end 70.358 -132.1054)
		(width 0.127)
		(layer "F.Cu")
		(net "UART_SEL_MUX")
	)
	(segment
		(start 85.344 -128.1176)
		(end 85.037422 -128.424178)
		(width 0.127)
		(layer "F.Cu")
		(net "UART_SEL_MUX")
	)
	(segment
		(start 70.358 -132.1054)
		(end 70.358 -134.4676)
		(width 0.127)
		(layer "F.Cu")
		(net "UART_SEL_MUX")
	)
	(segment
		(start 89.2175 -127.0508)
		(end 88.1507 -128.1176)
		(width 0.127)
		(layer "F.Cu")
		(net "UART_SEL_MUX")
	)
	(segment
		(start 72.0217 -135.89)
		(end 71.7804 -135.89)
		(width 0.127)
		(layer "F.Cu")
		(net "UART_SEL_MUX")
	)
	(segment
		(start 89.2175 -127.0508)
		(end 89.2175 -128.0033)
		(width 0.127)
		(layer "F.Cu")
		(net "UART_SEL_MUX")
	)
	(segment
		(start 89.2175 -130.0226)
		(end 89.2175 -129.004568)
		(width 0.127)
		(layer "F.Cu")
		(net "UART_SEL_MUX")
	)
	(segment
		(start 80.9498 -131.2926)
		(end 76.0476 -131.2926)
		(width 0.127)
		(layer "F.Cu")
		(net "UART_SEL_MUX")
	)
	(segment
		(start 84.0359 -130.2131)
		(end 82.0293 -130.2131)
		(width 0.127)
		(layer "F.Cu")
		(net "UART_SEL_MUX")
	)
	(segment
		(start 82.0293 -130.2131)
		(end 80.9498 -131.2926)
		(width 0.127)
		(layer "F.Cu")
		(net "UART_SEL_MUX")
	)
	(segment
		(start 89.9668 -131.191)
		(end 89.2175 -130.4417)
		(width 0.127)
		(layer "F.Cu")
		(net "UART_SEL_MUX")
	)
	(segment
		(start 82.423 -135.1788)
		(end 82.0166 -134.7724)
		(width 0.127)
		(layer "F.Cu")
		(net "UART_SEL_MUX")
	)
	(segment
		(start 89.2302 -128.016)
		(end 89.2302 -128.98628)
		(width 0.127)
		(layer "F.Cu")
		(net "UART_SEL_MUX")
	)
	(segment
		(start 92.9386 -129.121662)
		(end 92.9386 -130.7338)
		(width 0.127)
		(layer "F.Cu")
		(net "UART_SEL_MUX")
	)
	(segment
		(start 91.805506 -130.811016)
		(end 91.057984 -130.811016)
		(width 0.127)
		(layer "F.Cu")
		(net "UART_SEL_MUX")
	)
	(segment
		(start 89.2175 -128.0033)
		(end 89.2302 -128.016)
		(width 0.127)
		(layer "F.Cu")
		(net "UART_SEL_MUX")
	)
	(segment
		(start 91.805506 -128.812036)
		(end 92.628974 -128.812036)
		(width 0.127)
		(layer "F.Cu")
		(net "UART_SEL_MUX")
	)
	(segment
		(start 89.2302 -128.98628)
		(end 89.232994 -128.989074)
		(width 0.127)
		(layer "F.Cu")
		(net "UART_SEL_MUX")
	)
	(segment
		(start 92.628974 -128.812036)
		(end 92.9386 -129.121662)
		(width 0.127)
		(layer "F.Cu")
		(net "UART_SEL_MUX")
	)
	(segment
		(start 70.358 -134.4676)
		(end 70.9168 -135.0264)
		(width 0.127)
		(layer "F.Cu")
		(net "UART_SEL_MUX")
	)
	(segment
		(start 91.057984 -130.811016)
		(end 90.678 -131.191)
		(width 0.127)
		(layer "F.Cu")
		(net "UART_SEL_MUX")
	)
	(segment
		(start 71.7804 -135.89)
		(end 70.9168 -135.0264)
		(width 0.127)
		(layer "F.Cu")
		(net "UART_SEL_MUX")
	)
	(segment
		(start 89.2175 -130.4417)
		(end 89.2175 -130.0226)
		(width 0.127)
		(layer "F.Cu")
		(net "UART_SEL_MUX")
	)
	(segment
		(start 76.0476 -131.2926)
		(end 75.4888 -130.7338)
		(width 0.127)
		(layer "F.Cu")
		(net "UART_SEL_MUX")
	)
	(segment
		(start 75.4888 -130.7338)
		(end 71.7296 -130.7338)
		(width 0.127)
		(layer "F.Cu")
		(net "UART_SEL_MUX")
	)
	(via
		(at 70.9168 -135.0264)
		(size 0.508)
		(drill 0.254)
		(layers "F.Cu" "B.Cu")
		(net "UART_SEL_MUX")
	)
	(via
		(at 82.0166 -134.7724)
		(size 0.508)
		(drill 0.254)
		(layers "F.Cu" "B.Cu")
		(net "UART_SEL_MUX")
	)
	(via
		(at 89.2302 -128.016)
		(size 0.6604)
		(drill 0.3302)
		(layers "F.Cu" "B.Cu")
		(net "UART_SEL_MUX")
	)
	(segment
		(start 81.7626 -135.0264)
		(end 82.0166 -134.7724)
		(width 0.127)
		(layer "In5.Cu")
		(net "UART_SEL_MUX")
	)
	(segment
		(start 70.9168 -135.0264)
		(end 81.7626 -135.0264)
		(width 0.127)
		(layer "In5.Cu")
		(net "UART_SEL_MUX")
	)
	(segment
		(start 80.5815 -136.4615)
		(end 80.264 -136.144)
		(width 0.127)
		(layer "F.Cu")
		(net "D_FLIP_Q#")
	)
	(segment
		(start 79.921354 -135.801354)
		(end 80.264 -136.144)
		(width 0.127)
		(layer "F.Cu")
		(net "D_FLIP_Q#")
	)
	(segment
		(start 82.423 -136.4615)
		(end 81.28 -136.4615)
		(width 0.127)
		(layer "F.Cu")
		(net "D_FLIP_Q#")
	)
	(segment
		(start 78.084426 -134.919466)
		(end 79.420466 -134.919466)
		(width 0.127)
		(layer "F.Cu")
		(net "D_FLIP_Q#")
	)
	(segment
		(start 79.921354 -135.420354)
		(end 79.921354 -135.801354)
		(width 0.127)
		(layer "F.Cu")
		(net "D_FLIP_Q#")
	)
	(segment
		(start 81.28 -136.4615)
		(end 80.5815 -136.4615)
		(width 0.127)
		(layer "F.Cu")
		(net "D_FLIP_Q#")
	)
	(segment
		(start 79.420466 -134.919466)
		(end 79.921354 -135.420354)
		(width 0.127)
		(layer "F.Cu")
		(net "D_FLIP_Q#")
	)
	(via
		(at 80.264 -136.144)
		(size 0.6604)
		(drill 0.3302)
		(layers "F.Cu" "B.Cu")
		(net "D_FLIP_Q#")
	)
	(segment
		(start 74.266552 -135.965946)
		(end 74.812652 -135.419846)
		(width 0.127)
		(layer "F.Cu")
		(net "D_FLIP_Q")
	)
	(segment
		(start 74.812652 -135.419846)
		(end 75.747626 -135.419846)
		(width 0.127)
		(layer "F.Cu")
		(net "D_FLIP_Q")
	)
	(segment
		(start 72.986646 -135.965946)
		(end 72.9107 -135.89)
		(width 0.127)
		(layer "F.Cu")
		(net "D_FLIP_Q")
	)
	(segment
		(start 73.885806 -135.965946)
		(end 72.986646 -135.965946)
		(width 0.127)
		(layer "F.Cu")
		(net "D_FLIP_Q")
	)
	(segment
		(start 73.885806 -135.965946)
		(end 74.266552 -135.965946)
		(width 0.127)
		(layer "F.Cu")
		(net "D_FLIP_Q")
	)
	(via
		(at 73.885806 -135.965946)
		(size 0.6604)
		(drill 0.3302)
		(layers "F.Cu" "B.Cu")
		(net "D_FLIP_Q")
	)
	(segment
		(start 74.694796 -134.419086)
		(end 75.747626 -134.419086)
		(width 0.3048)
		(layer "F.Cu")
		(net "D_FLIP_PRE#")
	)
	(segment
		(start 74.174096 -133.714236)
		(end 74.373994 -133.914134)
		(width 0.3048)
		(layer "F.Cu")
		(net "D_FLIP_PRE#")
	)
	(segment
		(start 74.373994 -133.914134)
		(end 74.373994 -134.098284)
		(width 0.3048)
		(layer "F.Cu")
		(net "D_FLIP_PRE#")
	)
	(segment
		(start 73.885806 -133.425946)
		(end 74.174096 -133.714236)
		(width 0.508)
		(layer "F.Cu")
		(net "D_FLIP_PRE#")
	)
	(segment
		(start 73.25106 -132.7912)
		(end 73.885806 -133.425946)
		(width 0.508)
		(layer "F.Cu")
		(net "D_FLIP_PRE#")
	)
	(segment
		(start 72.9107 -132.7912)
		(end 73.25106 -132.7912)
		(width 0.508)
		(layer "F.Cu")
		(net "D_FLIP_PRE#")
	)
	(segment
		(start 74.373994 -134.098284)
		(end 74.694796 -134.419086)
		(width 0.3048)
		(layer "F.Cu")
		(net "D_FLIP_PRE#")
	)
	(via
		(at 73.885806 -133.425946)
		(size 0.6604)
		(drill 0.3302)
		(layers "F.Cu" "B.Cu")
		(net "D_FLIP_PRE#")
	)
	(segment
		(start 80.899 -134.62)
		(end 81.28 -135.001)
		(width 0.127)
		(layer "F.Cu")
		(net "D_FLIP_D")
	)
	(segment
		(start 79.575914 -134.62)
		(end 80.264 -134.62)
		(width 0.127)
		(layer "F.Cu")
		(net "D_FLIP_D")
	)
	(segment
		(start 80.264 -134.62)
		(end 80.899 -134.62)
		(width 0.127)
		(layer "F.Cu")
		(net "D_FLIP_D")
	)
	(segment
		(start 79.375 -134.419086)
		(end 79.575914 -134.62)
		(width 0.127)
		(layer "F.Cu")
		(net "D_FLIP_D")
	)
	(segment
		(start 81.28 -135.001)
		(end 81.28 -135.5725)
		(width 0.127)
		(layer "F.Cu")
		(net "D_FLIP_D")
	)
	(segment
		(start 78.084426 -134.419086)
		(end 79.375 -134.419086)
		(width 0.127)
		(layer "F.Cu")
		(net "D_FLIP_D")
	)
	(via
		(at 80.264 -134.62)
		(size 0.6604)
		(drill 0.3302)
		(layers "F.Cu" "B.Cu")
		(net "D_FLIP_D")
	)
	(segment
		(start 73.885806 -134.695946)
		(end 73.50887 -134.695946)
		(width 0.127)
		(layer "F.Cu")
		(net "D_FLIP_CLR#")
	)
	(segment
		(start 73.305416 -134.8994)
		(end 72.8853 -134.8994)
		(width 0.127)
		(layer "F.Cu")
		(net "D_FLIP_CLR#")
	)
	(segment
		(start 73.50887 -134.695946)
		(end 73.305416 -134.8994)
		(width 0.127)
		(layer "F.Cu")
		(net "D_FLIP_CLR#")
	)
	(segment
		(start 74.7014 -134.919466)
		(end 75.747626 -134.919466)
		(width 0.127)
		(layer "F.Cu")
		(net "D_FLIP_CLR#")
	)
	(segment
		(start 74.125074 -134.695946)
		(end 74.165714 -134.736586)
		(width 0.127)
		(layer "F.Cu")
		(net "D_FLIP_CLR#")
	)
	(segment
		(start 72.8853 -134.8994)
		(end 72.8853 -133.9342)
		(width 0.127)
		(layer "F.Cu")
		(net "D_FLIP_CLR#")
	)
	(segment
		(start 74.51852 -134.736586)
		(end 74.7014 -134.919466)
		(width 0.127)
		(layer "F.Cu")
		(net "D_FLIP_CLR#")
	)
	(segment
		(start 73.885806 -134.695946)
		(end 74.125074 -134.695946)
		(width 0.127)
		(layer "F.Cu")
		(net "D_FLIP_CLR#")
	)
	(segment
		(start 74.165714 -134.736586)
		(end 74.51852 -134.736586)
		(width 0.127)
		(layer "F.Cu")
		(net "D_FLIP_CLR#")
	)
	(via
		(at 73.885806 -134.695946)
		(size 0.6604)
		(drill 0.3302)
		(layers "F.Cu" "B.Cu")
		(net "D_FLIP_CLR#")
	)
	(segment
		(start 43.299888 -138.999976)
		(end 43.299888 -138.999722)
		(width 0.127)
		(layer "F.Cu")
		(net "BMC_UART_SEL_OUT")
	)
	(segment
		(start 86.22411 -127.731774)
		(end 84.917026 -127.731774)
		(width 0.127)
		(layer "F.Cu")
		(net "BMC_UART_SEL_OUT")
	)
	(segment
		(start 88.1888 -127.1905)
		(end 86.765384 -127.1905)
		(width 0.127)
		(layer "F.Cu")
		(net "BMC_UART_SEL_OUT")
	)
	(segment
		(start 88.3285 -127.0508)
		(end 88.1888 -127.1905)
		(width 0.127)
		(layer "F.Cu")
		(net "BMC_UART_SEL_OUT")
	)
	(segment
		(start 86.765384 -127.1905)
		(end 86.22411 -127.731774)
		(width 0.127)
		(layer "F.Cu")
		(net "BMC_UART_SEL_OUT")
	)
	(segment
		(start 84.917026 -127.731774)
		(end 84.6836 -127.9652)
		(width 0.127)
		(layer "F.Cu")
		(net "BMC_UART_SEL_OUT")
	)
	(segment
		(start 43.299888 -138.999722)
		(end 42.900092 -138.599926)
		(width 0.127)
		(layer "F.Cu")
		(net "BMC_UART_SEL_OUT")
	)
	(via
		(at 84.6836 -127.9652)
		(size 0.508)
		(drill 0.254)
		(layers "F.Cu" "B.Cu")
		(net "BMC_UART_SEL_OUT")
	)
	(via
		(at 42.900092 -138.599926)
		(size 0.4572)
		(drill 0.2032)
		(layers "F.Cu" "B.Cu")
		(net "BMC_UART_SEL_OUT")
	)
	(via
		(at 84.56676 -136.978898)
		(size 0.508)
		(drill 0.254)
		(layers "F.Cu" "B.Cu")
		(net "BMC_UART_SEL_OUT")
	)
	(via
		(at 86.765384 -127.1905)
		(size 0.6604)
		(drill 0.3302)
		(layers "F.Cu" "B.Cu")
		(net "BMC_UART_SEL_OUT")
	)
	(segment
		(start 84.633308 -131.075938)
		(end 84.633308 -131.612386)
		(width 0.127)
		(layer "In2.Cu")
		(net "BMC_UART_SEL_OUT")
	)
	(segment
		(start 84.56676 -131.678934)
		(end 84.56676 -136.978898)
		(width 0.127)
		(layer "In2.Cu")
		(net "BMC_UART_SEL_OUT")
	)
	(segment
		(start 84.554568 -128.094232)
		(end 84.554568 -130.997198)
		(width 0.127)
		(layer "In2.Cu")
		(net "BMC_UART_SEL_OUT")
	)
	(segment
		(start 84.554568 -130.997198)
		(end 84.633308 -131.075938)
		(width 0.127)
		(layer "In2.Cu")
		(net "BMC_UART_SEL_OUT")
	)
	(segment
		(start 84.633308 -131.612386)
		(end 84.56676 -131.678934)
		(width 0.127)
		(layer "In2.Cu")
		(net "BMC_UART_SEL_OUT")
	)
	(segment
		(start 84.6836 -127.9652)
		(end 84.554568 -128.094232)
		(width 0.127)
		(layer "In2.Cu")
		(net "BMC_UART_SEL_OUT")
	)
	(segment
		(start 62.32398 -135.7122)
		(end 62.418214 -135.806434)
		(width 0.127)
		(layer "In5.Cu")
		(net "BMC_UART_SEL_OUT")
	)
	(segment
		(start 68.153788 -136.4488)
		(end 69.677788 -137.9728)
		(width 0.127)
		(layer "In5.Cu")
		(net "BMC_UART_SEL_OUT")
	)
	(segment
		(start 44.66336 -138.194034)
		(end 46.479714 -136.37768)
		(width 0.127)
		(layer "In5.Cu")
		(net "BMC_UART_SEL_OUT")
	)
	(segment
		(start 82.939382 -136.7155)
		(end 83.412076 -136.7155)
		(width 0.127)
		(layer "In5.Cu")
		(net "BMC_UART_SEL_OUT")
	)
	(segment
		(start 50.412142 -136.37768)
		(end 50.638456 -136.603994)
		(width 0.127)
		(layer "In5.Cu")
		(net "BMC_UART_SEL_OUT")
	)
	(segment
		(start 62.118748 -135.7122)
		(end 62.32398 -135.7122)
		(width 0.127)
		(layer "In5.Cu")
		(net "BMC_UART_SEL_OUT")
	)
	(segment
		(start 56.775604 -136.603994)
		(end 56.956452 -136.423146)
		(width 0.127)
		(layer "In5.Cu")
		(net "BMC_UART_SEL_OUT")
	)
	(segment
		(start 59.264042 -135.297418)
		(end 61.703966 -135.297418)
		(width 0.127)
		(layer "In5.Cu")
		(net "BMC_UART_SEL_OUT")
	)
	(segment
		(start 58.138314 -136.423146)
		(end 59.264042 -135.297418)
		(width 0.127)
		(layer "In5.Cu")
		(net "BMC_UART_SEL_OUT")
	)
	(segment
		(start 61.703966 -135.297418)
		(end 62.118748 -135.7122)
		(width 0.127)
		(layer "In5.Cu")
		(net "BMC_UART_SEL_OUT")
	)
	(segment
		(start 82.825082 -136.8298)
		(end 82.939382 -136.7155)
		(width 0.127)
		(layer "In5.Cu")
		(net "BMC_UART_SEL_OUT")
	)
	(segment
		(start 43.305984 -138.194034)
		(end 44.66336 -138.194034)
		(width 0.127)
		(layer "In5.Cu")
		(net "BMC_UART_SEL_OUT")
	)
	(segment
		(start 62.80785 -135.806434)
		(end 62.89675 -135.717534)
		(width 0.127)
		(layer "In5.Cu")
		(net "BMC_UART_SEL_OUT")
	)
	(segment
		(start 62.89675 -135.717534)
		(end 65.3796 -135.717534)
		(width 0.127)
		(layer "In5.Cu")
		(net "BMC_UART_SEL_OUT")
	)
	(segment
		(start 72.644 -137.9728)
		(end 74.168 -136.4488)
		(width 0.127)
		(layer "In5.Cu")
		(net "BMC_UART_SEL_OUT")
	)
	(segment
		(start 77.47 -136.4488)
		(end 77.851 -136.8298)
		(width 0.127)
		(layer "In5.Cu")
		(net "BMC_UART_SEL_OUT")
	)
	(segment
		(start 42.900092 -138.599926)
		(end 43.305984 -138.194034)
		(width 0.127)
		(layer "In5.Cu")
		(net "BMC_UART_SEL_OUT")
	)
	(segment
		(start 77.851 -136.8298)
		(end 82.825082 -136.8298)
		(width 0.127)
		(layer "In5.Cu")
		(net "BMC_UART_SEL_OUT")
	)
	(segment
		(start 69.677788 -137.9728)
		(end 72.644 -137.9728)
		(width 0.127)
		(layer "In5.Cu")
		(net "BMC_UART_SEL_OUT")
	)
	(segment
		(start 46.479714 -136.37768)
		(end 50.412142 -136.37768)
		(width 0.127)
		(layer "In5.Cu")
		(net "BMC_UART_SEL_OUT")
	)
	(segment
		(start 56.956452 -136.423146)
		(end 58.138314 -136.423146)
		(width 0.127)
		(layer "In5.Cu")
		(net "BMC_UART_SEL_OUT")
	)
	(segment
		(start 83.675474 -136.978898)
		(end 84.56676 -136.978898)
		(width 0.127)
		(layer "In5.Cu")
		(net "BMC_UART_SEL_OUT")
	)
	(segment
		(start 65.3796 -135.717534)
		(end 66.110866 -136.4488)
		(width 0.127)
		(layer "In5.Cu")
		(net "BMC_UART_SEL_OUT")
	)
	(segment
		(start 50.638456 -136.603994)
		(end 56.775604 -136.603994)
		(width 0.127)
		(layer "In5.Cu")
		(net "BMC_UART_SEL_OUT")
	)
	(segment
		(start 62.418214 -135.806434)
		(end 62.80785 -135.806434)
		(width 0.127)
		(layer "In5.Cu")
		(net "BMC_UART_SEL_OUT")
	)
	(segment
		(start 83.412076 -136.7155)
		(end 83.675474 -136.978898)
		(width 0.127)
		(layer "In5.Cu")
		(net "BMC_UART_SEL_OUT")
	)
	(segment
		(start 66.110866 -136.4488)
		(end 68.153788 -136.4488)
		(width 0.127)
		(layer "In5.Cu")
		(net "BMC_UART_SEL_OUT")
	)
	(segment
		(start 74.168 -136.4488)
		(end 77.47 -136.4488)
		(width 0.127)
		(layer "In5.Cu")
		(net "BMC_UART_SEL_OUT")
	)
	(segment
		(start 44.899834 -139.800076)
		(end 44.89958 -139.800076)
		(width 0.127)
		(layer "F.Cu")
		(net "BMC_UART_SEL_IN")
	)
	(segment
		(start 83.1215 -132.5245)
		(end 83.1215 -133.604)
		(width 0.127)
		(layer "F.Cu")
		(net "BMC_UART_SEL_IN")
	)
	(segment
		(start 82.8548 -132.2578)
		(end 83.1215 -132.5245)
		(width 0.127)
		(layer "F.Cu")
		(net "BMC_UART_SEL_IN")
	)
	(segment
		(start 80.3148 -132.2578)
		(end 81.788 -132.2578)
		(width 0.127)
		(layer "F.Cu")
		(net "BMC_UART_SEL_IN")
	)
	(segment
		(start 78.6384 -132.1181)
		(end 78.6384 -132.3086)
		(width 0.127)
		(layer "F.Cu")
		(net "BMC_UART_SEL_IN")
	)
	(segment
		(start 78.6384 -132.3086)
		(end 79.0956 -132.7658)
		(width 0.127)
		(layer "F.Cu")
		(net "BMC_UART_SEL_IN")
	)
	(segment
		(start 79.8068 -132.7658)
		(end 80.3148 -132.2578)
		(width 0.127)
		(layer "F.Cu")
		(net "BMC_UART_SEL_IN")
	)
	(segment
		(start 44.89958 -139.800076)
		(end 44.500038 -139.400534)
		(width 0.127)
		(layer "F.Cu")
		(net "BMC_UART_SEL_IN")
	)
	(segment
		(start 81.788 -132.2578)
		(end 82.8548 -132.2578)
		(width 0.127)
		(layer "F.Cu")
		(net "BMC_UART_SEL_IN")
	)
	(segment
		(start 79.0956 -132.7658)
		(end 79.8068 -132.7658)
		(width 0.127)
		(layer "F.Cu")
		(net "BMC_UART_SEL_IN")
	)
	(via
		(at 79.3242 -137.3124)
		(size 0.508)
		(drill 0.254)
		(layers "F.Cu" "B.Cu")
		(net "BMC_UART_SEL_IN")
	)
	(via
		(at 81.788 -132.2578)
		(size 0.6604)
		(drill 0.3302)
		(layers "F.Cu" "B.Cu")
		(net "BMC_UART_SEL_IN")
	)
	(via
		(at 78.6384 -132.1181)
		(size 0.508)
		(drill 0.254)
		(layers "F.Cu" "B.Cu")
		(net "BMC_UART_SEL_IN")
	)
	(via
		(at 44.500038 -139.400534)
		(size 0.4572)
		(drill 0.2032)
		(layers "F.Cu" "B.Cu")
		(net "BMC_UART_SEL_IN")
	)
	(segment
		(start 78.6003 -133.35762)
		(end 78.6003 -136.2329)
		(width 0.127)
		(layer "In2.Cu")
		(net "BMC_UART_SEL_IN")
	)
	(segment
		(start 78.6384 -133.31952)
		(end 78.6003 -133.35762)
		(width 0.127)
		(layer "In2.Cu")
		(net "BMC_UART_SEL_IN")
	)
	(segment
		(start 78.6003 -136.2329)
		(end 79.3242 -136.9568)
		(width 0.127)
		(layer "In2.Cu")
		(net "BMC_UART_SEL_IN")
	)
	(segment
		(start 79.3242 -136.9568)
		(end 79.3242 -137.3124)
		(width 0.127)
		(layer "In2.Cu")
		(net "BMC_UART_SEL_IN")
	)
	(segment
		(start 78.6384 -132.1181)
		(end 78.6384 -133.31952)
		(width 0.127)
		(layer "In2.Cu")
		(net "BMC_UART_SEL_IN")
	)
	(segment
		(start 67.9958 -136.8298)
		(end 69.5452 -138.3792)
		(width 0.127)
		(layer "In5.Cu")
		(net "BMC_UART_SEL_IN")
	)
	(segment
		(start 65.306448 -136.187434)
		(end 65.948814 -136.8298)
		(width 0.127)
		(layer "In5.Cu")
		(net "BMC_UART_SEL_IN")
	)
	(segment
		(start 57.051194 -136.651746)
		(end 58.448702 -136.651746)
		(width 0.127)
		(layer "In5.Cu")
		(net "BMC_UART_SEL_IN")
	)
	(segment
		(start 56.870346 -136.832594)
		(end 57.051194 -136.651746)
		(width 0.127)
		(layer "In5.Cu")
		(net "BMC_UART_SEL_IN")
	)
	(segment
		(start 72.7964 -138.3792)
		(end 74.2442 -136.9314)
		(width 0.127)
		(layer "In5.Cu")
		(net "BMC_UART_SEL_IN")
	)
	(segment
		(start 44.500038 -139.400534)
		(end 44.893738 -139.006834)
		(width 0.127)
		(layer "In5.Cu")
		(net "BMC_UART_SEL_IN")
	)
	(segment
		(start 69.5452 -138.3792)
		(end 72.7964 -138.3792)
		(width 0.127)
		(layer "In5.Cu")
		(net "BMC_UART_SEL_IN")
	)
	(segment
		(start 77.724 -137.3124)
		(end 79.3242 -137.3124)
		(width 0.127)
		(layer "In5.Cu")
		(net "BMC_UART_SEL_IN")
	)
	(segment
		(start 44.893738 -138.44905)
		(end 46.736508 -136.60628)
		(width 0.127)
		(layer "In5.Cu")
		(net "BMC_UART_SEL_IN")
	)
	(segment
		(start 62.054994 -136.187434)
		(end 65.306448 -136.187434)
		(width 0.127)
		(layer "In5.Cu")
		(net "BMC_UART_SEL_IN")
	)
	(segment
		(start 46.736508 -136.60628)
		(end 50.3174 -136.60628)
		(width 0.127)
		(layer "In5.Cu")
		(net "BMC_UART_SEL_IN")
	)
	(segment
		(start 50.3174 -136.60628)
		(end 50.543714 -136.832594)
		(width 0.127)
		(layer "In5.Cu")
		(net "BMC_UART_SEL_IN")
	)
	(segment
		(start 61.545978 -135.678418)
		(end 62.054994 -136.187434)
		(width 0.127)
		(layer "In5.Cu")
		(net "BMC_UART_SEL_IN")
	)
	(segment
		(start 44.893738 -139.006834)
		(end 44.893738 -138.44905)
		(width 0.127)
		(layer "In5.Cu")
		(net "BMC_UART_SEL_IN")
	)
	(segment
		(start 77.343 -136.9314)
		(end 77.724 -137.3124)
		(width 0.127)
		(layer "In5.Cu")
		(net "BMC_UART_SEL_IN")
	)
	(segment
		(start 65.948814 -136.8298)
		(end 67.9958 -136.8298)
		(width 0.127)
		(layer "In5.Cu")
		(net "BMC_UART_SEL_IN")
	)
	(segment
		(start 59.42203 -135.678418)
		(end 61.545978 -135.678418)
		(width 0.127)
		(layer "In5.Cu")
		(net "BMC_UART_SEL_IN")
	)
	(segment
		(start 50.543714 -136.832594)
		(end 56.870346 -136.832594)
		(width 0.127)
		(layer "In5.Cu")
		(net "BMC_UART_SEL_IN")
	)
	(segment
		(start 74.2442 -136.9314)
		(end 77.343 -136.9314)
		(width 0.127)
		(layer "In5.Cu")
		(net "BMC_UART_SEL_IN")
	)
	(segment
		(start 58.448702 -136.651746)
		(end 59.42203 -135.678418)
		(width 0.127)
		(layer "In5.Cu")
		(net "BMC_UART_SEL_IN")
	)
	(via
		(at 177.0634 -114.3508)
		(size 0.6096)
		(drill 0.3048)
		(layers "F.Cu" "B.Cu")
		(net "U83_VREF2")
	)
	(via
		(at 207.1624 -101.1682)
		(size 0.6096)
		(drill 0.3048)
		(layers "F.Cu" "B.Cu")
		(net "U82_VREF2")
	)
	(segment
		(start 64.9732 -137.0584)
		(end 64.9732 -137.5918)
		(width 0.127)
		(layer "F.Cu")
		(net "TP_BMC_GPIOA0")
	)
	(segment
		(start 56.926988 -142.5448)
		(end 55.755032 -142.5448)
		(width 0.127)
		(layer "F.Cu")
		(net "TP_BMC_GPIOA0")
	)
	(segment
		(start 57.05348 -142.428468)
		(end 57.04332 -142.428468)
		(width 0.127)
		(layer "F.Cu")
		(net "TP_BMC_GPIOA0")
	)
	(segment
		(start 61.555884 -138.723116)
		(end 61.0489 -139.2301)
		(width 0.127)
		(layer "F.Cu")
		(net "TP_BMC_GPIOA0")
	)
	(segment
		(start 59.31027 -139.729718)
		(end 59.228482 -139.729718)
		(width 0.127)
		(layer "F.Cu")
		(net "TP_BMC_GPIOA0")
	)
	(segment
		(start 57.04332 -142.428468)
		(end 56.926988 -142.5448)
		(width 0.127)
		(layer "F.Cu")
		(net "TP_BMC_GPIOA0")
	)
	(segment
		(start 64.9732 -137.5918)
		(end 64.313308 -138.251692)
		(width 0.127)
		(layer "F.Cu")
		(net "TP_BMC_GPIOA0")
	)
	(segment
		(start 59.809888 -139.2301)
		(end 59.31027 -139.729718)
		(width 0.127)
		(layer "F.Cu")
		(net "TP_BMC_GPIOA0")
	)
	(segment
		(start 55.755032 -142.5448)
		(end 55.299864 -142.999968)
		(width 0.127)
		(layer "F.Cu")
		(net "TP_BMC_GPIOA0")
	)
	(segment
		(start 63.841884 -138.723116)
		(end 61.555884 -138.723116)
		(width 0.127)
		(layer "F.Cu")
		(net "TP_BMC_GPIOA0")
	)
	(segment
		(start 61.0489 -139.2301)
		(end 59.809888 -139.2301)
		(width 0.127)
		(layer "F.Cu")
		(net "TP_BMC_GPIOA0")
	)
	(segment
		(start 59.228482 -139.729718)
		(end 58.948574 -140.009626)
		(width 0.127)
		(layer "F.Cu")
		(net "TP_BMC_GPIOA0")
	)
	(segment
		(start 58.948574 -140.533374)
		(end 57.05348 -142.428468)
		(width 0.127)
		(layer "F.Cu")
		(net "TP_BMC_GPIOA0")
	)
	(segment
		(start 64.313308 -138.251692)
		(end 63.841884 -138.723116)
		(width 0.127)
		(layer "F.Cu")
		(net "TP_BMC_GPIOA0")
	)
	(segment
		(start 58.948574 -140.009626)
		(end 58.948574 -140.533374)
		(width 0.127)
		(layer "F.Cu")
		(net "TP_BMC_GPIOA0")
	)
	(via
		(at 64.313308 -138.251692)
		(size 0.6604)
		(drill 0.3302)
		(layers "F.Cu" "B.Cu")
		(net "TP_BMC_GPIOA0")
	)
	(via
		(at 64.9732 -137.0584)
		(size 0.508)
		(drill 0.254)
		(layers "F.Cu" "B.Cu")
		(net "TP_BMC_GPIOA0")
	)
	(segment
		(start 63.7667 -136.1948)
		(end 64.7065 -136.1948)
		(width 0.127)
		(layer "B.Cu")
		(net "TP_BMC_GPIOA0")
	)
	(segment
		(start 64.7065 -136.1948)
		(end 64.8081 -136.0932)
		(width 0.127)
		(layer "B.Cu")
		(net "TP_BMC_GPIOA0")
	)
	(segment
		(start 64.9732 -137.0584)
		(end 64.9732 -136.2583)
		(width 0.127)
		(layer "B.Cu")
		(net "TP_BMC_GPIOA0")
	)
	(segment
		(start 64.9732 -136.2583)
		(end 64.8081 -136.0932)
		(width 0.127)
		(layer "B.Cu")
		(net "TP_BMC_GPIOA0")
	)
	(segment
		(start 65.4304 -138.0236)
		(end 65.4304 -137.5156)
		(width 0.127)
		(layer "B.Cu")
		(net "TP_BMC_GPIOA0")
	)
	(segment
		(start 65.4304 -137.5156)
		(end 64.9732 -137.0584)
		(width 0.127)
		(layer "B.Cu")
		(net "TP_BMC_GPIOA0")
	)
	(segment
		(start 65.36055 -150.68804)
		(end 65.28054 -150.76805)
		(width 0.127)
		(layer "F.Cu")
		(net "U30_Q1")
	)
	(segment
		(start 66.9798 -150.368)
		(end 67.9704 -150.368)
		(width 0.127)
		(layer "F.Cu")
		(net "U30_Q1")
	)
	(segment
		(start 66.30035 -150.68804)
		(end 65.36055 -150.68804)
		(width 0.127)
		(layer "F.Cu")
		(net "U30_Q1")
	)
	(segment
		(start 66.65976 -150.68804)
		(end 66.9798 -150.368)
		(width 0.127)
		(layer "F.Cu")
		(net "U30_Q1")
	)
	(segment
		(start 66.30035 -150.68804)
		(end 66.65976 -150.68804)
		(width 0.127)
		(layer "F.Cu")
		(net "U30_Q1")
	)
	(via
		(at 66.30035 -150.68804)
		(size 0.6604)
		(drill 0.3302)
		(layers "F.Cu" "B.Cu")
		(net "U30_Q1")
	)
	(segment
		(start 49.2379 -129.0066)
		(end 49.657 -128.5875)
		(width 0.127)
		(layer "F.Cu")
		(net "SCC_RMT_FULLPWR_EN")
	)
	(segment
		(start 48.643032 -130.198368)
		(end 49.2379 -129.6035)
		(width 0.127)
		(layer "F.Cu")
		(net "SCC_RMT_FULLPWR_EN")
	)
	(segment
		(start 49.2379 -129.6035)
		(end 49.2379 -129.0066)
		(width 0.127)
		(layer "F.Cu")
		(net "SCC_RMT_FULLPWR_EN")
	)
	(segment
		(start 49.299876 -139.40028)
		(end 49.299876 -139.444476)
		(width 0.127)
		(layer "F.Cu")
		(net "SCC_RMT_FULLPWR_EN")
	)
	(segment
		(start 49.299876 -139.444476)
		(end 49.655476 -139.800076)
		(width 0.127)
		(layer "F.Cu")
		(net "SCC_RMT_FULLPWR_EN")
	)
	(segment
		(start 49.655476 -139.800076)
		(end 49.699926 -139.800076)
		(width 0.127)
		(layer "F.Cu")
		(net "SCC_RMT_FULLPWR_EN")
	)
	(segment
		(start 48.495966 -130.198368)
		(end 48.643032 -130.198368)
		(width 0.127)
		(layer "F.Cu")
		(net "SCC_RMT_FULLPWR_EN")
	)
	(via
		(at 48.495966 -130.198368)
		(size 0.508)
		(drill 0.254)
		(layers "F.Cu" "B.Cu")
		(net "SCC_RMT_FULLPWR_EN")
	)
	(via
		(at 49.299876 -139.40028)
		(size 0.4572)
		(drill 0.2032)
		(layers "F.Cu" "B.Cu")
		(net "SCC_RMT_FULLPWR_EN")
	)
	(segment
		(start 49.0347 -136.1567)
		(end 49.693576 -136.815576)
		(width 0.127)
		(layer "In2.Cu")
		(net "SCC_RMT_FULLPWR_EN")
	)
	(segment
		(start 49.693576 -139.00658)
		(end 49.299876 -139.40028)
		(width 0.127)
		(layer "In2.Cu")
		(net "SCC_RMT_FULLPWR_EN")
	)
	(segment
		(start 48.495966 -131.981448)
		(end 49.0347 -132.520182)
		(width 0.127)
		(layer "In2.Cu")
		(net "SCC_RMT_FULLPWR_EN")
	)
	(segment
		(start 49.693576 -136.815576)
		(end 49.693576 -139.00658)
		(width 0.127)
		(layer "In2.Cu")
		(net "SCC_RMT_FULLPWR_EN")
	)
	(segment
		(start 49.0347 -132.520182)
		(end 49.0347 -136.1567)
		(width 0.127)
		(layer "In2.Cu")
		(net "SCC_RMT_FULLPWR_EN")
	)
	(segment
		(start 48.495966 -130.198368)
		(end 48.495966 -131.981448)
		(width 0.127)
		(layer "In2.Cu")
		(net "SCC_RMT_FULLPWR_EN")
	)
	(segment
		(start 49.699926 -138.999976)
		(end 49.299876 -138.599926)
		(width 0.127)
		(layer "F.Cu")
		(net "SCC_LOC_FULLPWR_EN")
	)
	(via
		(at 47.963836 -126.21768)
		(size 0.508)
		(drill 0.254)
		(layers "F.Cu" "B.Cu")
		(net "SCC_LOC_FULLPWR_EN")
	)
	(via
		(at 49.299876 -138.599926)
		(size 0.4572)
		(drill 0.2032)
		(layers "F.Cu" "B.Cu")
		(net "SCC_LOC_FULLPWR_EN")
	)
	(via
		(at 47.742856 -125.330204)
		(size 0.6096)
		(drill 0.3048)
		(layers "F.Cu" "B.Cu")
		(net "SCC_LOC_FULLPWR_EN")
	)
	(segment
		(start 48.8442 -125.3617)
		(end 47.774352 -125.3617)
		(width 0.127)
		(layer "B.Cu")
		(net "SCC_LOC_FULLPWR_EN")
	)
	(segment
		(start 47.742856 -125.9967)
		(end 47.963836 -126.21768)
		(width 0.127)
		(layer "B.Cu")
		(net "SCC_LOC_FULLPWR_EN")
	)
	(segment
		(start 47.774352 -125.3617)
		(end 47.742856 -125.330204)
		(width 0.127)
		(layer "B.Cu")
		(net "SCC_LOC_FULLPWR_EN")
	)
	(segment
		(start 47.742856 -125.330204)
		(end 47.742856 -125.9967)
		(width 0.127)
		(layer "B.Cu")
		(net "SCC_LOC_FULLPWR_EN")
	)
	(segment
		(start 47.963836 -126.21768)
		(end 47.9044 -126.277116)
		(width 0.127)
		(layer "In2.Cu")
		(net "SCC_LOC_FULLPWR_EN")
	)
	(segment
		(start 47.9044 -127.254)
		(end 48.006 -127.3556)
		(width 0.127)
		(layer "In2.Cu")
		(net "SCC_LOC_FULLPWR_EN")
	)
	(segment
		(start 48.4632 -134.1628)
		(end 48.4632 -136.3218)
		(width 0.127)
		(layer "In2.Cu")
		(net "SCC_LOC_FULLPWR_EN")
	)
	(segment
		(start 48.006 -132.736082)
		(end 48.0949 -132.824982)
		(width 0.127)
		(layer "In2.Cu")
		(net "SCC_LOC_FULLPWR_EN")
	)
	(segment
		(start 47.9044 -126.277116)
		(end 47.9044 -127.254)
		(width 0.127)
		(layer "In2.Cu")
		(net "SCC_LOC_FULLPWR_EN")
	)
	(segment
		(start 48.0949 -132.824982)
		(end 48.0949 -133.214618)
		(width 0.127)
		(layer "In2.Cu")
		(net "SCC_LOC_FULLPWR_EN")
	)
	(segment
		(start 48.006 -133.303518)
		(end 48.006 -133.7056)
		(width 0.127)
		(layer "In2.Cu")
		(net "SCC_LOC_FULLPWR_EN")
	)
	(segment
		(start 48.4632 -136.3218)
		(end 48.906176 -136.764776)
		(width 0.127)
		(layer "In2.Cu")
		(net "SCC_LOC_FULLPWR_EN")
	)
	(segment
		(start 48.906176 -138.206226)
		(end 49.299876 -138.599926)
		(width 0.127)
		(layer "In2.Cu")
		(net "SCC_LOC_FULLPWR_EN")
	)
	(segment
		(start 48.006 -127.3556)
		(end 48.006 -132.736082)
		(width 0.127)
		(layer "In2.Cu")
		(net "SCC_LOC_FULLPWR_EN")
	)
	(segment
		(start 48.006 -133.7056)
		(end 48.4632 -134.1628)
		(width 0.127)
		(layer "In2.Cu")
		(net "SCC_LOC_FULLPWR_EN")
	)
	(segment
		(start 48.906176 -136.764776)
		(end 48.906176 -138.206226)
		(width 0.127)
		(layer "In2.Cu")
		(net "SCC_LOC_FULLPWR_EN")
	)
	(segment
		(start 48.0949 -133.214618)
		(end 48.006 -133.303518)
		(width 0.127)
		(layer "In2.Cu")
		(net "SCC_LOC_FULLPWR_EN")
	)
	(via
		(at 135.878824 -15.9766)
		(size 0.6096)
		(drill 0.3048)
		(layers "F.Cu" "B.Cu")
		(net "IOM_MATED_N")
	)
	(via
		(at 135.255 -14.8844)
		(size 0.508)
		(drill 0.254)
		(layers "F.Cu" "B.Cu")
		(net "IOM_MATED_N")
	)
	(segment
		(start 135.878824 -17.460468)
		(end 134.715758 -17.460468)
		(width 0.127)
		(layer "B.Cu")
		(net "IOM_MATED_N")
	)
	(segment
		(start 135.878824 -17.460468)
		(end 135.878824 -15.9766)
		(width 0.127)
		(layer "B.Cu")
		(net "IOM_MATED_N")
	)
	(segment
		(start 135.878824 -15.508224)
		(end 135.255 -14.8844)
		(width 0.127)
		(layer "B.Cu")
		(net "IOM_MATED_N")
	)
	(segment
		(start 135.878824 -15.9766)
		(end 135.878824 -15.508224)
		(width 0.127)
		(layer "B.Cu")
		(net "IOM_MATED_N")
	)
	(segment
		(start 134.715758 -17.460468)
		(end 133.61035 -16.35506)
		(width 0.127)
		(layer "B.Cu")
		(net "IOM_MATED_N")
	)
	(segment
		(start 141.871446 -40.028622)
		(end 141.299946 -40.600122)
		(width 0.127)
		(layer "In2.Cu")
		(net "IOM_MATED_N")
	)
	(segment
		(start 141.871446 -29.454094)
		(end 141.871446 -40.028622)
		(width 0.127)
		(layer "In2.Cu")
		(net "IOM_MATED_N")
	)
	(segment
		(start 135.255 -14.8844)
		(end 134.318756 -15.820644)
		(width 0.127)
		(layer "In2.Cu")
		(net "IOM_MATED_N")
	)
	(segment
		(start 134.318756 -21.901404)
		(end 141.871446 -29.454094)
		(width 0.127)
		(layer "In2.Cu")
		(net "IOM_MATED_N")
	)
	(segment
		(start 134.318756 -15.820644)
		(end 134.318756 -21.901404)
		(width 0.127)
		(layer "In2.Cu")
		(net "IOM_MATED_N")
	)
	(via
		(at 116.22659 -17.78381)
		(size 0.6096)
		(drill 0.3048)
		(layers "F.Cu" "B.Cu")
		(net "IOM_ADM1278_EN")
	)
	(segment
		(start 115.6208 -11.15314)
		(end 116.74094 -10.033)
		(width 0.127)
		(layer "B.Cu")
		(net "IOM_ADM1278_EN")
	)
	(segment
		(start 119.041926 -20.5994)
		(end 130.6322 -20.5994)
		(width 0.127)
		(layer "B.Cu")
		(net "IOM_ADM1278_EN")
	)
	(segment
		(start 115.6208 -17.17802)
		(end 115.6208 -11.15314)
		(width 0.127)
		(layer "B.Cu")
		(net "IOM_ADM1278_EN")
	)
	(segment
		(start 116.22659 -17.78381)
		(end 115.6208 -17.17802)
		(width 0.127)
		(layer "B.Cu")
		(net "IOM_ADM1278_EN")
	)
	(segment
		(start 130.89382 -20.86102)
		(end 132.41782 -20.86102)
		(width 0.127)
		(layer "B.Cu")
		(net "IOM_ADM1278_EN")
	)
	(segment
		(start 132.6261 -19.53006)
		(end 132.42036 -19.7358)
		(width 0.127)
		(layer "B.Cu")
		(net "IOM_ADM1278_EN")
	)
	(segment
		(start 116.22659 -17.78381)
		(end 119.041926 -20.5994)
		(width 0.127)
		(layer "B.Cu")
		(net "IOM_ADM1278_EN")
	)
	(segment
		(start 132.6261 -18.26006)
		(end 132.6261 -19.53006)
		(width 0.127)
		(layer "B.Cu")
		(net "IOM_ADM1278_EN")
	)
	(segment
		(start 130.6322 -20.5994)
		(end 130.89382 -20.86102)
		(width 0.127)
		(layer "B.Cu")
		(net "IOM_ADM1278_EN")
	)
	(segment
		(start 116.74094 -10.033)
		(end 116.74094 -9.42086)
		(width 0.127)
		(layer "B.Cu")
		(net "IOM_ADM1278_EN")
	)
	(segment
		(start 132.42036 -19.7358)
		(end 132.42036 -20.85848)
		(width 0.127)
		(layer "B.Cu")
		(net "IOM_ADM1278_EN")
	)
	(segment
		(start 132.42036 -20.85848)
		(end 132.41782 -20.86102)
		(width 0.127)
		(layer "B.Cu")
		(net "IOM_ADM1278_EN")
	)
	(via
		(at 99.255326 -125.826266)
		(size 0.508)
		(drill 0.254)
		(layers "F.Cu" "B.Cu")
		(net "BMC_TO_EXP_RESET_N")
	)
	(via
		(at 79.2226 -129.921)
		(size 0.508)
		(drill 0.254)
		(layers "F.Cu" "B.Cu")
		(net "BMC_TO_EXP_RESET_N")
	)
	(segment
		(start 79.2226 -129.921)
		(end 79.51724 -129.62636)
		(width 0.127)
		(layer "B.Cu")
		(net "BMC_TO_EXP_RESET_N")
	)
	(segment
		(start 79.51724 -129.62636)
		(end 80.3529 -129.62636)
		(width 0.127)
		(layer "B.Cu")
		(net "BMC_TO_EXP_RESET_N")
	)
	(segment
		(start 99.255326 -125.085094)
		(end 98.2472 -124.076968)
		(width 0.127)
		(layer "In2.Cu")
		(net "BMC_TO_EXP_RESET_N")
	)
	(segment
		(start 104.280462 -40.651938)
		(end 104.280462 -31.416244)
		(width 0.127)
		(layer "In2.Cu")
		(net "BMC_TO_EXP_RESET_N")
	)
	(segment
		(start 104.280462 -31.416244)
		(end 106.51109 -29.185616)
		(width 0.127)
		(layer "In2.Cu")
		(net "BMC_TO_EXP_RESET_N")
	)
	(segment
		(start 98.2472 -124.076968)
		(end 98.2472 -120.4722)
		(width 0.127)
		(layer "In2.Cu")
		(net "BMC_TO_EXP_RESET_N")
	)
	(segment
		(start 99.06 -45.8724)
		(end 104.280462 -40.651938)
		(width 0.127)
		(layer "In2.Cu")
		(net "BMC_TO_EXP_RESET_N")
	)
	(segment
		(start 98.2472 -120.4722)
		(end 99.06 -119.6594)
		(width 0.127)
		(layer "In2.Cu")
		(net "BMC_TO_EXP_RESET_N")
	)
	(segment
		(start 112.671606 -29.185616)
		(end 114.8715 -31.38551)
		(width 0.127)
		(layer "In2.Cu")
		(net "BMC_TO_EXP_RESET_N")
	)
	(segment
		(start 106.51109 -29.185616)
		(end 112.671606 -29.185616)
		(width 0.127)
		(layer "In2.Cu")
		(net "BMC_TO_EXP_RESET_N")
	)
	(segment
		(start 114.8715 -42.97172)
		(end 116.099844 -44.200064)
		(width 0.127)
		(layer "In2.Cu")
		(net "BMC_TO_EXP_RESET_N")
	)
	(segment
		(start 114.8715 -31.38551)
		(end 114.8715 -42.97172)
		(width 0.127)
		(layer "In2.Cu")
		(net "BMC_TO_EXP_RESET_N")
	)
	(segment
		(start 99.255326 -125.826266)
		(end 99.255326 -125.085094)
		(width 0.127)
		(layer "In2.Cu")
		(net "BMC_TO_EXP_RESET_N")
	)
	(segment
		(start 99.06 -119.6594)
		(end 99.06 -45.8724)
		(width 0.127)
		(layer "In2.Cu")
		(net "BMC_TO_EXP_RESET_N")
	)
	(segment
		(start 79.2226 -129.921)
		(end 79.5782 -130.2766)
		(width 0.127)
		(layer "In5.Cu")
		(net "BMC_TO_EXP_RESET_N")
	)
	(segment
		(start 87.9856 -128.3462)
		(end 89.816432 -126.515368)
		(width 0.127)
		(layer "In5.Cu")
		(net "BMC_TO_EXP_RESET_N")
	)
	(segment
		(start 89.816432 -126.515368)
		(end 93.387418 -126.515368)
		(width 0.127)
		(layer "In5.Cu")
		(net "BMC_TO_EXP_RESET_N")
	)
	(segment
		(start 84.004912 -129.9718)
		(end 85.7758 -129.9718)
		(width 0.127)
		(layer "In5.Cu")
		(net "BMC_TO_EXP_RESET_N")
	)
	(segment
		(start 97.630996 -127.450596)
		(end 99.255326 -125.826266)
		(width 0.127)
		(layer "In5.Cu")
		(net "BMC_TO_EXP_RESET_N")
	)
	(segment
		(start 85.7758 -129.9718)
		(end 87.4014 -128.3462)
		(width 0.127)
		(layer "In5.Cu")
		(net "BMC_TO_EXP_RESET_N")
	)
	(segment
		(start 83.700112 -130.2766)
		(end 84.004912 -129.9718)
		(width 0.127)
		(layer "In5.Cu")
		(net "BMC_TO_EXP_RESET_N")
	)
	(segment
		(start 94.322646 -127.450596)
		(end 97.630996 -127.450596)
		(width 0.127)
		(layer "In5.Cu")
		(net "BMC_TO_EXP_RESET_N")
	)
	(segment
		(start 87.4014 -128.3462)
		(end 87.9856 -128.3462)
		(width 0.127)
		(layer "In5.Cu")
		(net "BMC_TO_EXP_RESET_N")
	)
	(segment
		(start 93.387418 -126.515368)
		(end 94.322646 -127.450596)
		(width 0.127)
		(layer "In5.Cu")
		(net "BMC_TO_EXP_RESET_N")
	)
	(segment
		(start 79.5782 -130.2766)
		(end 83.700112 -130.2766)
		(width 0.127)
		(layer "In5.Cu")
		(net "BMC_TO_EXP_RESET_N")
	)
	(segment
		(start 44.099988 -151.800306)
		(end 43.700192 -152.200102)
		(width 0.127)
		(layer "F.Cu")
		(net "IOM_TYPE3")
	)
	(segment
		(start 44.099988 -151.800052)
		(end 44.099988 -151.800306)
		(width 0.127)
		(layer "F.Cu")
		(net "IOM_TYPE3")
	)
	(via
		(at 44.004738 -154.178)
		(size 0.6096)
		(drill 0.3048)
		(layers "F.Cu" "B.Cu")
		(net "IOM_TYPE3")
	)
	(via
		(at 43.700192 -152.200102)
		(size 0.4572)
		(drill 0.2032)
		(layers "F.Cu" "B.Cu")
		(net "IOM_TYPE3")
	)
	(segment
		(start 43.333416 -156.285184)
		(end 43.333416 -156.68752)
		(width 0.127)
		(layer "B.Cu")
		(net "IOM_TYPE3")
	)
	(segment
		(start 44.069 -152.56891)
		(end 43.700192 -152.200102)
		(width 0.127)
		(layer "B.Cu")
		(net "IOM_TYPE3")
	)
	(segment
		(start 44.069 -154.113738)
		(end 44.069 -152.56891)
		(width 0.127)
		(layer "B.Cu")
		(net "IOM_TYPE3")
	)
	(segment
		(start 43.333416 -156.68752)
		(end 41.829736 -158.1912)
		(width 0.127)
		(layer "B.Cu")
		(net "IOM_TYPE3")
	)
	(segment
		(start 43.8023 -155.8163)
		(end 43.333416 -156.285184)
		(width 0.127)
		(layer "B.Cu")
		(net "IOM_TYPE3")
	)
	(segment
		(start 38.1381 -158.1912)
		(end 37.4777 -157.5308)
		(width 0.127)
		(layer "B.Cu")
		(net "IOM_TYPE3")
	)
	(segment
		(start 44.004738 -154.178)
		(end 44.069 -154.113738)
		(width 0.127)
		(layer "B.Cu")
		(net "IOM_TYPE3")
	)
	(segment
		(start 44.004738 -154.178)
		(end 43.8023 -154.380438)
		(width 0.127)
		(layer "B.Cu")
		(net "IOM_TYPE3")
	)
	(segment
		(start 36.3855 -157.5308)
		(end 37.4777 -157.5308)
		(width 0.127)
		(layer "B.Cu")
		(net "IOM_TYPE3")
	)
	(segment
		(start 41.829736 -158.1912)
		(end 38.1381 -158.1912)
		(width 0.127)
		(layer "B.Cu")
		(net "IOM_TYPE3")
	)
	(segment
		(start 43.8023 -154.380438)
		(end 43.8023 -155.8163)
		(width 0.127)
		(layer "B.Cu")
		(net "IOM_TYPE3")
	)
	(segment
		(start 44.899834 -151.800306)
		(end 44.500038 -152.200102)
		(width 0.127)
		(layer "F.Cu")
		(net "IOM_TYPE2")
	)
	(segment
		(start 44.899834 -151.800052)
		(end 44.899834 -151.800306)
		(width 0.127)
		(layer "F.Cu")
		(net "IOM_TYPE2")
	)
	(via
		(at 41.275 -158.7119)
		(size 0.6096)
		(drill 0.3048)
		(layers "F.Cu" "B.Cu")
		(net "IOM_TYPE2")
	)
	(via
		(at 44.500038 -152.200102)
		(size 0.4572)
		(drill 0.2032)
		(layers "F.Cu" "B.Cu")
		(net "IOM_TYPE2")
	)
	(segment
		(start 43.714416 -156.300932)
		(end 44.500038 -155.51531)
		(width 0.127)
		(layer "B.Cu")
		(net "IOM_TYPE2")
	)
	(segment
		(start 34.158682 -159.0802)
		(end 32.9311 -159.0802)
		(width 0.127)
		(layer "B.Cu")
		(net "IOM_TYPE2")
	)
	(segment
		(start 36.6395 -158.7119)
		(end 36.1696 -159.1818)
		(width 0.127)
		(layer "B.Cu")
		(net "IOM_TYPE2")
	)
	(segment
		(start 43.714416 -156.845508)
		(end 43.714416 -156.300932)
		(width 0.127)
		(layer "B.Cu")
		(net "IOM_TYPE2")
	)
	(segment
		(start 44.500038 -155.51531)
		(end 44.500038 -152.200102)
		(width 0.127)
		(layer "B.Cu")
		(net "IOM_TYPE2")
	)
	(segment
		(start 41.848024 -158.7119)
		(end 43.714416 -156.845508)
		(width 0.127)
		(layer "B.Cu")
		(net "IOM_TYPE2")
	)
	(segment
		(start 41.275 -158.7119)
		(end 41.848024 -158.7119)
		(width 0.127)
		(layer "B.Cu")
		(net "IOM_TYPE2")
	)
	(segment
		(start 36.1696 -159.1818)
		(end 34.260282 -159.1818)
		(width 0.127)
		(layer "B.Cu")
		(net "IOM_TYPE2")
	)
	(segment
		(start 41.275 -158.7119)
		(end 36.6395 -158.7119)
		(width 0.127)
		(layer "B.Cu")
		(net "IOM_TYPE2")
	)
	(segment
		(start 34.260282 -159.1818)
		(end 34.158682 -159.0802)
		(width 0.127)
		(layer "B.Cu")
		(net "IOM_TYPE2")
	)
	(segment
		(start 32.9311 -160.1724)
		(end 32.9311 -159.0802)
		(width 0.127)
		(layer "B.Cu")
		(net "IOM_TYPE2")
	)
	(segment
		(start 32.9819 -160.2232)
		(end 32.9311 -160.1724)
		(width 0.127)
		(layer "B.Cu")
		(net "IOM_TYPE2")
	)
	(segment
		(start 44.899834 -151.000206)
		(end 44.500038 -151.400002)
		(width 0.127)
		(layer "F.Cu")
		(net "IOM_TYPE1")
	)
	(segment
		(start 44.899834 -150.999952)
		(end 44.899834 -151.000206)
		(width 0.127)
		(layer "F.Cu")
		(net "IOM_TYPE1")
	)
	(via
		(at 34.125916 -160.590484)
		(size 0.6096)
		(drill 0.3048)
		(layers "F.Cu" "B.Cu")
		(net "IOM_TYPE1")
	)
	(via
		(at 44.500038 -151.400002)
		(size 0.4572)
		(drill 0.2032)
		(layers "F.Cu" "B.Cu")
		(net "IOM_TYPE1")
	)
	(segment
		(start 44.906438 -151.806402)
		(end 44.906438 -155.683712)
		(width 0.127)
		(layer "B.Cu")
		(net "IOM_TYPE1")
	)
	(segment
		(start 44.906438 -155.683712)
		(end 44.120816 -156.469334)
		(width 0.127)
		(layer "B.Cu")
		(net "IOM_TYPE1")
	)
	(segment
		(start 44.500038 -151.400002)
		(end 44.906438 -151.806402)
		(width 0.127)
		(layer "B.Cu")
		(net "IOM_TYPE1")
	)
	(segment
		(start 33.4518 -161.2646)
		(end 32.9819 -161.2646)
		(width 0.127)
		(layer "B.Cu")
		(net "IOM_TYPE1")
	)
	(segment
		(start 44.120816 -156.469334)
		(end 44.120816 -156.978096)
		(width 0.127)
		(layer "B.Cu")
		(net "IOM_TYPE1")
	)
	(segment
		(start 34.798 -159.9184)
		(end 34.125916 -160.590484)
		(width 0.127)
		(layer "B.Cu")
		(net "IOM_TYPE1")
	)
	(segment
		(start 36.195 -159.9184)
		(end 34.798 -159.9184)
		(width 0.127)
		(layer "B.Cu")
		(net "IOM_TYPE1")
	)
	(segment
		(start 41.840912 -159.258)
		(end 36.8554 -159.258)
		(width 0.127)
		(layer "B.Cu")
		(net "IOM_TYPE1")
	)
	(segment
		(start 32.9819 -162.306)
		(end 32.9819 -161.2646)
		(width 0.127)
		(layer "B.Cu")
		(net "IOM_TYPE1")
	)
	(segment
		(start 34.125916 -160.590484)
		(end 33.4518 -161.2646)
		(width 0.127)
		(layer "B.Cu")
		(net "IOM_TYPE1")
	)
	(segment
		(start 44.120816 -156.978096)
		(end 41.840912 -159.258)
		(width 0.127)
		(layer "B.Cu")
		(net "IOM_TYPE1")
	)
	(segment
		(start 36.8554 -159.258)
		(end 36.195 -159.9184)
		(width 0.127)
		(layer "B.Cu")
		(net "IOM_TYPE1")
	)
	(segment
		(start 46.500034 -150.199852)
		(end 46.471078 -150.199852)
		(width 0.127)
		(layer "F.Cu")
		(net "IOM_TYPE0")
	)
	(segment
		(start 46.471078 -150.199852)
		(end 46.10862 -150.56231)
		(width 0.127)
		(layer "F.Cu")
		(net "IOM_TYPE0")
	)
	(via
		(at 46.10862 -150.56231)
		(size 0.4572)
		(drill 0.2032)
		(layers "F.Cu" "B.Cu")
		(net "IOM_TYPE0")
	)
	(via
		(at 39.6113 -150.37054)
		(size 0.6096)
		(drill 0.3048)
		(layers "F.Cu" "B.Cu")
		(net "IOM_TYPE0")
	)
	(segment
		(start 38.5445 -149.987)
		(end 38.94074 -149.987)
		(width 0.127)
		(layer "B.Cu")
		(net "IOM_TYPE0")
	)
	(segment
		(start 40.133016 -150.37054)
		(end 39.6113 -150.37054)
		(width 0.127)
		(layer "B.Cu")
		(net "IOM_TYPE0")
	)
	(segment
		(start 39.32428 -150.37054)
		(end 39.6113 -150.37054)
		(width 0.127)
		(layer "B.Cu")
		(net "IOM_TYPE0")
	)
	(segment
		(start 46.47819 -150.56231)
		(end 46.9138 -150.1267)
		(width 0.127)
		(layer "B.Cu")
		(net "IOM_TYPE0")
	)
	(segment
		(start 45.39361 -150.193756)
		(end 40.3098 -150.193756)
		(width 0.127)
		(layer "B.Cu")
		(net "IOM_TYPE0")
	)
	(segment
		(start 45.762164 -150.56231)
		(end 45.39361 -150.193756)
		(width 0.127)
		(layer "B.Cu")
		(net "IOM_TYPE0")
	)
	(segment
		(start 40.3098 -150.193756)
		(end 40.133016 -150.37054)
		(width 0.127)
		(layer "B.Cu")
		(net "IOM_TYPE0")
	)
	(segment
		(start 46.10862 -150.56231)
		(end 45.762164 -150.56231)
		(width 0.127)
		(layer "B.Cu")
		(net "IOM_TYPE0")
	)
	(segment
		(start 38.94074 -149.987)
		(end 39.32428 -150.37054)
		(width 0.127)
		(layer "B.Cu")
		(net "IOM_TYPE0")
	)
	(segment
		(start 46.10862 -150.56231)
		(end 46.47819 -150.56231)
		(width 0.127)
		(layer "B.Cu")
		(net "IOM_TYPE0")
	)
	(segment
		(start 70.5104 -169.0624)
		(end 70.231 -169.0624)
		(width 0.127)
		(layer "F.Cu")
		(net "BMC_SELF_HW_RST_D")
	)
	(segment
		(start 62.439042 -167.595042)
		(end 61.244734 -166.400734)
		(width 0.127)
		(layer "F.Cu")
		(net "BMC_SELF_HW_RST_D")
	)
	(segment
		(start 70.231 -169.0624)
		(end 69.4944 -168.3258)
		(width 0.127)
		(layer "F.Cu")
		(net "BMC_SELF_HW_RST_D")
	)
	(segment
		(start 67.6656 -168.8592)
		(end 67.8434 -169.037)
		(width 0.127)
		(layer "F.Cu")
		(net "BMC_SELF_HW_RST_D")
	)
	(segment
		(start 67.8434 -169.037)
		(end 67.8434 -169.7482)
		(width 0.127)
		(layer "F.Cu")
		(net "BMC_SELF_HW_RST_D")
	)
	(segment
		(start 67.6656 -168.1988)
		(end 67.061842 -167.595042)
		(width 0.127)
		(layer "F.Cu")
		(net "BMC_SELF_HW_RST_D")
	)
	(segment
		(start 69.4944 -168.3258)
		(end 68.6054 -168.3258)
		(width 0.127)
		(layer "F.Cu")
		(net "BMC_SELF_HW_RST_D")
	)
	(segment
		(start 68.4784 -168.1988)
		(end 67.6656 -168.1988)
		(width 0.127)
		(layer "F.Cu")
		(net "BMC_SELF_HW_RST_D")
	)
	(segment
		(start 68.6054 -168.3258)
		(end 68.4784 -168.1988)
		(width 0.127)
		(layer "F.Cu")
		(net "BMC_SELF_HW_RST_D")
	)
	(segment
		(start 67.6656 -168.1988)
		(end 67.6656 -168.8592)
		(width 0.127)
		(layer "F.Cu")
		(net "BMC_SELF_HW_RST_D")
	)
	(segment
		(start 61.244734 -166.400734)
		(end 60.656978 -166.400734)
		(width 0.127)
		(layer "F.Cu")
		(net "BMC_SELF_HW_RST_D")
	)
	(segment
		(start 67.061842 -167.595042)
		(end 62.439042 -167.595042)
		(width 0.127)
		(layer "F.Cu")
		(net "BMC_SELF_HW_RST_D")
	)
	(via
		(at 68.6054 -168.3258)
		(size 0.6604)
		(drill 0.3302)
		(layers "F.Cu" "B.Cu")
		(net "BMC_SELF_HW_RST_D")
	)
	(via
		(at 67.6656 -168.1988)
		(size 0.508)
		(drill 0.254)
		(layers "F.Cu" "B.Cu")
		(net "BMC_SELF_HW_RST_D")
	)
	(segment
		(start 67.624452 -168.239948)
		(end 67.6656 -168.1988)
		(width 0.127)
		(layer "B.Cu")
		(net "BMC_SELF_HW_RST_D")
	)
	(segment
		(start 67.624452 -169.155618)
		(end 67.624452 -168.239948)
		(width 0.127)
		(layer "B.Cu")
		(net "BMC_SELF_HW_RST_D")
	)
	(segment
		(start 67.751452 -169.282618)
		(end 67.624452 -169.155618)
		(width 0.127)
		(layer "B.Cu")
		(net "BMC_SELF_HW_RST_D")
	)
	(via
		(at 154.748738 -16.054578)
		(size 0.6604)
		(drill 0.3302)
		(layers "F.Cu" "B.Cu")
		(net "P12V_STBY_VIN_PU4")
	)
	(segment
		(start 218.992958 -101.187504)
		(end 218.816936 -101.363526)
		(width 0.254)
		(layer "F.Cu")
		(net "P12V_STBY_VDD_U81")
	)
	(segment
		(start 218.992958 -99.832668)
		(end 218.992958 -101.187504)
		(width 0.254)
		(layer "F.Cu")
		(net "P12V_STBY_VDD_U81")
	)
	(via
		(at 218.816936 -101.363526)
		(size 0.508)
		(drill 0.254)
		(layers "F.Cu" "B.Cu")
		(net "P12V_STBY_VDD_U81")
	)
	(via
		(at 218.541092 -100.284026)
		(size 0.6096)
		(drill 0.3048)
		(layers "F.Cu" "B.Cu")
		(net "P12V_STBY_VDD_U81")
	)
	(segment
		(start 219.127324 -99.738434)
		(end 219.086684 -99.738434)
		(width 0.254)
		(layer "B.Cu")
		(net "P12V_STBY_VDD_U81")
	)
	(segment
		(start 218.541092 -101.087682)
		(end 218.816936 -101.363526)
		(width 0.254)
		(layer "B.Cu")
		(net "P12V_STBY_VDD_U81")
	)
	(segment
		(start 220.101414 -99.716844)
		(end 219.148914 -99.716844)
		(width 0.254)
		(layer "B.Cu")
		(net "P12V_STBY_VDD_U81")
	)
	(segment
		(start 218.541092 -100.284026)
		(end 218.541092 -101.087682)
		(width 0.254)
		(layer "B.Cu")
		(net "P12V_STBY_VDD_U81")
	)
	(segment
		(start 221.42323 -99.716844)
		(end 221.690692 -99.449382)
		(width 0.254)
		(layer "B.Cu")
		(net "P12V_STBY_VDD_U81")
	)
	(segment
		(start 220.101414 -99.716844)
		(end 221.42323 -99.716844)
		(width 0.254)
		(layer "B.Cu")
		(net "P12V_STBY_VDD_U81")
	)
	(segment
		(start 219.086684 -99.738434)
		(end 218.541092 -100.284026)
		(width 0.254)
		(layer "B.Cu")
		(net "P12V_STBY_VDD_U81")
	)
	(segment
		(start 219.148914 -99.716844)
		(end 219.127324 -99.738434)
		(width 0.254)
		(layer "B.Cu")
		(net "P12V_STBY_VDD_U81")
	)
	(segment
		(start 31.845504 -180.570632)
		(end 30.744668 -180.570632)
		(width 0.254)
		(layer "F.Cu")
		(net "P12V_STBY_VDD_PU2")
	)
	(segment
		(start 30.744668 -180.570632)
		(end 30.441646 -180.26761)
		(width 0.254)
		(layer "F.Cu")
		(net "P12V_STBY_VDD_PU2")
	)
	(via
		(at 27.807412 -181.16423)
		(size 0.6096)
		(drill 0.3048)
		(layers "F.Cu" "B.Cu")
		(net "P12V_STBY_VDD_PU2")
	)
	(via
		(at 30.441646 -180.26761)
		(size 0.508)
		(drill 0.254)
		(layers "F.Cu" "B.Cu")
		(net "P12V_STBY_VDD_PU2")
	)
	(segment
		(start 26.35123 -181.16423)
		(end 27.807412 -181.16423)
		(width 0.254)
		(layer "B.Cu")
		(net "P12V_STBY_VDD_PU2")
	)
	(segment
		(start 25.4254 -179.2478)
		(end 25.4254 -180.2384)
		(width 0.254)
		(layer "B.Cu")
		(net "P12V_STBY_VDD_PU2")
	)
	(segment
		(start 26.0858 -180.8988)
		(end 26.35123 -181.16423)
		(width 0.254)
		(layer "B.Cu")
		(net "P12V_STBY_VDD_PU2")
	)
	(segment
		(start 25.4254 -180.2384)
		(end 26.0858 -180.8988)
		(width 0.254)
		(layer "B.Cu")
		(net "P12V_STBY_VDD_PU2")
	)
	(segment
		(start 29.545026 -181.16423)
		(end 30.441646 -180.26761)
		(width 0.254)
		(layer "B.Cu")
		(net "P12V_STBY_VDD_PU2")
	)
	(segment
		(start 27.807412 -181.16423)
		(end 29.545026 -181.16423)
		(width 0.254)
		(layer "B.Cu")
		(net "P12V_STBY_VDD_PU2")
	)
	(segment
		(start 52.499768 -140.200126)
		(end 52.099972 -140.599922)
		(width 0.127)
		(layer "F.Cu")
		(net "M2_2_ACTIVE_N")
	)
	(segment
		(start 167.570912 -130.79984)
		(end 166.910512 -131.46024)
		(width 0.127)
		(layer "F.Cu")
		(net "M2_2_ACTIVE_N")
	)
	(segment
		(start 52.500022 -140.200126)
		(end 52.499768 -140.200126)
		(width 0.127)
		(layer "F.Cu")
		(net "M2_2_ACTIVE_N")
	)
	(segment
		(start 170.82516 -130.79984)
		(end 167.570912 -130.79984)
		(width 0.127)
		(layer "F.Cu")
		(net "M2_2_ACTIVE_N")
	)
	(segment
		(start 172.39996 -129.22504)
		(end 170.82516 -130.79984)
		(width 0.127)
		(layer "F.Cu")
		(net "M2_2_ACTIVE_N")
	)
	(segment
		(start 172.39996 -127.324866)
		(end 172.39996 -129.22504)
		(width 0.127)
		(layer "F.Cu")
		(net "M2_2_ACTIVE_N")
	)
	(via
		(at 58.57494 -112.78997)
		(size 0.508)
		(drill 0.254)
		(layers "F.Cu" "B.Cu")
		(net "M2_2_ACTIVE_N")
	)
	(via
		(at 172.39996 -129.22504)
		(size 0.508)
		(drill 0.254)
		(layers "F.Cu" "B.Cu")
		(net "M2_2_ACTIVE_N")
	)
	(via
		(at 52.500022 -140.200126)
		(size 0.4572)
		(drill 0.2032)
		(layers "F.Cu" "B.Cu")
		(net "M2_2_ACTIVE_N")
	)
	(via
		(at 74.85888 -47.1424)
		(size 0.508)
		(drill 0.254)
		(layers "F.Cu" "B.Cu")
		(net "M2_2_ACTIVE_N")
	)
	(via
		(at 62.4332 -112.6744)
		(size 0.6096)
		(drill 0.3048)
		(layers "F.Cu" "B.Cu")
		(net "M2_2_ACTIVE_N")
	)
	(segment
		(start 62.2046 -112.903)
		(end 58.68797 -112.903)
		(width 0.127)
		(layer "B.Cu")
		(net "M2_2_ACTIVE_N")
	)
	(segment
		(start 74.61758 -47.3837)
		(end 74.61758 -96.831404)
		(width 0.127)
		(layer "B.Cu")
		(net "M2_2_ACTIVE_N")
	)
	(segment
		(start 84.258658 -102.179882)
		(end 84.258658 -108.10367)
		(width 0.127)
		(layer "B.Cu")
		(net "M2_2_ACTIVE_N")
	)
	(segment
		(start 74.266044 -111.80318)
		(end 67.09918 -111.80318)
		(width 0.127)
		(layer "B.Cu")
		(net "M2_2_ACTIVE_N")
	)
	(segment
		(start 82.129376 -100.0506)
		(end 84.258658 -102.179882)
		(width 0.127)
		(layer "B.Cu")
		(net "M2_2_ACTIVE_N")
	)
	(segment
		(start 75.18781 -110.881414)
		(end 74.266044 -111.80318)
		(width 0.127)
		(layer "B.Cu")
		(net "M2_2_ACTIVE_N")
	)
	(segment
		(start 80.827626 -99.450144)
		(end 81.428082 -100.0506)
		(width 0.127)
		(layer "B.Cu")
		(net "M2_2_ACTIVE_N")
	)
	(segment
		(start 82.175858 -109.73054)
		(end 81.848198 -110.0582)
		(width 0.127)
		(layer "B.Cu")
		(net "M2_2_ACTIVE_N")
	)
	(segment
		(start 77.23632 -99.450144)
		(end 80.827626 -99.450144)
		(width 0.127)
		(layer "B.Cu")
		(net "M2_2_ACTIVE_N")
	)
	(segment
		(start 58.68797 -112.903)
		(end 58.57494 -112.78997)
		(width 0.127)
		(layer "B.Cu")
		(net "M2_2_ACTIVE_N")
	)
	(segment
		(start 82.631788 -109.73054)
		(end 82.175858 -109.73054)
		(width 0.127)
		(layer "B.Cu")
		(net "M2_2_ACTIVE_N")
	)
	(segment
		(start 66.22796 -112.6744)
		(end 62.4332 -112.6744)
		(width 0.127)
		(layer "B.Cu")
		(net "M2_2_ACTIVE_N")
	)
	(segment
		(start 84.258658 -108.10367)
		(end 82.631788 -109.73054)
		(width 0.127)
		(layer "B.Cu")
		(net "M2_2_ACTIVE_N")
	)
	(segment
		(start 74.61758 -96.831404)
		(end 77.23632 -99.450144)
		(width 0.127)
		(layer "B.Cu")
		(net "M2_2_ACTIVE_N")
	)
	(segment
		(start 81.428082 -100.0506)
		(end 82.129376 -100.0506)
		(width 0.127)
		(layer "B.Cu")
		(net "M2_2_ACTIVE_N")
	)
	(segment
		(start 80.53578 -110.881414)
		(end 75.18781 -110.881414)
		(width 0.127)
		(layer "B.Cu")
		(net "M2_2_ACTIVE_N")
	)
	(segment
		(start 74.85888 -47.1424)
		(end 74.61758 -47.3837)
		(width 0.127)
		(layer "B.Cu")
		(net "M2_2_ACTIVE_N")
	)
	(segment
		(start 62.4332 -112.6744)
		(end 62.2046 -112.903)
		(width 0.127)
		(layer "B.Cu")
		(net "M2_2_ACTIVE_N")
	)
	(segment
		(start 81.848198 -110.0582)
		(end 81.358994 -110.0582)
		(width 0.127)
		(layer "B.Cu")
		(net "M2_2_ACTIVE_N")
	)
	(segment
		(start 81.358994 -110.0582)
		(end 80.53578 -110.881414)
		(width 0.127)
		(layer "B.Cu")
		(net "M2_2_ACTIVE_N")
	)
	(segment
		(start 67.09918 -111.80318)
		(end 66.22796 -112.6744)
		(width 0.127)
		(layer "B.Cu")
		(net "M2_2_ACTIVE_N")
	)
	(segment
		(start 58.1914 -114.621056)
		(end 56.034178 -116.778278)
		(width 0.127)
		(layer "In2.Cu")
		(net "M2_2_ACTIVE_N")
	)
	(segment
		(start 56.034178 -120.495822)
		(end 55.0672 -121.4628)
		(width 0.127)
		(layer "In2.Cu")
		(net "M2_2_ACTIVE_N")
	)
	(segment
		(start 53.706014 -135.981186)
		(end 53.706014 -139.550902)
		(width 0.127)
		(layer "In2.Cu")
		(net "M2_2_ACTIVE_N")
	)
	(segment
		(start 58.1914 -113.17351)
		(end 58.1914 -114.621056)
		(width 0.127)
		(layer "In2.Cu")
		(net "M2_2_ACTIVE_N")
	)
	(segment
		(start 56.034178 -116.778278)
		(end 56.034178 -120.495822)
		(width 0.127)
		(layer "In2.Cu")
		(net "M2_2_ACTIVE_N")
	)
	(segment
		(start 53.45049 -139.806426)
		(end 53.136546 -139.806426)
		(width 0.127)
		(layer "In2.Cu")
		(net "M2_2_ACTIVE_N")
	)
	(segment
		(start 54.356 -132.08)
		(end 54.356 -135.3312)
		(width 0.127)
		(layer "In2.Cu")
		(net "M2_2_ACTIVE_N")
	)
	(segment
		(start 55.0672 -121.4628)
		(end 55.0672 -131.3688)
		(width 0.127)
		(layer "In2.Cu")
		(net "M2_2_ACTIVE_N")
	)
	(segment
		(start 54.356 -135.3312)
		(end 53.706014 -135.981186)
		(width 0.127)
		(layer "In2.Cu")
		(net "M2_2_ACTIVE_N")
	)
	(segment
		(start 52.742846 -140.200126)
		(end 52.500022 -140.200126)
		(width 0.127)
		(layer "In2.Cu")
		(net "M2_2_ACTIVE_N")
	)
	(segment
		(start 58.57494 -112.78997)
		(end 58.1914 -113.17351)
		(width 0.127)
		(layer "In2.Cu")
		(net "M2_2_ACTIVE_N")
	)
	(segment
		(start 53.706014 -139.550902)
		(end 53.45049 -139.806426)
		(width 0.127)
		(layer "In2.Cu")
		(net "M2_2_ACTIVE_N")
	)
	(segment
		(start 53.136546 -139.806426)
		(end 52.742846 -140.200126)
		(width 0.127)
		(layer "In2.Cu")
		(net "M2_2_ACTIVE_N")
	)
	(segment
		(start 55.0672 -131.3688)
		(end 54.356 -132.08)
		(width 0.127)
		(layer "In2.Cu")
		(net "M2_2_ACTIVE_N")
	)
	(segment
		(start 75.869292 -44.200572)
		(end 75.869292 -37.478208)
		(width 0.127)
		(layer "In5.Cu")
		(net "M2_2_ACTIVE_N")
	)
	(segment
		(start 213.400386 -89.531952)
		(end 213.400386 -117.028976)
		(width 0.127)
		(layer "In5.Cu")
		(net "M2_2_ACTIVE_N")
	)
	(segment
		(start 92.28201 -6.870192)
		(end 96.701356 -2.450846)
		(width 0.127)
		(layer "In5.Cu")
		(net "M2_2_ACTIVE_N")
	)
	(segment
		(start 174.2948 -127.3302)
		(end 172.39996 -129.22504)
		(width 0.127)
		(layer "In5.Cu")
		(net "M2_2_ACTIVE_N")
	)
	(segment
		(start 75.6412 -44.428664)
		(end 75.869292 -44.200572)
		(width 0.127)
		(layer "In5.Cu")
		(net "M2_2_ACTIVE_N")
	)
	(segment
		(start 97.964498 -2.4511)
		(end 175.052228 -2.4511)
		(width 0.127)
		(layer "In5.Cu")
		(net "M2_2_ACTIVE_N")
	)
	(segment
		(start 200.654412 -6.223)
		(end 202.49642 -8.065008)
		(width 0.127)
		(layer "In5.Cu")
		(net "M2_2_ACTIVE_N")
	)
	(segment
		(start 96.701356 -2.450846)
		(end 97.964244 -2.450846)
		(width 0.127)
		(layer "In5.Cu")
		(net "M2_2_ACTIVE_N")
	)
	(segment
		(start 79.022956 -12.05357)
		(end 79.022956 -11.632946)
		(width 0.127)
		(layer "In5.Cu")
		(net "M2_2_ACTIVE_N")
	)
	(segment
		(start 74.85888 -47.1424)
		(end 75.6412 -46.36008)
		(width 0.127)
		(layer "In5.Cu")
		(net "M2_2_ACTIVE_N")
	)
	(segment
		(start 79.022956 -11.632946)
		(end 83.78571 -6.870192)
		(width 0.127)
		(layer "In5.Cu")
		(net "M2_2_ACTIVE_N")
	)
	(segment
		(start 202.49642 -8.065008)
		(end 207.8228 -8.065008)
		(width 0.127)
		(layer "In5.Cu")
		(net "M2_2_ACTIVE_N")
	)
	(segment
		(start 207.8228 -8.065008)
		(end 215.24214 -15.484348)
		(width 0.127)
		(layer "In5.Cu")
		(net "M2_2_ACTIVE_N")
	)
	(segment
		(start 215.24214 -49.521872)
		(end 214.355172 -50.40884)
		(width 0.127)
		(layer "In5.Cu")
		(net "M2_2_ACTIVE_N")
	)
	(segment
		(start 75.6412 -46.36008)
		(end 75.6412 -44.428664)
		(width 0.127)
		(layer "In5.Cu")
		(net "M2_2_ACTIVE_N")
	)
	(segment
		(start 213.400386 -117.028976)
		(end 203.099162 -127.3302)
		(width 0.127)
		(layer "In5.Cu")
		(net "M2_2_ACTIVE_N")
	)
	(segment
		(start 215.24214 -15.484348)
		(end 215.24214 -49.521872)
		(width 0.127)
		(layer "In5.Cu")
		(net "M2_2_ACTIVE_N")
	)
	(segment
		(start 214.355172 -88.577166)
		(end 213.400386 -89.531952)
		(width 0.127)
		(layer "In5.Cu")
		(net "M2_2_ACTIVE_N")
	)
	(segment
		(start 79.02321 -12.053824)
		(end 79.022956 -12.05357)
		(width 0.127)
		(layer "In5.Cu")
		(net "M2_2_ACTIVE_N")
	)
	(segment
		(start 97.964244 -2.450846)
		(end 97.964498 -2.4511)
		(width 0.127)
		(layer "In5.Cu")
		(net "M2_2_ACTIVE_N")
	)
	(segment
		(start 178.824128 -6.223)
		(end 200.654412 -6.223)
		(width 0.127)
		(layer "In5.Cu")
		(net "M2_2_ACTIVE_N")
	)
	(segment
		(start 75.869292 -37.478208)
		(end 79.02321 -34.32429)
		(width 0.127)
		(layer "In5.Cu")
		(net "M2_2_ACTIVE_N")
	)
	(segment
		(start 175.052228 -2.4511)
		(end 178.824128 -6.223)
		(width 0.127)
		(layer "In5.Cu")
		(net "M2_2_ACTIVE_N")
	)
	(segment
		(start 79.02321 -34.32429)
		(end 79.02321 -12.053824)
		(width 0.127)
		(layer "In5.Cu")
		(net "M2_2_ACTIVE_N")
	)
	(segment
		(start 203.099162 -127.3302)
		(end 174.2948 -127.3302)
		(width 0.127)
		(layer "In5.Cu")
		(net "M2_2_ACTIVE_N")
	)
	(segment
		(start 214.355172 -50.40884)
		(end 214.355172 -88.577166)
		(width 0.127)
		(layer "In5.Cu")
		(net "M2_2_ACTIVE_N")
	)
	(segment
		(start 83.78571 -6.870192)
		(end 92.28201 -6.870192)
		(width 0.127)
		(layer "In5.Cu")
		(net "M2_2_ACTIVE_N")
	)
	(segment
		(start 197.39991 -127.324866)
		(end 197.39991 -129.49809)
		(width 0.127)
		(layer "F.Cu")
		(net "M2_1_ACTIVE_N")
	)
	(segment
		(start 196.088 -130.81)
		(end 192.913 -130.81)
		(width 0.127)
		(layer "F.Cu")
		(net "M2_1_ACTIVE_N")
	)
	(segment
		(start 52.499768 -139.40028)
		(end 52.099972 -139.800076)
		(width 0.127)
		(layer "F.Cu")
		(net "M2_1_ACTIVE_N")
	)
	(segment
		(start 197.39991 -129.49809)
		(end 196.088 -130.81)
		(width 0.127)
		(layer "F.Cu")
		(net "M2_1_ACTIVE_N")
	)
	(segment
		(start 191.7192 -132.0038)
		(end 191.7192 -133.8453)
		(width 0.127)
		(layer "F.Cu")
		(net "M2_1_ACTIVE_N")
	)
	(segment
		(start 192.913 -130.81)
		(end 191.7192 -132.0038)
		(width 0.127)
		(layer "F.Cu")
		(net "M2_1_ACTIVE_N")
	)
	(via
		(at 52.499768 -139.40028)
		(size 0.4572)
		(drill 0.2032)
		(layers "F.Cu" "B.Cu")
		(net "M2_1_ACTIVE_N")
	)
	(via
		(at 57.558178 -112.790732)
		(size 0.508)
		(drill 0.254)
		(layers "F.Cu" "B.Cu")
		(net "M2_1_ACTIVE_N")
	)
	(via
		(at 74.85888 -45.3644)
		(size 0.508)
		(drill 0.254)
		(layers "F.Cu" "B.Cu")
		(net "M2_1_ACTIVE_N")
	)
	(via
		(at 197.39991 -129.49809)
		(size 0.508)
		(drill 0.254)
		(layers "F.Cu" "B.Cu")
		(net "M2_1_ACTIVE_N")
	)
	(via
		(at 67.92849 -112.413288)
		(size 0.6096)
		(drill 0.3048)
		(layers "F.Cu" "B.Cu")
		(net "M2_1_ACTIVE_N")
	)
	(segment
		(start 80.693768 -111.262414)
		(end 75.345798 -111.262414)
		(width 0.127)
		(layer "B.Cu")
		(net "M2_1_ACTIVE_N")
	)
	(segment
		(start 76.702412 -97.536)
		(end 79.45247 -97.536)
		(width 0.127)
		(layer "B.Cu")
		(net "M2_1_ACTIVE_N")
	)
	(segment
		(start 75.345798 -111.262414)
		(end 74.195178 -112.413034)
		(width 0.127)
		(layer "B.Cu")
		(net "M2_1_ACTIVE_N")
	)
	(segment
		(start 75.5396 -46.04512)
		(end 75.5396 -47.7774)
		(width 0.127)
		(layer "B.Cu")
		(net "M2_1_ACTIVE_N")
	)
	(segment
		(start 74.85888 -45.3644)
		(end 75.5396 -46.04512)
		(width 0.127)
		(layer "B.Cu")
		(net "M2_1_ACTIVE_N")
	)
	(segment
		(start 75.06335 -48.25365)
		(end 75.06335 -95.896938)
		(width 0.127)
		(layer "B.Cu")
		(net "M2_1_ACTIVE_N")
	)
	(segment
		(start 75.06335 -95.896938)
		(end 76.702412 -97.536)
		(width 0.127)
		(layer "B.Cu")
		(net "M2_1_ACTIVE_N")
	)
	(segment
		(start 84.639658 -102.021894)
		(end 84.639658 -108.261658)
		(width 0.127)
		(layer "B.Cu")
		(net "M2_1_ACTIVE_N")
	)
	(segment
		(start 82.287364 -99.6696)
		(end 84.639658 -102.021894)
		(width 0.127)
		(layer "B.Cu")
		(net "M2_1_ACTIVE_N")
	)
	(segment
		(start 67.92849 -112.413288)
		(end 67.248532 -112.413288)
		(width 0.127)
		(layer "B.Cu")
		(net "M2_1_ACTIVE_N")
	)
	(segment
		(start 84.639658 -108.261658)
		(end 82.789776 -110.11154)
		(width 0.127)
		(layer "B.Cu")
		(net "M2_1_ACTIVE_N")
	)
	(segment
		(start 82.789776 -110.11154)
		(end 82.333846 -110.11154)
		(width 0.127)
		(layer "B.Cu")
		(net "M2_1_ACTIVE_N")
	)
	(segment
		(start 81.58607 -99.6696)
		(end 82.287364 -99.6696)
		(width 0.127)
		(layer "B.Cu")
		(net "M2_1_ACTIVE_N")
	)
	(segment
		(start 79.45247 -97.536)
		(end 81.58607 -99.6696)
		(width 0.127)
		(layer "B.Cu")
		(net "M2_1_ACTIVE_N")
	)
	(segment
		(start 81.516982 -110.4392)
		(end 80.693768 -111.262414)
		(width 0.127)
		(layer "B.Cu")
		(net "M2_1_ACTIVE_N")
	)
	(segment
		(start 66.37782 -113.284)
		(end 58.403744 -113.284)
		(width 0.127)
		(layer "B.Cu")
		(net "M2_1_ACTIVE_N")
	)
	(segment
		(start 74.195178 -112.413034)
		(end 69.810376 -112.413034)
		(width 0.127)
		(layer "B.Cu")
		(net "M2_1_ACTIVE_N")
	)
	(segment
		(start 82.333846 -110.11154)
		(end 82.006186 -110.4392)
		(width 0.127)
		(layer "B.Cu")
		(net "M2_1_ACTIVE_N")
	)
	(segment
		(start 57.910476 -112.790732)
		(end 57.558178 -112.790732)
		(width 0.127)
		(layer "B.Cu")
		(net "M2_1_ACTIVE_N")
	)
	(segment
		(start 82.006186 -110.4392)
		(end 81.516982 -110.4392)
		(width 0.127)
		(layer "B.Cu")
		(net "M2_1_ACTIVE_N")
	)
	(segment
		(start 75.5396 -47.7774)
		(end 75.06335 -48.25365)
		(width 0.127)
		(layer "B.Cu")
		(net "M2_1_ACTIVE_N")
	)
	(segment
		(start 58.403744 -113.284)
		(end 57.910476 -112.790732)
		(width 0.127)
		(layer "B.Cu")
		(net "M2_1_ACTIVE_N")
	)
	(segment
		(start 69.810376 -112.413034)
		(end 69.810122 -112.413288)
		(width 0.127)
		(layer "B.Cu")
		(net "M2_1_ACTIVE_N")
	)
	(segment
		(start 67.248532 -112.413288)
		(end 66.37782 -113.284)
		(width 0.127)
		(layer "B.Cu")
		(net "M2_1_ACTIVE_N")
	)
	(segment
		(start 69.810122 -112.413288)
		(end 67.92849 -112.413288)
		(width 0.127)
		(layer "B.Cu")
		(net "M2_1_ACTIVE_N")
	)
	(segment
		(start 52.106068 -139.00658)
		(end 52.499768 -139.40028)
		(width 0.127)
		(layer "In2.Cu")
		(net "M2_1_ACTIVE_N")
	)
	(segment
		(start 52.106068 -137.637012)
		(end 52.106068 -139.00658)
		(width 0.127)
		(layer "In2.Cu")
		(net "M2_1_ACTIVE_N")
	)
	(segment
		(start 57.558178 -112.790732)
		(end 55.475378 -114.873532)
		(width 0.127)
		(layer "In2.Cu")
		(net "M2_1_ACTIVE_N")
	)
	(segment
		(start 52.45608 -117.231922)
		(end 52.45608 -125.43282)
		(width 0.127)
		(layer "In2.Cu")
		(net "M2_1_ACTIVE_N")
	)
	(segment
		(start 53.017166 -133.480556)
		(end 52.5018 -133.995922)
		(width 0.127)
		(layer "In2.Cu")
		(net "M2_1_ACTIVE_N")
	)
	(segment
		(start 52.5018 -133.995922)
		(end 52.5018 -137.24128)
		(width 0.127)
		(layer "In2.Cu")
		(net "M2_1_ACTIVE_N")
	)
	(segment
		(start 53.017166 -129.946654)
		(end 53.017166 -133.480556)
		(width 0.127)
		(layer "In2.Cu")
		(net "M2_1_ACTIVE_N")
	)
	(segment
		(start 52.45608 -125.43282)
		(end 53.1749 -126.15164)
		(width 0.127)
		(layer "In2.Cu")
		(net "M2_1_ACTIVE_N")
	)
	(segment
		(start 55.475378 -114.873532)
		(end 54.81447 -114.873532)
		(width 0.127)
		(layer "In2.Cu")
		(net "M2_1_ACTIVE_N")
	)
	(segment
		(start 52.5018 -137.24128)
		(end 52.106068 -137.637012)
		(width 0.127)
		(layer "In2.Cu")
		(net "M2_1_ACTIVE_N")
	)
	(segment
		(start 53.1749 -129.78892)
		(end 53.017166 -129.946654)
		(width 0.127)
		(layer "In2.Cu")
		(net "M2_1_ACTIVE_N")
	)
	(segment
		(start 54.81447 -114.873532)
		(end 52.45608 -117.231922)
		(width 0.127)
		(layer "In2.Cu")
		(net "M2_1_ACTIVE_N")
	)
	(segment
		(start 53.1749 -126.15164)
		(end 53.1749 -129.78892)
		(width 0.127)
		(layer "In2.Cu")
		(net "M2_1_ACTIVE_N")
	)
	(segment
		(start 200.6346 -5.6642)
		(end 202.654408 -7.684008)
		(width 0.127)
		(layer "In5.Cu")
		(net "M2_1_ACTIVE_N")
	)
	(segment
		(start 78.641956 -12.211558)
		(end 78.641956 -11.474958)
		(width 0.127)
		(layer "In5.Cu")
		(net "M2_1_ACTIVE_N")
	)
	(segment
		(start 98.122232 -2.069846)
		(end 98.122486 -2.0701)
		(width 0.127)
		(layer "In5.Cu")
		(net "M2_1_ACTIVE_N")
	)
	(segment
		(start 98.122486 -2.0701)
		(end 175.210216 -2.0701)
		(width 0.127)
		(layer "In5.Cu")
		(net "M2_1_ACTIVE_N")
	)
	(segment
		(start 75.2602 -44.270676)
		(end 75.488292 -44.042584)
		(width 0.127)
		(layer "In5.Cu")
		(net "M2_1_ACTIVE_N")
	)
	(segment
		(start 202.654408 -7.684008)
		(end 207.980788 -7.684008)
		(width 0.127)
		(layer "In5.Cu")
		(net "M2_1_ACTIVE_N")
	)
	(segment
		(start 214.570564 -116.645436)
		(end 203.504546 -127.711454)
		(width 0.127)
		(layer "In5.Cu")
		(net "M2_1_ACTIVE_N")
	)
	(segment
		(start 214.736172 -87.736172)
		(end 215.519 -88.519)
		(width 0.127)
		(layer "In5.Cu")
		(net "M2_1_ACTIVE_N")
	)
	(segment
		(start 194.835018 -4.9149)
		(end 195.584318 -5.6642)
		(width 0.127)
		(layer "In5.Cu")
		(net "M2_1_ACTIVE_N")
	)
	(segment
		(start 214.736172 -50.566828)
		(end 214.736172 -87.736172)
		(width 0.127)
		(layer "In5.Cu")
		(net "M2_1_ACTIVE_N")
	)
	(segment
		(start 96.543368 -2.069846)
		(end 98.122232 -2.069846)
		(width 0.127)
		(layer "In5.Cu")
		(net "M2_1_ACTIVE_N")
	)
	(segment
		(start 175.210216 -2.0701)
		(end 178.804316 -5.6642)
		(width 0.127)
		(layer "In5.Cu")
		(net "M2_1_ACTIVE_N")
	)
	(segment
		(start 214.570564 -90.537538)
		(end 214.570564 -116.645436)
		(width 0.127)
		(layer "In5.Cu")
		(net "M2_1_ACTIVE_N")
	)
	(segment
		(start 215.519 -88.519)
		(end 215.519 -89.589102)
		(width 0.127)
		(layer "In5.Cu")
		(net "M2_1_ACTIVE_N")
	)
	(segment
		(start 193.696082 -5.6642)
		(end 194.445382 -4.9149)
		(width 0.127)
		(layer "In5.Cu")
		(net "M2_1_ACTIVE_N")
	)
	(segment
		(start 78.641956 -11.474958)
		(end 83.627722 -6.489192)
		(width 0.127)
		(layer "In5.Cu")
		(net "M2_1_ACTIVE_N")
	)
	(segment
		(start 75.488292 -37.32022)
		(end 78.64221 -34.166302)
		(width 0.127)
		(layer "In5.Cu")
		(net "M2_1_ACTIVE_N")
	)
	(segment
		(start 195.584318 -5.6642)
		(end 200.6346 -5.6642)
		(width 0.127)
		(layer "In5.Cu")
		(net "M2_1_ACTIVE_N")
	)
	(segment
		(start 75.2602 -44.96308)
		(end 75.2602 -44.270676)
		(width 0.127)
		(layer "In5.Cu")
		(net "M2_1_ACTIVE_N")
	)
	(segment
		(start 215.7222 -15.42542)
		(end 215.7222 -49.5808)
		(width 0.127)
		(layer "In5.Cu")
		(net "M2_1_ACTIVE_N")
	)
	(segment
		(start 215.7222 -49.5808)
		(end 214.736172 -50.566828)
		(width 0.127)
		(layer "In5.Cu")
		(net "M2_1_ACTIVE_N")
	)
	(segment
		(start 178.804316 -5.6642)
		(end 193.696082 -5.6642)
		(width 0.127)
		(layer "In5.Cu")
		(net "M2_1_ACTIVE_N")
	)
	(segment
		(start 83.627722 -6.489192)
		(end 92.124022 -6.489192)
		(width 0.127)
		(layer "In5.Cu")
		(net "M2_1_ACTIVE_N")
	)
	(segment
		(start 78.64221 -34.166302)
		(end 78.64221 -12.211812)
		(width 0.127)
		(layer "In5.Cu")
		(net "M2_1_ACTIVE_N")
	)
	(segment
		(start 199.186546 -127.711454)
		(end 197.39991 -129.49809)
		(width 0.127)
		(layer "In5.Cu")
		(net "M2_1_ACTIVE_N")
	)
	(segment
		(start 75.488292 -44.042584)
		(end 75.488292 -37.32022)
		(width 0.127)
		(layer "In5.Cu")
		(net "M2_1_ACTIVE_N")
	)
	(segment
		(start 207.980788 -7.684008)
		(end 215.7222 -15.42542)
		(width 0.127)
		(layer "In5.Cu")
		(net "M2_1_ACTIVE_N")
	)
	(segment
		(start 78.64221 -12.211812)
		(end 78.641956 -12.211558)
		(width 0.127)
		(layer "In5.Cu")
		(net "M2_1_ACTIVE_N")
	)
	(segment
		(start 194.445382 -4.9149)
		(end 194.835018 -4.9149)
		(width 0.127)
		(layer "In5.Cu")
		(net "M2_1_ACTIVE_N")
	)
	(segment
		(start 215.519 -89.589102)
		(end 214.570564 -90.537538)
		(width 0.127)
		(layer "In5.Cu")
		(net "M2_1_ACTIVE_N")
	)
	(segment
		(start 203.504546 -127.711454)
		(end 199.186546 -127.711454)
		(width 0.127)
		(layer "In5.Cu")
		(net "M2_1_ACTIVE_N")
	)
	(segment
		(start 74.85888 -45.3644)
		(end 75.2602 -44.96308)
		(width 0.127)
		(layer "In5.Cu")
		(net "M2_1_ACTIVE_N")
	)
	(segment
		(start 92.124022 -6.489192)
		(end 96.543368 -2.069846)
		(width 0.127)
		(layer "In5.Cu")
		(net "M2_1_ACTIVE_N")
	)
	(segment
		(start 100.33 -145.541746)
		(end 99.490276 -145.541746)
		(width 0.127)
		(layer "F.Cu")
		(net "I2C_DEBUG_SDA_L")
	)
	(segment
		(start 100.3554 -145.516346)
		(end 100.33 -145.541746)
		(width 0.127)
		(layer "F.Cu")
		(net "I2C_DEBUG_SDA_L")
	)
	(via
		(at 80.724502 -148.582126)
		(size 0.508)
		(drill 0.254)
		(layers "F.Cu" "B.Cu")
		(net "I2C_DEBUG_SDA_L")
	)
	(via
		(at 71.50354 -148.082762)
		(size 0.508)
		(drill 0.254)
		(layers "F.Cu" "B.Cu")
		(net "I2C_DEBUG_SDA_L")
	)
	(via
		(at 100.3554 -145.516346)
		(size 0.508)
		(drill 0.254)
		(layers "F.Cu" "B.Cu")
		(net "I2C_DEBUG_SDA_L")
	)
	(segment
		(start 78.763368 -148.089366)
		(end 80.231742 -148.089366)
		(width 0.127)
		(layer "B.Cu")
		(net "I2C_DEBUG_SDA_L")
	)
	(segment
		(start 70.993 -145.415)
		(end 70.993 -145.9738)
		(width 0.127)
		(layer "B.Cu")
		(net "I2C_DEBUG_SDA_L")
	)
	(segment
		(start 71.50354 -146.48434)
		(end 71.50354 -148.082762)
		(width 0.127)
		(layer "B.Cu")
		(net "I2C_DEBUG_SDA_L")
	)
	(segment
		(start 69.56933 -144.247108)
		(end 69.825108 -144.247108)
		(width 0.127)
		(layer "B.Cu")
		(net "I2C_DEBUG_SDA_L")
	)
	(segment
		(start 69.56933 -144.247108)
		(end 68.530724 -144.247108)
		(width 0.127)
		(layer "B.Cu")
		(net "I2C_DEBUG_SDA_L")
	)
	(segment
		(start 69.825108 -144.247108)
		(end 70.993 -145.415)
		(width 0.127)
		(layer "B.Cu")
		(net "I2C_DEBUG_SDA_L")
	)
	(segment
		(start 80.231742 -148.089366)
		(end 80.724502 -148.582126)
		(width 0.127)
		(layer "B.Cu")
		(net "I2C_DEBUG_SDA_L")
	)
	(segment
		(start 70.993 -145.9738)
		(end 71.50354 -146.48434)
		(width 0.127)
		(layer "B.Cu")
		(net "I2C_DEBUG_SDA_L")
	)
	(segment
		(start 87.181436 -146.579336)
		(end 86.398862 -146.579336)
		(width 0.127)
		(layer "In5.Cu")
		(net "I2C_DEBUG_SDA_L")
	)
	(segment
		(start 80.724502 -148.582126)
		(end 79.386176 -147.2438)
		(width 0.127)
		(layer "In5.Cu")
		(net "I2C_DEBUG_SDA_L")
	)
	(segment
		(start 71.530718 -148.055584)
		(end 71.50354 -148.082762)
		(width 0.127)
		(layer "In5.Cu")
		(net "I2C_DEBUG_SDA_L")
	)
	(segment
		(start 79.386176 -147.2438)
		(end 75.030584 -147.2438)
		(width 0.127)
		(layer "In5.Cu")
		(net "I2C_DEBUG_SDA_L")
	)
	(segment
		(start 81.330292 -147.537424)
		(end 81.330292 -147.976336)
		(width 0.127)
		(layer "In5.Cu")
		(net "I2C_DEBUG_SDA_L")
	)
	(segment
		(start 74.2188 -148.055584)
		(end 71.530718 -148.055584)
		(width 0.127)
		(layer "In5.Cu")
		(net "I2C_DEBUG_SDA_L")
	)
	(segment
		(start 75.030584 -147.2438)
		(end 74.2188 -148.055584)
		(width 0.127)
		(layer "In5.Cu")
		(net "I2C_DEBUG_SDA_L")
	)
	(segment
		(start 93.42247 -145.98015)
		(end 90.966036 -145.98015)
		(width 0.127)
		(layer "In5.Cu")
		(net "I2C_DEBUG_SDA_L")
	)
	(segment
		(start 82.609436 -146.25828)
		(end 81.330292 -147.537424)
		(width 0.127)
		(layer "In5.Cu")
		(net "I2C_DEBUG_SDA_L")
	)
	(segment
		(start 86.077806 -146.25828)
		(end 82.609436 -146.25828)
		(width 0.127)
		(layer "In5.Cu")
		(net "I2C_DEBUG_SDA_L")
	)
	(segment
		(start 99.892358 -145.598388)
		(end 93.804232 -145.598388)
		(width 0.127)
		(layer "In5.Cu")
		(net "I2C_DEBUG_SDA_L")
	)
	(segment
		(start 93.804232 -145.598388)
		(end 93.42247 -145.98015)
		(width 0.127)
		(layer "In5.Cu")
		(net "I2C_DEBUG_SDA_L")
	)
	(segment
		(start 100.3554 -145.516346)
		(end 99.9744 -145.516346)
		(width 0.127)
		(layer "In5.Cu")
		(net "I2C_DEBUG_SDA_L")
	)
	(segment
		(start 86.398862 -146.579336)
		(end 86.077806 -146.25828)
		(width 0.127)
		(layer "In5.Cu")
		(net "I2C_DEBUG_SDA_L")
	)
	(segment
		(start 90.524584 -145.538698)
		(end 88.222074 -145.538698)
		(width 0.127)
		(layer "In5.Cu")
		(net "I2C_DEBUG_SDA_L")
	)
	(segment
		(start 90.966036 -145.98015)
		(end 90.524584 -145.538698)
		(width 0.127)
		(layer "In5.Cu")
		(net "I2C_DEBUG_SDA_L")
	)
	(segment
		(start 88.222074 -145.538698)
		(end 87.181436 -146.579336)
		(width 0.127)
		(layer "In5.Cu")
		(net "I2C_DEBUG_SDA_L")
	)
	(segment
		(start 99.9744 -145.516346)
		(end 99.892358 -145.598388)
		(width 0.127)
		(layer "In5.Cu")
		(net "I2C_DEBUG_SDA_L")
	)
	(segment
		(start 81.330292 -147.976336)
		(end 80.724502 -148.582126)
		(width 0.127)
		(layer "In5.Cu")
		(net "I2C_DEBUG_SDA_L")
	)
	(segment
		(start 100.267008 -144.381474)
		(end 99.47783 -144.381474)
		(width 0.127)
		(layer "F.Cu")
		(net "I2C_DEBUG_SCL_L")
	)
	(segment
		(start 100.362258 -144.286224)
		(end 100.267008 -144.381474)
		(width 0.127)
		(layer "F.Cu")
		(net "I2C_DEBUG_SCL_L")
	)
	(via
		(at 72.7456 -144.5768)
		(size 0.508)
		(drill 0.254)
		(layers "F.Cu" "B.Cu")
		(net "I2C_DEBUG_SCL_L")
	)
	(via
		(at 80.724502 -147.439126)
		(size 0.508)
		(drill 0.254)
		(layers "F.Cu" "B.Cu")
		(net "I2C_DEBUG_SCL_L")
	)
	(via
		(at 100.362258 -144.286224)
		(size 0.508)
		(drill 0.254)
		(layers "F.Cu" "B.Cu")
		(net "I2C_DEBUG_SCL_L")
	)
	(segment
		(start 69.547486 -143.220694)
		(end 68.379086 -143.220694)
		(width 0.127)
		(layer "B.Cu")
		(net "I2C_DEBUG_SCL_L")
	)
	(segment
		(start 71.389494 -143.220694)
		(end 69.547486 -143.220694)
		(width 0.127)
		(layer "B.Cu")
		(net "I2C_DEBUG_SCL_L")
	)
	(segment
		(start 72.7456 -144.5768)
		(end 71.389494 -143.220694)
		(width 0.127)
		(layer "B.Cu")
		(net "I2C_DEBUG_SCL_L")
	)
	(segment
		(start 68.379086 -143.220694)
		(end 68.506086 -143.221202)
		(width 0.127)
		(layer "B.Cu")
		(net "I2C_DEBUG_SCL_L")
	)
	(segment
		(start 78.763368 -147.439126)
		(end 80.724502 -147.439126)
		(width 0.127)
		(layer "B.Cu")
		(net "I2C_DEBUG_SCL_L")
	)
	(segment
		(start 91.176602 -145.47215)
		(end 90.73515 -145.030698)
		(width 0.127)
		(layer "In5.Cu")
		(net "I2C_DEBUG_SCL_L")
	)
	(segment
		(start 73.210928 -145.042128)
		(end 72.7456 -144.5768)
		(width 0.127)
		(layer "In5.Cu")
		(net "I2C_DEBUG_SCL_L")
	)
	(segment
		(start 87.150448 -145.471134)
		(end 87.150194 -145.47088)
		(width 0.127)
		(layer "In5.Cu")
		(net "I2C_DEBUG_SCL_L")
	)
	(segment
		(start 93.593666 -145.090388)
		(end 93.211904 -145.47215)
		(width 0.127)
		(layer "In5.Cu")
		(net "I2C_DEBUG_SCL_L")
	)
	(segment
		(start 97.911158 -145.090388)
		(end 93.593666 -145.090388)
		(width 0.127)
		(layer "In5.Cu")
		(net "I2C_DEBUG_SCL_L")
	)
	(segment
		(start 90.73515 -145.030698)
		(end 88.011508 -145.030698)
		(width 0.127)
		(layer "In5.Cu")
		(net "I2C_DEBUG_SCL_L")
	)
	(segment
		(start 87.150194 -145.47088)
		(end 82.67827 -145.47088)
		(width 0.127)
		(layer "In5.Cu")
		(net "I2C_DEBUG_SCL_L")
	)
	(segment
		(start 80.724502 -147.439126)
		(end 79.868776 -146.5834)
		(width 0.127)
		(layer "In5.Cu")
		(net "I2C_DEBUG_SCL_L")
	)
	(segment
		(start 98.500946 -144.5006)
		(end 97.911158 -145.090388)
		(width 0.127)
		(layer "In5.Cu")
		(net "I2C_DEBUG_SCL_L")
	)
	(segment
		(start 93.211904 -145.47215)
		(end 91.176602 -145.47215)
		(width 0.127)
		(layer "In5.Cu")
		(net "I2C_DEBUG_SCL_L")
	)
	(segment
		(start 87.571072 -145.471134)
		(end 87.150448 -145.471134)
		(width 0.127)
		(layer "In5.Cu")
		(net "I2C_DEBUG_SCL_L")
	)
	(segment
		(start 75.4888 -146.5834)
		(end 73.947528 -145.042128)
		(width 0.127)
		(layer "In5.Cu")
		(net "I2C_DEBUG_SCL_L")
	)
	(segment
		(start 79.868776 -146.5834)
		(end 75.4888 -146.5834)
		(width 0.127)
		(layer "In5.Cu")
		(net "I2C_DEBUG_SCL_L")
	)
	(segment
		(start 73.947528 -145.042128)
		(end 73.210928 -145.042128)
		(width 0.127)
		(layer "In5.Cu")
		(net "I2C_DEBUG_SCL_L")
	)
	(segment
		(start 80.724502 -147.424648)
		(end 80.724502 -147.439126)
		(width 0.127)
		(layer "In5.Cu")
		(net "I2C_DEBUG_SCL_L")
	)
	(segment
		(start 88.011508 -145.030698)
		(end 87.571072 -145.471134)
		(width 0.127)
		(layer "In5.Cu")
		(net "I2C_DEBUG_SCL_L")
	)
	(segment
		(start 100.362258 -144.286224)
		(end 100.147882 -144.5006)
		(width 0.127)
		(layer "In5.Cu")
		(net "I2C_DEBUG_SCL_L")
	)
	(segment
		(start 82.67827 -145.47088)
		(end 80.724502 -147.424648)
		(width 0.127)
		(layer "In5.Cu")
		(net "I2C_DEBUG_SCL_L")
	)
	(segment
		(start 100.147882 -144.5006)
		(end 98.500946 -144.5006)
		(width 0.127)
		(layer "In5.Cu")
		(net "I2C_DEBUG_SCL_L")
	)
	(segment
		(start 36.910518 -128.330198)
		(end 36.50996 -127.92964)
		(width 0.127)
		(layer "B.Cu")
		(net "U104_EN")
	)
	(segment
		(start 37.896546 -128.330198)
		(end 37.400738 -128.330198)
		(width 0.127)
		(layer "B.Cu")
		(net "U104_EN")
	)
	(segment
		(start 36.50996 -127.92964)
		(end 35.6997 -127.92964)
		(width 0.127)
		(layer "B.Cu")
		(net "U104_EN")
	)
	(segment
		(start 38.443154 -128.332738)
		(end 37.899086 -128.332738)
		(width 0.127)
		(layer "B.Cu")
		(net "U104_EN")
	)
	(segment
		(start 37.899086 -128.332738)
		(end 37.896546 -128.330198)
		(width 0.127)
		(layer "B.Cu")
		(net "U104_EN")
	)
	(segment
		(start 37.400738 -128.330198)
		(end 36.910518 -128.330198)
		(width 0.127)
		(layer "B.Cu")
		(net "U104_EN")
	)
	(segment
		(start 52.900072 -140.599922)
		(end 53.299868 -140.200126)
		(width 0.127)
		(layer "F.Cu")
		(net "SYS_RST_EN")
	)
	(segment
		(start 52.899818 -140.599922)
		(end 52.900072 -140.599922)
		(width 0.127)
		(layer "F.Cu")
		(net "SYS_RST_EN")
	)
	(via
		(at 59.350656 -122.646186)
		(size 0.508)
		(drill 0.254)
		(layers "F.Cu" "B.Cu")
		(net "SYS_RST_EN")
	)
	(via
		(at 53.299868 -140.200126)
		(size 0.4572)
		(drill 0.2032)
		(layers "F.Cu" "B.Cu")
		(net "SYS_RST_EN")
	)
	(via
		(at 36.83 -124.1044)
		(size 0.508)
		(drill 0.254)
		(layers "F.Cu" "B.Cu")
		(net "SYS_RST_EN")
	)
	(via
		(at 36.83 -125.0188)
		(size 0.6096)
		(drill 0.3048)
		(layers "F.Cu" "B.Cu")
		(net "SYS_RST_EN")
	)
	(segment
		(start 37.400738 -126.29642)
		(end 36.83 -125.725682)
		(width 0.127)
		(layer "B.Cu")
		(net "SYS_RST_EN")
	)
	(segment
		(start 36.83 -125.725682)
		(end 36.83 -125.0188)
		(width 0.127)
		(layer "B.Cu")
		(net "SYS_RST_EN")
	)
	(segment
		(start 36.83 -124.1044)
		(end 36.83 -125.0188)
		(width 0.127)
		(layer "B.Cu")
		(net "SYS_RST_EN")
	)
	(segment
		(start 37.400738 -127.441198)
		(end 37.400738 -126.29642)
		(width 0.127)
		(layer "B.Cu")
		(net "SYS_RST_EN")
	)
	(segment
		(start 55.85079 -139.806426)
		(end 56.0959 -139.561316)
		(width 0.127)
		(layer "In2.Cu")
		(net "SYS_RST_EN")
	)
	(segment
		(start 59.350656 -128.036574)
		(end 59.350656 -122.646186)
		(width 0.127)
		(layer "In2.Cu")
		(net "SYS_RST_EN")
	)
	(segment
		(start 53.299868 -140.200126)
		(end 53.542946 -140.200126)
		(width 0.127)
		(layer "In2.Cu")
		(net "SYS_RST_EN")
	)
	(segment
		(start 56.0959 -139.561316)
		(end 56.0959 -133.116828)
		(width 0.127)
		(layer "In2.Cu")
		(net "SYS_RST_EN")
	)
	(segment
		(start 53.542946 -140.200126)
		(end 53.936646 -139.806426)
		(width 0.127)
		(layer "In2.Cu")
		(net "SYS_RST_EN")
	)
	(segment
		(start 60.0583 -128.744218)
		(end 59.350656 -128.036574)
		(width 0.127)
		(layer "In2.Cu")
		(net "SYS_RST_EN")
	)
	(segment
		(start 53.936646 -139.806426)
		(end 55.85079 -139.806426)
		(width 0.127)
		(layer "In2.Cu")
		(net "SYS_RST_EN")
	)
	(segment
		(start 58.2803 -131.620006)
		(end 60.0583 -129.842006)
		(width 0.127)
		(layer "In2.Cu")
		(net "SYS_RST_EN")
	)
	(segment
		(start 60.0583 -129.842006)
		(end 60.0583 -128.744218)
		(width 0.127)
		(layer "In2.Cu")
		(net "SYS_RST_EN")
	)
	(segment
		(start 57.592722 -131.620006)
		(end 58.2803 -131.620006)
		(width 0.127)
		(layer "In2.Cu")
		(net "SYS_RST_EN")
	)
	(segment
		(start 56.0959 -133.116828)
		(end 57.592722 -131.620006)
		(width 0.127)
		(layer "In2.Cu")
		(net "SYS_RST_EN")
	)
	(segment
		(start 57.90946 -123.253246)
		(end 54.368954 -123.253246)
		(width 0.127)
		(layer "In5.Cu")
		(net "SYS_RST_EN")
	)
	(segment
		(start 58.51652 -122.646186)
		(end 57.90946 -123.253246)
		(width 0.127)
		(layer "In5.Cu")
		(net "SYS_RST_EN")
	)
	(segment
		(start 37.6936 -124.968)
		(end 36.83 -124.1044)
		(width 0.127)
		(layer "In5.Cu")
		(net "SYS_RST_EN")
	)
	(segment
		(start 42.3799 -125.8951)
		(end 41.4528 -124.968)
		(width 0.127)
		(layer "In5.Cu")
		(net "SYS_RST_EN")
	)
	(segment
		(start 54.33441 -123.28779)
		(end 53.293264 -123.28779)
		(width 0.127)
		(layer "In5.Cu")
		(net "SYS_RST_EN")
	)
	(segment
		(start 41.4528 -124.968)
		(end 37.6936 -124.968)
		(width 0.127)
		(layer "In5.Cu")
		(net "SYS_RST_EN")
	)
	(segment
		(start 44.20616 -125.8951)
		(end 42.3799 -125.8951)
		(width 0.127)
		(layer "In5.Cu")
		(net "SYS_RST_EN")
	)
	(segment
		(start 59.350656 -122.646186)
		(end 58.51652 -122.646186)
		(width 0.127)
		(layer "In5.Cu")
		(net "SYS_RST_EN")
	)
	(segment
		(start 53.293264 -123.28779)
		(end 50.988468 -125.592586)
		(width 0.127)
		(layer "In5.Cu")
		(net "SYS_RST_EN")
	)
	(segment
		(start 54.368954 -123.253246)
		(end 54.33441 -123.28779)
		(width 0.127)
		(layer "In5.Cu")
		(net "SYS_RST_EN")
	)
	(segment
		(start 50.988468 -125.592586)
		(end 44.508674 -125.592586)
		(width 0.127)
		(layer "In5.Cu")
		(net "SYS_RST_EN")
	)
	(segment
		(start 44.508674 -125.592586)
		(end 44.20616 -125.8951)
		(width 0.127)
		(layer "In5.Cu")
		(net "SYS_RST_EN")
	)
	(via
		(at 56.679084 -124.292614)
		(size 0.6096)
		(drill 0.3048)
		(layers "F.Cu" "B.Cu")
		(net "DEBUG_RST_BTN_N_R")
	)
	(segment
		(start 56.321198 -124.6505)
		(end 56.679084 -124.292614)
		(width 0.127)
		(layer "B.Cu")
		(net "DEBUG_RST_BTN_N_R")
	)
	(segment
		(start 55.0164 -125.8316)
		(end 55.0164 -128.07442)
		(width 0.127)
		(layer "B.Cu")
		(net "DEBUG_RST_BTN_N_R")
	)
	(segment
		(start 57.14365 -123.828048)
		(end 57.14365 -122.974354)
		(width 0.127)
		(layer "B.Cu")
		(net "DEBUG_RST_BTN_N_R")
	)
	(segment
		(start 55.499 -124.6505)
		(end 55.499 -125.349)
		(width 0.127)
		(layer "B.Cu")
		(net "DEBUG_RST_BTN_N_R")
	)
	(segment
		(start 55.499 -124.6505)
		(end 56.321198 -124.6505)
		(width 0.127)
		(layer "B.Cu")
		(net "DEBUG_RST_BTN_N_R")
	)
	(segment
		(start 56.679084 -124.292614)
		(end 57.14365 -123.828048)
		(width 0.127)
		(layer "B.Cu")
		(net "DEBUG_RST_BTN_N_R")
	)
	(segment
		(start 55.499 -125.349)
		(end 55.0164 -125.8316)
		(width 0.127)
		(layer "B.Cu")
		(net "DEBUG_RST_BTN_N_R")
	)
	(segment
		(start 92.057474 -56.7182)
		(end 92.057474 -57.368694)
		(width 0.127)
		(layer "F.Cu")
		(net "P3V3_EN_R")
	)
	(segment
		(start 90.100658 -59.32551)
		(end 92.057474 -57.368694)
		(width 0.127)
		(layer "F.Cu")
		(net "P3V3_EN_R")
	)
	(segment
		(start 92.2274 -56.1086)
		(end 92.2274 -56.548274)
		(width 0.127)
		(layer "F.Cu")
		(net "P3V3_EN_R")
	)
	(segment
		(start 93.5609 -49.5808)
		(end 93.5609 -48.860456)
		(width 0.127)
		(layer "F.Cu")
		(net "P3V3_EN_R")
	)
	(segment
		(start 92.3544 -49.8602)
		(end 93.2815 -49.8602)
		(width 0.127)
		(layer "F.Cu")
		(net "P3V3_EN_R")
	)
	(segment
		(start 89.22639 -59.32551)
		(end 90.100658 -59.32551)
		(width 0.127)
		(layer "F.Cu")
		(net "P3V3_EN_R")
	)
	(segment
		(start 91.1352 -54.753002)
		(end 91.1352 -51.0794)
		(width 0.127)
		(layer "F.Cu")
		(net "P3V3_EN_R")
	)
	(segment
		(start 93.5609 -48.860456)
		(end 94.1451 -48.276256)
		(width 0.127)
		(layer "F.Cu")
		(net "P3V3_EN_R")
	)
	(segment
		(start 93.728286 -46.949868)
		(end 94.1451 -47.366682)
		(width 0.127)
		(layer "F.Cu")
		(net "P3V3_EN_R")
	)
	(segment
		(start 92.2274 -56.548274)
		(end 92.057474 -56.7182)
		(width 0.127)
		(layer "F.Cu")
		(net "P3V3_EN_R")
	)
	(segment
		(start 91.1352 -51.0794)
		(end 92.3544 -49.8602)
		(width 0.127)
		(layer "F.Cu")
		(net "P3V3_EN_R")
	)
	(segment
		(start 93.2815 -49.8602)
		(end 93.5609 -49.5808)
		(width 0.127)
		(layer "F.Cu")
		(net "P3V3_EN_R")
	)
	(segment
		(start 92.2274 -55.845202)
		(end 91.1352 -54.753002)
		(width 0.127)
		(layer "F.Cu")
		(net "P3V3_EN_R")
	)
	(segment
		(start 94.1451 -47.366682)
		(end 94.1451 -48.276256)
		(width 0.127)
		(layer "F.Cu")
		(net "P3V3_EN_R")
	)
	(segment
		(start 92.2274 -56.1086)
		(end 92.2274 -55.845202)
		(width 0.127)
		(layer "F.Cu")
		(net "P3V3_EN_R")
	)
	(segment
		(start 93.728286 -45.648626)
		(end 93.728286 -46.949868)
		(width 0.127)
		(layer "F.Cu")
		(net "P3V3_EN_R")
	)
	(via
		(at 92.2274 -56.1086)
		(size 0.6604)
		(drill 0.3302)
		(layers "F.Cu" "B.Cu")
		(net "P3V3_EN_R")
	)
	(via
		(at 92.71 -19.177)
		(size 0.6096)
		(drill 0.3048)
		(layers "F.Cu" "B.Cu")
		(net "USB_CONN_GND")
	)
	(segment
		(start 91.609926 -12.649962)
		(end 91.609926 -14.07287)
		(width 0.508)
		(layer "B.Cu")
		(net "USB_CONN_GND")
	)
	(segment
		(start 86.190074 -21.927058)
		(end 86.190074 -23.349966)
		(width 0.508)
		(layer "B.Cu")
		(net "USB_CONN_GND")
	)
	(segment
		(start 85.071966 -23.349966)
		(end 86.190074 -23.349966)
		(width 0.508)
		(layer "B.Cu")
		(net "USB_CONN_GND")
	)
	(segment
		(start 91.609926 -23.349966)
		(end 91.609926 -25.115774)
		(width 0.508)
		(layer "B.Cu")
		(net "USB_CONN_GND")
	)
	(segment
		(start 90.491818 -12.649962)
		(end 91.609926 -12.649962)
		(width 0.508)
		(layer "B.Cu")
		(net "USB_CONN_GND")
	)
	(segment
		(start 86.190074 -23.349966)
		(end 86.190074 -24.772874)
		(width 0.508)
		(layer "B.Cu")
		(net "USB_CONN_GND")
	)
	(segment
		(start 91.609926 -21.584158)
		(end 91.609926 -23.349966)
		(width 0.508)
		(layer "B.Cu")
		(net "USB_CONN_GND")
	)
	(segment
		(start 91.609926 -23.349966)
		(end 92.728034 -23.349966)
		(width 0.508)
		(layer "B.Cu")
		(net "USB_CONN_GND")
	)
	(segment
		(start 91.609926 -12.649962)
		(end 92.728034 -12.649962)
		(width 0.508)
		(layer "B.Cu")
		(net "USB_CONN_GND")
	)
	(segment
		(start 85.071966 -12.649962)
		(end 86.190074 -12.649962)
		(width 0.508)
		(layer "B.Cu")
		(net "USB_CONN_GND")
	)
	(segment
		(start 91.609926 -11.227054)
		(end 91.609926 -12.649962)
		(width 0.508)
		(layer "B.Cu")
		(net "USB_CONN_GND")
	)
	(segment
		(start 86.190074 -12.649962)
		(end 87.308182 -12.649962)
		(width 0.508)
		(layer "B.Cu")
		(net "USB_CONN_GND")
	)
	(segment
		(start 86.190074 -23.349966)
		(end 87.308182 -23.349966)
		(width 0.508)
		(layer "B.Cu")
		(net "USB_CONN_GND")
	)
	(segment
		(start 86.190074 -12.649962)
		(end 86.190074 -14.41577)
		(width 0.508)
		(layer "B.Cu")
		(net "USB_CONN_GND")
	)
	(segment
		(start 86.190074 -10.884154)
		(end 86.190074 -12.649962)
		(width 0.508)
		(layer "B.Cu")
		(net "USB_CONN_GND")
	)
	(segment
		(start 90.491818 -23.349966)
		(end 91.609926 -23.349966)
		(width 0.508)
		(layer "B.Cu")
		(net "USB_CONN_GND")
	)
	(segment
		(start 14.9225 -9.327642)
		(end 15.500096 -8.750046)
		(width 0.254)
		(layer "F.Cu")
		(net "RST_BTN_GND")
	)
	(segment
		(start 14.9225 -11.43)
		(end 14.9225 -9.327642)
		(width 0.254)
		(layer "F.Cu")
		(net "RST_BTN_GND")
	)
	(segment
		(start 14.9225 -12.3825)
		(end 15.748 -13.208)
		(width 0.254)
		(layer "F.Cu")
		(net "RST_BTN_GND")
	)
	(segment
		(start 14.9225 -11.43)
		(end 14.9225 -12.3825)
		(width 0.254)
		(layer "F.Cu")
		(net "RST_BTN_GND")
	)
	(segment
		(start 8.499856 -8.750046)
		(end 15.500096 -8.750046)
		(width 0.254)
		(layer "In2.Cu")
		(net "RST_BTN_GND")
	)
	(segment
		(start 26.122376 -12.910566)
		(end 26.122376 -12.627864)
		(width 0.254)
		(layer "F.Cu")
		(net "PWR_BTN_GND")
	)
	(segment
		(start 25.010872 -14.02207)
		(end 26.122376 -12.910566)
		(width 0.254)
		(layer "F.Cu")
		(net "PWR_BTN_GND")
	)
	(segment
		(start 25.023572 -14.03477)
		(end 25.010872 -14.02207)
		(width 0.254)
		(layer "F.Cu")
		(net "PWR_BTN_GND")
	)
	(segment
		(start 25.023572 -14.98727)
		(end 25.849072 -15.81277)
		(width 0.254)
		(layer "F.Cu")
		(net "PWR_BTN_GND")
	)
	(segment
		(start 26.122376 -12.627864)
		(end 27.500072 -11.250168)
		(width 0.254)
		(layer "F.Cu")
		(net "PWR_BTN_GND")
	)
	(segment
		(start 25.023572 -14.03477)
		(end 25.023572 -14.98727)
		(width 0.254)
		(layer "F.Cu")
		(net "PWR_BTN_GND")
	)
	(segment
		(start 20.499832 -11.250168)
		(end 27.500072 -11.250168)
		(width 0.254)
		(layer "In2.Cu")
		(net "PWR_BTN_GND")
	)
	(via
		(at 228.696266 -99.380548)
		(size 0.6096)
		(drill 0.3048)
		(layers "F.Cu" "B.Cu")
		(net "P12V_STBY_VIN_U81")
	)
	(via
		(at 225.691192 -99.802442)
		(size 0.7112)
		(drill 0.4064)
		(layers "F.Cu" "B.Cu")
		(net "P12V_STBY_VIN_U81")
	)
	(via
		(at 226.961192 -98.532442)
		(size 0.7112)
		(drill 0.4064)
		(layers "F.Cu" "B.Cu")
		(net "P12V_STBY_VIN_U81")
	)
	(via
		(at 224.421192 -99.802442)
		(size 0.7112)
		(drill 0.4064)
		(layers "F.Cu" "B.Cu")
		(net "P12V_STBY_VIN_U81")
	)
	(via
		(at 226.961192 -99.802442)
		(size 0.7112)
		(drill 0.4064)
		(layers "F.Cu" "B.Cu")
		(net "P12V_STBY_VIN_U81")
	)
	(via
		(at 224.421192 -98.532442)
		(size 0.7112)
		(drill 0.4064)
		(layers "F.Cu" "B.Cu")
		(net "P12V_STBY_VIN_U81")
	)
	(via
		(at 225.691192 -98.532442)
		(size 0.7112)
		(drill 0.4064)
		(layers "F.Cu" "B.Cu")
		(net "P12V_STBY_VIN_U81")
	)
	(via
		(at 26.449528 -183.602122)
		(size 0.6604)
		(drill 0.3302)
		(layers "F.Cu" "B.Cu")
		(net "P12V_STBY_VIN_PU2")
	)
	(via
		(at 222.306388 -53.792374)
		(size 0.7112)
		(drill 0.4064)
		(layers "F.Cu" "B.Cu")
		(net "P12V_STBY_VIN_PU1")
	)
	(via
		(at 222.306388 -52.522374)
		(size 0.7112)
		(drill 0.4064)
		(layers "F.Cu" "B.Cu")
		(net "P12V_STBY_VIN_PU1")
	)
	(via
		(at 223.576388 -52.522374)
		(size 0.7112)
		(drill 0.4064)
		(layers "F.Cu" "B.Cu")
		(net "P12V_STBY_VIN_PU1")
	)
	(via
		(at 222.280988 -55.062374)
		(size 0.7112)
		(drill 0.4064)
		(layers "F.Cu" "B.Cu")
		(net "P12V_STBY_VIN_PU1")
	)
	(via
		(at 221.300294 -55.529734)
		(size 0.6604)
		(drill 0.3302)
		(layers "F.Cu" "B.Cu")
		(net "P12V_STBY_VIN_PU1")
	)
	(via
		(at 223.576388 -53.792374)
		(size 0.7112)
		(drill 0.4064)
		(layers "F.Cu" "B.Cu")
		(net "P12V_STBY_VIN_PU1")
	)
	(via
		(at 223.550988 -55.062374)
		(size 0.7112)
		(drill 0.4064)
		(layers "F.Cu" "B.Cu")
		(net "P12V_STBY_VIN_PU1")
	)
	(segment
		(start 152.132538 -16.054578)
		(end 153.021538 -16.054578)
		(width 0.254)
		(layer "F.Cu")
		(net "P12V_STBY_VCC_PU4")
	)
	(segment
		(start 153.67508 -13.99032)
		(end 153.67508 -12.959842)
		(width 0.254)
		(layer "F.Cu")
		(net "P12V_STBY_VCC_PU4")
	)
	(segment
		(start 153.427938 -14.657578)
		(end 153.427938 -15.648178)
		(width 0.254)
		(layer "F.Cu")
		(net "P12V_STBY_VCC_PU4")
	)
	(segment
		(start 153.427938 -14.237462)
		(end 153.67508 -13.99032)
		(width 0.254)
		(layer "F.Cu")
		(net "P12V_STBY_VCC_PU4")
	)
	(segment
		(start 153.427938 -15.648178)
		(end 153.351738 -15.724378)
		(width 0.254)
		(layer "F.Cu")
		(net "P12V_STBY_VCC_PU4")
	)
	(segment
		(start 153.427938 -14.657578)
		(end 153.427938 -14.237462)
		(width 0.254)
		(layer "F.Cu")
		(net "P12V_STBY_VCC_PU4")
	)
	(segment
		(start 153.021538 -16.054578)
		(end 153.351738 -15.724378)
		(width 0.254)
		(layer "F.Cu")
		(net "P12V_STBY_VCC_PU4")
	)
	(via
		(at 153.427938 -14.657578)
		(size 0.6604)
		(drill 0.3302)
		(layers "F.Cu" "B.Cu")
		(net "P12V_STBY_VCC_PU4")
	)
	(via
		(at 126.5174 -8.636)
		(size 0.6604)
		(drill 0.3302)
		(layers "F.Cu" "B.Cu")
		(net "MB0_CM_GATE_2")
	)
	(segment
		(start 180.408072 -126.395988)
		(end 180.399944 -126.404116)
		(width 0.127)
		(layer "F.Cu")
		(net "I2C_M2_2_1V8_SDA")
	)
	(segment
		(start 179.925218 -125.307852)
		(end 180.408072 -125.790706)
		(width 0.127)
		(layer "F.Cu")
		(net "I2C_M2_2_1V8_SDA")
	)
	(segment
		(start 180.399944 -126.404116)
		(end 180.399944 -127.324866)
		(width 0.127)
		(layer "F.Cu")
		(net "I2C_M2_2_1V8_SDA")
	)
	(segment
		(start 180.408072 -125.790706)
		(end 180.408072 -126.395988)
		(width 0.127)
		(layer "F.Cu")
		(net "I2C_M2_2_1V8_SDA")
	)
	(segment
		(start 179.925218 -124.714)
		(end 179.925218 -125.307852)
		(width 0.127)
		(layer "F.Cu")
		(net "I2C_M2_2_1V8_SDA")
	)
	(via
		(at 178.939444 -123.997466)
		(size 0.6096)
		(drill 0.3048)
		(layers "F.Cu" "B.Cu")
		(net "I2C_M2_2_1V8_SDA")
	)
	(via
		(at 179.925218 -124.714)
		(size 0.508)
		(drill 0.254)
		(layers "F.Cu" "B.Cu")
		(net "I2C_M2_2_1V8_SDA")
	)
	(segment
		(start 179.925218 -124.714)
		(end 179.655978 -124.714)
		(width 0.127)
		(layer "B.Cu")
		(net "I2C_M2_2_1V8_SDA")
	)
	(segment
		(start 178.53406 -122.132852)
		(end 178.53406 -120.316244)
		(width 0.127)
		(layer "B.Cu")
		(net "I2C_M2_2_1V8_SDA")
	)
	(segment
		(start 178.013614 -122.988832)
		(end 178.013614 -122.653298)
		(width 0.127)
		(layer "B.Cu")
		(net "I2C_M2_2_1V8_SDA")
	)
	(segment
		(start 178.013614 -122.988832)
		(end 178.013614 -123.071636)
		(width 0.127)
		(layer "B.Cu")
		(net "I2C_M2_2_1V8_SDA")
	)
	(segment
		(start 178.013614 -123.071636)
		(end 178.939444 -123.997466)
		(width 0.127)
		(layer "B.Cu")
		(net "I2C_M2_2_1V8_SDA")
	)
	(segment
		(start 178.013614 -122.653298)
		(end 178.53406 -122.132852)
		(width 0.127)
		(layer "B.Cu")
		(net "I2C_M2_2_1V8_SDA")
	)
	(segment
		(start 179.655978 -124.714)
		(end 178.939444 -123.997466)
		(width 0.127)
		(layer "B.Cu")
		(net "I2C_M2_2_1V8_SDA")
	)
	(segment
		(start 179.2478 -125.349)
		(end 179.900072 -126.001272)
		(width 0.127)
		(layer "F.Cu")
		(net "I2C_M2_2_1V8_SCL")
	)
	(segment
		(start 179.900072 -126.001272)
		(end 179.900072 -127.324866)
		(width 0.127)
		(layer "F.Cu")
		(net "I2C_M2_2_1V8_SCL")
	)
	(via
		(at 177.975006 -124.81306)
		(size 0.6096)
		(drill 0.3048)
		(layers "F.Cu" "B.Cu")
		(net "I2C_M2_2_1V8_SCL")
	)
	(via
		(at 179.2478 -125.349)
		(size 0.508)
		(drill 0.254)
		(layers "F.Cu" "B.Cu")
		(net "I2C_M2_2_1V8_SCL")
	)
	(segment
		(start 178.510946 -125.349)
		(end 179.2478 -125.349)
		(width 0.127)
		(layer "B.Cu")
		(net "I2C_M2_2_1V8_SCL")
	)
	(segment
		(start 177.518568 -124.356622)
		(end 177.975006 -124.81306)
		(width 0.127)
		(layer "B.Cu")
		(net "I2C_M2_2_1V8_SCL")
	)
	(segment
		(start 177.88382 -121.831862)
		(end 177.747676 -121.968006)
		(width 0.127)
		(layer "B.Cu")
		(net "I2C_M2_2_1V8_SCL")
	)
	(segment
		(start 177.88382 -120.316244)
		(end 177.88382 -121.831862)
		(width 0.127)
		(layer "B.Cu")
		(net "I2C_M2_2_1V8_SCL")
	)
	(segment
		(start 177.747676 -121.968006)
		(end 177.518568 -122.197114)
		(width 0.127)
		(layer "B.Cu")
		(net "I2C_M2_2_1V8_SCL")
	)
	(segment
		(start 177.518568 -122.197114)
		(end 177.518568 -124.356622)
		(width 0.127)
		(layer "B.Cu")
		(net "I2C_M2_2_1V8_SCL")
	)
	(segment
		(start 177.975006 -124.81306)
		(end 178.510946 -125.349)
		(width 0.127)
		(layer "B.Cu")
		(net "I2C_M2_2_1V8_SCL")
	)
	(segment
		(start 204.949552 -125.422152)
		(end 205.399894 -125.872494)
		(width 0.127)
		(layer "F.Cu")
		(net "I2C_M2_1_1V8_SDA")
	)
	(segment
		(start 204.949552 -124.815092)
		(end 204.949552 -125.422152)
		(width 0.127)
		(layer "F.Cu")
		(net "I2C_M2_1_1V8_SDA")
	)
	(segment
		(start 205.399894 -125.872494)
		(end 205.399894 -127.324866)
		(width 0.127)
		(layer "F.Cu")
		(net "I2C_M2_1_1V8_SDA")
	)
	(via
		(at 204.949552 -124.815092)
		(size 0.508)
		(drill 0.254)
		(layers "F.Cu" "B.Cu")
		(net "I2C_M2_1_1V8_SDA")
	)
	(via
		(at 210.7438 -108.4072)
		(size 0.6096)
		(drill 0.3048)
		(layers "F.Cu" "B.Cu")
		(net "I2C_M2_1_1V8_SDA")
	)
	(segment
		(start 210.7438 -109.2962)
		(end 210.7438 -108.4072)
		(width 0.127)
		(layer "B.Cu")
		(net "I2C_M2_1_1V8_SDA")
	)
	(segment
		(start 208.134712 -107.349798)
		(end 209.55635 -107.349798)
		(width 0.127)
		(layer "B.Cu")
		(net "I2C_M2_1_1V8_SDA")
	)
	(segment
		(start 210.7438 -108.4072)
		(end 210.4136 -108.077)
		(width 0.127)
		(layer "B.Cu")
		(net "I2C_M2_1_1V8_SDA")
	)
	(segment
		(start 210.4136 -108.077)
		(end 209.677 -108.077)
		(width 0.127)
		(layer "B.Cu")
		(net "I2C_M2_1_1V8_SDA")
	)
	(segment
		(start 210.058 -113.629694)
		(end 210.058 -109.982)
		(width 0.127)
		(layer "B.Cu")
		(net "I2C_M2_1_1V8_SDA")
	)
	(segment
		(start 204.949552 -124.815092)
		(end 204.0128 -123.87834)
		(width 0.127)
		(layer "B.Cu")
		(net "I2C_M2_1_1V8_SDA")
	)
	(segment
		(start 209.5627 -107.9627)
		(end 209.5627 -107.343448)
		(width 0.127)
		(layer "B.Cu")
		(net "I2C_M2_1_1V8_SDA")
	)
	(segment
		(start 204.0128 -123.87834)
		(end 204.0128 -119.674894)
		(width 0.127)
		(layer "B.Cu")
		(net "I2C_M2_1_1V8_SDA")
	)
	(segment
		(start 204.0128 -119.674894)
		(end 210.058 -113.629694)
		(width 0.127)
		(layer "B.Cu")
		(net "I2C_M2_1_1V8_SDA")
	)
	(segment
		(start 209.55635 -107.349798)
		(end 209.5627 -107.343448)
		(width 0.127)
		(layer "B.Cu")
		(net "I2C_M2_1_1V8_SDA")
	)
	(segment
		(start 209.677 -108.077)
		(end 209.5627 -107.9627)
		(width 0.127)
		(layer "B.Cu")
		(net "I2C_M2_1_1V8_SDA")
	)
	(segment
		(start 210.058 -109.982)
		(end 210.7438 -109.2962)
		(width 0.127)
		(layer "B.Cu")
		(net "I2C_M2_1_1V8_SDA")
	)
	(segment
		(start 204.900022 -126.185422)
		(end 204.900022 -127.324866)
		(width 0.127)
		(layer "F.Cu")
		(net "I2C_M2_1_1V8_SCL")
	)
	(segment
		(start 204.0382 -125.3236)
		(end 204.900022 -126.185422)
		(width 0.127)
		(layer "F.Cu")
		(net "I2C_M2_1_1V8_SCL")
	)
	(segment
		(start 204.0382 -124.8664)
		(end 204.0382 -125.3236)
		(width 0.127)
		(layer "F.Cu")
		(net "I2C_M2_1_1V8_SCL")
	)
	(via
		(at 209.55 -108.9152)
		(size 0.6096)
		(drill 0.3048)
		(layers "F.Cu" "B.Cu")
		(net "I2C_M2_1_1V8_SCL")
	)
	(via
		(at 204.0382 -124.8664)
		(size 0.508)
		(drill 0.254)
		(layers "F.Cu" "B.Cu")
		(net "I2C_M2_1_1V8_SCL")
	)
	(segment
		(start 209.55 -113.419128)
		(end 203.5048 -119.464328)
		(width 0.127)
		(layer "B.Cu")
		(net "I2C_M2_1_1V8_SCL")
	)
	(segment
		(start 207.484472 -107.349798)
		(end 207.484472 -108.773722)
		(width 0.127)
		(layer "B.Cu")
		(net "I2C_M2_1_1V8_SCL")
	)
	(segment
		(start 207.484472 -108.773722)
		(end 207.504284 -108.793534)
		(width 0.127)
		(layer "B.Cu")
		(net "I2C_M2_1_1V8_SCL")
	)
	(segment
		(start 209.55 -108.9152)
		(end 209.55 -113.419128)
		(width 0.127)
		(layer "B.Cu")
		(net "I2C_M2_1_1V8_SCL")
	)
	(segment
		(start 207.62595 -108.9152)
		(end 207.504284 -108.793534)
		(width 0.127)
		(layer "B.Cu")
		(net "I2C_M2_1_1V8_SCL")
	)
	(segment
		(start 203.5048 -124.333)
		(end 204.0382 -124.8664)
		(width 0.127)
		(layer "B.Cu")
		(net "I2C_M2_1_1V8_SCL")
	)
	(segment
		(start 209.55 -108.9152)
		(end 207.62595 -108.9152)
		(width 0.127)
		(layer "B.Cu")
		(net "I2C_M2_1_1V8_SCL")
	)
	(segment
		(start 203.5048 -119.464328)
		(end 203.5048 -124.333)
		(width 0.127)
		(layer "B.Cu")
		(net "I2C_M2_1_1V8_SCL")
	)
	(segment
		(start 38.702742 -151.55291)
		(end 38.702742 -151.697436)
		(width 0.127)
		(layer "F.Cu")
		(net "ENCL_FAULT_LED_R")
	)
	(segment
		(start 35.172142 -153.231342)
		(end 34.987484 -153.416)
		(width 0.127)
		(layer "F.Cu")
		(net "ENCL_FAULT_LED_R")
	)
	(segment
		(start 35.343084 -153.0604)
		(end 35.172142 -153.231342)
		(width 0.127)
		(layer "F.Cu")
		(net "ENCL_FAULT_LED_R")
	)
	(segment
		(start 34.391854 -153.416)
		(end 34.216848 -153.240994)
		(width 0.127)
		(layer "F.Cu")
		(net "ENCL_FAULT_LED_R")
	)
	(segment
		(start 34.987484 -153.416)
		(end 34.391854 -153.416)
		(width 0.127)
		(layer "F.Cu")
		(net "ENCL_FAULT_LED_R")
	)
	(segment
		(start 39.144448 -151.1554)
		(end 39.100252 -151.1554)
		(width 0.127)
		(layer "F.Cu")
		(net "ENCL_FAULT_LED_R")
	)
	(segment
		(start 39.100252 -151.1554)
		(end 38.702742 -151.55291)
		(width 0.127)
		(layer "F.Cu")
		(net "ENCL_FAULT_LED_R")
	)
	(segment
		(start 37.339778 -153.0604)
		(end 35.343084 -153.0604)
		(width 0.127)
		(layer "F.Cu")
		(net "ENCL_FAULT_LED_R")
	)
	(segment
		(start 38.702742 -151.697436)
		(end 37.339778 -153.0604)
		(width 0.127)
		(layer "F.Cu")
		(net "ENCL_FAULT_LED_R")
	)
	(segment
		(start 39.299896 -150.999952)
		(end 39.144448 -151.1554)
		(width 0.127)
		(layer "F.Cu")
		(net "ENCL_FAULT_LED_R")
	)
	(via
		(at 35.172142 -153.231342)
		(size 0.6604)
		(drill 0.3302)
		(layers "F.Cu" "B.Cu")
		(net "ENCL_FAULT_LED_R")
	)
	(segment
		(start 33.740598 -154.589988)
		(end 33.99409 -154.84348)
		(width 0.127)
		(layer "F.Cu")
		(net "ENCL_FAULT_LED")
	)
	(segment
		(start 33.327848 -153.240994)
		(end 33.740598 -153.653744)
		(width 0.127)
		(layer "F.Cu")
		(net "ENCL_FAULT_LED")
	)
	(segment
		(start 33.740598 -153.653744)
		(end 33.740598 -154.589988)
		(width 0.127)
		(layer "F.Cu")
		(net "ENCL_FAULT_LED")
	)
	(via
		(at 101.2444 -168.3258)
		(size 0.508)
		(drill 0.254)
		(layers "F.Cu" "B.Cu")
		(net "ENCL_FAULT_LED")
	)
	(via
		(at 33.99409 -154.84348)
		(size 0.508)
		(drill 0.254)
		(layers "F.Cu" "B.Cu")
		(net "ENCL_FAULT_LED")
	)
	(segment
		(start 33.77057 -155.067)
		(end 33.99409 -154.84348)
		(width 0.127)
		(layer "B.Cu")
		(net "ENCL_FAULT_LED")
	)
	(segment
		(start 32.5755 -155.067)
		(end 33.77057 -155.067)
		(width 0.127)
		(layer "B.Cu")
		(net "ENCL_FAULT_LED")
	)
	(segment
		(start 100.584 -121.025412)
		(end 100.584 -46.504352)
		(width 0.127)
		(layer "In2.Cu")
		(net "ENCL_FAULT_LED")
	)
	(segment
		(start 100.868988 -127.5588)
		(end 100.868988 -124.542804)
		(width 0.127)
		(layer "In2.Cu")
		(net "ENCL_FAULT_LED")
	)
	(segment
		(start 101.71811 -138.350244)
		(end 99.8474 -136.479534)
		(width 0.127)
		(layer "In2.Cu")
		(net "ENCL_FAULT_LED")
	)
	(segment
		(start 100.1776 -130.420618)
		(end 99.889818 -130.132836)
		(width 0.127)
		(layer "In2.Cu")
		(net "ENCL_FAULT_LED")
	)
	(segment
		(start 100.1776 -135.322564)
		(end 100.1776 -130.420618)
		(width 0.127)
		(layer "In2.Cu")
		(net "ENCL_FAULT_LED")
	)
	(segment
		(start 108.232448 -31.885382)
		(end 108.232448 -38.532562)
		(width 0.127)
		(layer "In2.Cu")
		(net "ENCL_FAULT_LED")
	)
	(segment
		(start 99.8474 -135.652764)
		(end 100.1776 -135.322564)
		(width 0.127)
		(layer "In2.Cu")
		(net "ENCL_FAULT_LED")
	)
	(segment
		(start 106.705146 -31.147512)
		(end 107.494578 -31.147512)
		(width 0.127)
		(layer "In2.Cu")
		(net "ENCL_FAULT_LED")
	)
	(segment
		(start 99.8474 -136.479534)
		(end 99.8474 -135.652764)
		(width 0.127)
		(layer "In2.Cu")
		(net "ENCL_FAULT_LED")
	)
	(segment
		(start 100.584 -46.504352)
		(end 105.804462 -41.28389)
		(width 0.127)
		(layer "In2.Cu")
		(net "ENCL_FAULT_LED")
	)
	(segment
		(start 99.889818 -128.53797)
		(end 100.868988 -127.5588)
		(width 0.127)
		(layer "In2.Cu")
		(net "ENCL_FAULT_LED")
	)
	(segment
		(start 100.868988 -124.542804)
		(end 99.7712 -123.445016)
		(width 0.127)
		(layer "In2.Cu")
		(net "ENCL_FAULT_LED")
	)
	(segment
		(start 108.232448 -38.532562)
		(end 108.89996 -39.200074)
		(width 0.127)
		(layer "In2.Cu")
		(net "ENCL_FAULT_LED")
	)
	(segment
		(start 99.7712 -121.838212)
		(end 100.584 -121.025412)
		(width 0.127)
		(layer "In2.Cu")
		(net "ENCL_FAULT_LED")
	)
	(segment
		(start 99.7712 -123.445016)
		(end 99.7712 -121.838212)
		(width 0.127)
		(layer "In2.Cu")
		(net "ENCL_FAULT_LED")
	)
	(segment
		(start 105.804462 -32.048196)
		(end 106.705146 -31.147512)
		(width 0.127)
		(layer "In2.Cu")
		(net "ENCL_FAULT_LED")
	)
	(segment
		(start 105.804462 -41.28389)
		(end 105.804462 -32.048196)
		(width 0.127)
		(layer "In2.Cu")
		(net "ENCL_FAULT_LED")
	)
	(segment
		(start 99.889818 -130.132836)
		(end 99.889818 -128.53797)
		(width 0.127)
		(layer "In2.Cu")
		(net "ENCL_FAULT_LED")
	)
	(segment
		(start 101.71811 -167.85209)
		(end 101.71811 -138.350244)
		(width 0.127)
		(layer "In2.Cu")
		(net "ENCL_FAULT_LED")
	)
	(segment
		(start 107.494578 -31.147512)
		(end 108.232448 -31.885382)
		(width 0.127)
		(layer "In2.Cu")
		(net "ENCL_FAULT_LED")
	)
	(segment
		(start 101.2444 -168.3258)
		(end 101.71811 -167.85209)
		(width 0.127)
		(layer "In2.Cu")
		(net "ENCL_FAULT_LED")
	)
	(segment
		(start 53.441346 -162.432746)
		(end 54.389274 -162.432746)
		(width 0.127)
		(layer "In5.Cu")
		(net "ENCL_FAULT_LED")
	)
	(segment
		(start 55.993284 -162.8394)
		(end 56.553354 -163.39947)
		(width 0.127)
		(layer "In5.Cu")
		(net "ENCL_FAULT_LED")
	)
	(segment
		(start 54.795928 -162.8394)
		(end 55.993284 -162.8394)
		(width 0.127)
		(layer "In5.Cu")
		(net "ENCL_FAULT_LED")
	)
	(segment
		(start 35.806126 -156.44495)
		(end 37.247576 -157.8864)
		(width 0.127)
		(layer "In5.Cu")
		(net "ENCL_FAULT_LED")
	)
	(segment
		(start 33.9852 -154.84348)
		(end 33.9852 -155.7528)
		(width 0.127)
		(layer "In5.Cu")
		(net "ENCL_FAULT_LED")
	)
	(segment
		(start 71.412608 -166.04488)
		(end 72.146414 -165.311074)
		(width 0.127)
		(layer "In5.Cu")
		(net "ENCL_FAULT_LED")
	)
	(segment
		(start 94.7801 -167.2717)
		(end 96.0374 -168.529)
		(width 0.127)
		(layer "In5.Cu")
		(net "ENCL_FAULT_LED")
	)
	(segment
		(start 88.289892 -166.087552)
		(end 89.47404 -167.2717)
		(width 0.127)
		(layer "In5.Cu")
		(net "ENCL_FAULT_LED")
	)
	(segment
		(start 84.649056 -166.087552)
		(end 88.289892 -166.087552)
		(width 0.127)
		(layer "In5.Cu")
		(net "ENCL_FAULT_LED")
	)
	(segment
		(start 83.872578 -165.311074)
		(end 84.649056 -166.087552)
		(width 0.127)
		(layer "In5.Cu")
		(net "ENCL_FAULT_LED")
	)
	(segment
		(start 72.146414 -165.311074)
		(end 83.872578 -165.311074)
		(width 0.127)
		(layer "In5.Cu")
		(net "ENCL_FAULT_LED")
	)
	(segment
		(start 49.592738 -158.584138)
		(end 53.441346 -162.432746)
		(width 0.127)
		(layer "In5.Cu")
		(net "ENCL_FAULT_LED")
	)
	(segment
		(start 33.99409 -154.84348)
		(end 33.9852 -154.84348)
		(width 0.127)
		(layer "In5.Cu")
		(net "ENCL_FAULT_LED")
	)
	(segment
		(start 63.774066 -166.04488)
		(end 71.412608 -166.04488)
		(width 0.127)
		(layer "In5.Cu")
		(net "ENCL_FAULT_LED")
	)
	(segment
		(start 89.47404 -167.2717)
		(end 94.7801 -167.2717)
		(width 0.127)
		(layer "In5.Cu")
		(net "ENCL_FAULT_LED")
	)
	(segment
		(start 56.553354 -163.39947)
		(end 61.128656 -163.39947)
		(width 0.127)
		(layer "In5.Cu")
		(net "ENCL_FAULT_LED")
	)
	(segment
		(start 34.67735 -156.44495)
		(end 35.806126 -156.44495)
		(width 0.127)
		(layer "In5.Cu")
		(net "ENCL_FAULT_LED")
	)
	(segment
		(start 42.048684 -158.584138)
		(end 49.592738 -158.584138)
		(width 0.127)
		(layer "In5.Cu")
		(net "ENCL_FAULT_LED")
	)
	(segment
		(start 33.9852 -155.7528)
		(end 34.67735 -156.44495)
		(width 0.127)
		(layer "In5.Cu")
		(net "ENCL_FAULT_LED")
	)
	(segment
		(start 37.247576 -157.8864)
		(end 41.350946 -157.8864)
		(width 0.127)
		(layer "In5.Cu")
		(net "ENCL_FAULT_LED")
	)
	(segment
		(start 101.0412 -168.529)
		(end 101.2444 -168.3258)
		(width 0.127)
		(layer "In5.Cu")
		(net "ENCL_FAULT_LED")
	)
	(segment
		(start 96.0374 -168.529)
		(end 101.0412 -168.529)
		(width 0.127)
		(layer "In5.Cu")
		(net "ENCL_FAULT_LED")
	)
	(segment
		(start 41.350946 -157.8864)
		(end 42.048684 -158.584138)
		(width 0.127)
		(layer "In5.Cu")
		(net "ENCL_FAULT_LED")
	)
	(segment
		(start 61.128656 -163.39947)
		(end 63.774066 -166.04488)
		(width 0.127)
		(layer "In5.Cu")
		(net "ENCL_FAULT_LED")
	)
	(segment
		(start 54.389274 -162.432746)
		(end 54.795928 -162.8394)
		(width 0.127)
		(layer "In5.Cu")
		(net "ENCL_FAULT_LED")
	)
	(segment
		(start 65.778126 -138.914886)
		(end 65.778126 -138.422634)
		(width 0.127)
		(layer "F.Cu")
		(net "COMP_SPARE_1_R")
	)
	(segment
		(start 52.899818 -141.400022)
		(end 52.900072 -141.400022)
		(width 0.127)
		(layer "F.Cu")
		(net "COMP_SPARE_1_R")
	)
	(segment
		(start 64.65824 -139.331954)
		(end 65.361058 -139.331954)
		(width 0.127)
		(layer "F.Cu")
		(net "COMP_SPARE_1_R")
	)
	(segment
		(start 65.361058 -139.331954)
		(end 65.778126 -138.914886)
		(width 0.127)
		(layer "F.Cu")
		(net "COMP_SPARE_1_R")
	)
	(segment
		(start 63.61303 -139.331954)
		(end 64.65824 -139.331954)
		(width 0.127)
		(layer "F.Cu")
		(net "COMP_SPARE_1_R")
	)
	(segment
		(start 52.900072 -141.400022)
		(end 53.299868 -141.000226)
		(width 0.127)
		(layer "F.Cu")
		(net "COMP_SPARE_1_R")
	)
	(via
		(at 64.65824 -139.331954)
		(size 0.6604)
		(drill 0.3302)
		(layers "F.Cu" "B.Cu")
		(net "COMP_SPARE_1_R")
	)
	(via
		(at 53.299868 -141.000226)
		(size 0.4572)
		(drill 0.2032)
		(layers "F.Cu" "B.Cu")
		(net "COMP_SPARE_1_R")
	)
	(via
		(at 63.61303 -139.331954)
		(size 0.508)
		(drill 0.254)
		(layers "F.Cu" "B.Cu")
		(net "COMP_SPARE_1_R")
	)
	(segment
		(start 61.176154 -139.789154)
		(end 56.660288 -139.789154)
		(width 0.127)
		(layer "In5.Cu")
		(net "COMP_SPARE_1_R")
	)
	(segment
		(start 63.61303 -139.331954)
		(end 63.065914 -139.87907)
		(width 0.127)
		(layer "In5.Cu")
		(net "COMP_SPARE_1_R")
	)
	(segment
		(start 61.26607 -139.87907)
		(end 61.176154 -139.789154)
		(width 0.127)
		(layer "In5.Cu")
		(net "COMP_SPARE_1_R")
	)
	(segment
		(start 63.065914 -139.87907)
		(end 61.26607 -139.87907)
		(width 0.127)
		(layer "In5.Cu")
		(net "COMP_SPARE_1_R")
	)
	(segment
		(start 55.8546 -140.594842)
		(end 53.705252 -140.594842)
		(width 0.127)
		(layer "In5.Cu")
		(net "COMP_SPARE_1_R")
	)
	(segment
		(start 53.705252 -140.594842)
		(end 53.299868 -141.000226)
		(width 0.127)
		(layer "In5.Cu")
		(net "COMP_SPARE_1_R")
	)
	(segment
		(start 56.660288 -139.789154)
		(end 55.8546 -140.594842)
		(width 0.127)
		(layer "In5.Cu")
		(net "COMP_SPARE_1_R")
	)
	(segment
		(start 61.769752 -134.698486)
		(end 61.769752 -134.239254)
		(width 0.127)
		(layer "F.Cu")
		(net "COMP_SPARE_0_R")
	)
	(segment
		(start 54.900068 -138.599926)
		(end 54.500018 -138.999976)
		(width 0.127)
		(layer "F.Cu")
		(net "COMP_SPARE_0_R")
	)
	(segment
		(start 61.582046 -135.2677)
		(end 61.582046 -134.886192)
		(width 0.127)
		(layer "F.Cu")
		(net "COMP_SPARE_0_R")
	)
	(segment
		(start 61.582046 -135.2677)
		(end 61.582046 -135.819388)
		(width 0.127)
		(layer "F.Cu")
		(net "COMP_SPARE_0_R")
	)
	(segment
		(start 61.582046 -134.886192)
		(end 61.769752 -134.698486)
		(width 0.127)
		(layer "F.Cu")
		(net "COMP_SPARE_0_R")
	)
	(segment
		(start 61.582046 -135.819388)
		(end 61.253116 -136.148318)
		(width 0.127)
		(layer "F.Cu")
		(net "COMP_SPARE_0_R")
	)
	(via
		(at 54.900068 -138.599926)
		(size 0.4572)
		(drill 0.2032)
		(layers "F.Cu" "B.Cu")
		(net "COMP_SPARE_0_R")
	)
	(via
		(at 61.253116 -136.148318)
		(size 0.508)
		(drill 0.254)
		(layers "F.Cu" "B.Cu")
		(net "COMP_SPARE_0_R")
	)
	(via
		(at 61.582046 -135.2677)
		(size 0.6604)
		(drill 0.3302)
		(layers "F.Cu" "B.Cu")
		(net "COMP_SPARE_0_R")
	)
	(segment
		(start 60.734702 -136.666732)
		(end 61.253116 -136.148318)
		(width 0.127)
		(layer "In5.Cu")
		(net "COMP_SPARE_0_R")
	)
	(segment
		(start 58.757058 -136.666732)
		(end 60.734702 -136.666732)
		(width 0.127)
		(layer "In5.Cu")
		(net "COMP_SPARE_0_R")
	)
	(segment
		(start 57.677812 -136.880346)
		(end 58.543444 -136.880346)
		(width 0.127)
		(layer "In5.Cu")
		(net "COMP_SPARE_0_R")
	)
	(segment
		(start 58.543444 -136.880346)
		(end 58.757058 -136.666732)
		(width 0.127)
		(layer "In5.Cu")
		(net "COMP_SPARE_0_R")
	)
	(segment
		(start 54.900068 -138.599926)
		(end 55.958232 -138.599926)
		(width 0.127)
		(layer "In5.Cu")
		(net "COMP_SPARE_0_R")
	)
	(segment
		(start 55.958232 -138.599926)
		(end 57.677812 -136.880346)
		(width 0.127)
		(layer "In5.Cu")
		(net "COMP_SPARE_0_R")
	)
	(segment
		(start 44.099988 -150.200106)
		(end 43.700192 -150.599902)
		(width 0.127)
		(layer "F.Cu")
		(net "UART_EXP_BMC_TX_R")
	)
	(segment
		(start 44.099988 -150.199852)
		(end 44.099988 -150.200106)
		(width 0.127)
		(layer "F.Cu")
		(net "UART_EXP_BMC_TX_R")
	)
	(via
		(at 74.105516 -172.843444)
		(size 0.6096)
		(drill 0.3048)
		(layers "F.Cu" "B.Cu")
		(net "UART_EXP_BMC_TX_R")
	)
	(via
		(at 43.700192 -150.599902)
		(size 0.4572)
		(drill 0.2032)
		(layers "F.Cu" "B.Cu")
		(net "UART_EXP_BMC_TX_R")
	)
	(via
		(at 35.502596 -169.338244)
		(size 0.508)
		(drill 0.254)
		(layers "F.Cu" "B.Cu")
		(net "UART_EXP_BMC_TX_R")
	)
	(segment
		(start 35.502596 -169.338244)
		(end 35.502596 -169.019728)
		(width 0.127)
		(layer "B.Cu")
		(net "UART_EXP_BMC_TX_R")
	)
	(segment
		(start 37.426138 -169.260266)
		(end 37.426138 -171.456858)
		(width 0.127)
		(layer "B.Cu")
		(net "UART_EXP_BMC_TX_R")
	)
	(segment
		(start 36.700714 -168.534842)
		(end 37.426138 -169.260266)
		(width 0.127)
		(layer "B.Cu")
		(net "UART_EXP_BMC_TX_R")
	)
	(segment
		(start 76.889356 -172.843444)
		(end 74.105516 -172.843444)
		(width 0.127)
		(layer "B.Cu")
		(net "UART_EXP_BMC_TX_R")
	)
	(segment
		(start 71.6661 -172.1485)
		(end 71.6661 -172.483018)
		(width 0.127)
		(layer "B.Cu")
		(net "UART_EXP_BMC_TX_R")
	)
	(segment
		(start 37.426138 -171.456858)
		(end 39.84244 -173.87316)
		(width 0.127)
		(layer "B.Cu")
		(net "UART_EXP_BMC_TX_R")
	)
	(segment
		(start 35.987482 -168.534842)
		(end 36.700714 -168.534842)
		(width 0.127)
		(layer "B.Cu")
		(net "UART_EXP_BMC_TX_R")
	)
	(segment
		(start 72.026526 -172.843444)
		(end 74.105516 -172.843444)
		(width 0.127)
		(layer "B.Cu")
		(net "UART_EXP_BMC_TX_R")
	)
	(segment
		(start 39.84244 -173.87316)
		(end 43.231054 -173.87316)
		(width 0.127)
		(layer "B.Cu")
		(net "UART_EXP_BMC_TX_R")
	)
	(segment
		(start 63.650368 -170.778932)
		(end 63.8937 -170.5356)
		(width 0.127)
		(layer "B.Cu")
		(net "UART_EXP_BMC_TX_R")
	)
	(segment
		(start 62.198758 -170.57878)
		(end 62.39891 -170.778932)
		(width 0.127)
		(layer "B.Cu")
		(net "UART_EXP_BMC_TX_R")
	)
	(segment
		(start 35.502596 -169.019728)
		(end 35.987482 -168.534842)
		(width 0.127)
		(layer "B.Cu")
		(net "UART_EXP_BMC_TX_R")
	)
	(segment
		(start 70.0532 -170.5356)
		(end 71.6661 -172.1485)
		(width 0.127)
		(layer "B.Cu")
		(net "UART_EXP_BMC_TX_R")
	)
	(segment
		(start 43.231054 -173.87316)
		(end 46.525434 -170.57878)
		(width 0.127)
		(layer "B.Cu")
		(net "UART_EXP_BMC_TX_R")
	)
	(segment
		(start 46.525434 -170.57878)
		(end 62.198758 -170.57878)
		(width 0.127)
		(layer "B.Cu")
		(net "UART_EXP_BMC_TX_R")
	)
	(segment
		(start 63.8937 -170.5356)
		(end 70.0532 -170.5356)
		(width 0.127)
		(layer "B.Cu")
		(net "UART_EXP_BMC_TX_R")
	)
	(segment
		(start 78.193646 -169.9133)
		(end 78.193646 -171.539154)
		(width 0.127)
		(layer "B.Cu")
		(net "UART_EXP_BMC_TX_R")
	)
	(segment
		(start 71.6661 -172.483018)
		(end 72.026526 -172.843444)
		(width 0.127)
		(layer "B.Cu")
		(net "UART_EXP_BMC_TX_R")
	)
	(segment
		(start 78.193646 -171.539154)
		(end 76.889356 -172.843444)
		(width 0.127)
		(layer "B.Cu")
		(net "UART_EXP_BMC_TX_R")
	)
	(segment
		(start 62.39891 -170.778932)
		(end 63.650368 -170.778932)
		(width 0.127)
		(layer "B.Cu")
		(net "UART_EXP_BMC_TX_R")
	)
	(segment
		(start 35.620198 -164.544248)
		(end 34.124646 -163.048696)
		(width 0.127)
		(layer "In2.Cu")
		(net "UART_EXP_BMC_TX_R")
	)
	(segment
		(start 35.502596 -169.338244)
		(end 35.620198 -169.220642)
		(width 0.127)
		(layer "In2.Cu")
		(net "UART_EXP_BMC_TX_R")
	)
	(segment
		(start 44.093892 -154.009344)
		(end 44.093892 -150.993602)
		(width 0.127)
		(layer "In2.Cu")
		(net "UART_EXP_BMC_TX_R")
	)
	(segment
		(start 39.309294 -158.793942)
		(end 44.093892 -154.009344)
		(width 0.127)
		(layer "In2.Cu")
		(net "UART_EXP_BMC_TX_R")
	)
	(segment
		(start 35.897312 -159.469836)
		(end 36.573206 -158.793942)
		(width 0.127)
		(layer "In2.Cu")
		(net "UART_EXP_BMC_TX_R")
	)
	(segment
		(start 34.1249 -162.522662)
		(end 34.1249 -160.208976)
		(width 0.127)
		(layer "In2.Cu")
		(net "UART_EXP_BMC_TX_R")
	)
	(segment
		(start 34.86404 -159.469836)
		(end 35.897312 -159.469836)
		(width 0.127)
		(layer "In2.Cu")
		(net "UART_EXP_BMC_TX_R")
	)
	(segment
		(start 34.124646 -162.522916)
		(end 34.1249 -162.522662)
		(width 0.127)
		(layer "In2.Cu")
		(net "UART_EXP_BMC_TX_R")
	)
	(segment
		(start 34.1249 -160.208976)
		(end 34.86404 -159.469836)
		(width 0.127)
		(layer "In2.Cu")
		(net "UART_EXP_BMC_TX_R")
	)
	(segment
		(start 35.620198 -169.220642)
		(end 35.620198 -164.544248)
		(width 0.127)
		(layer "In2.Cu")
		(net "UART_EXP_BMC_TX_R")
	)
	(segment
		(start 34.124646 -163.048696)
		(end 34.124646 -162.522916)
		(width 0.127)
		(layer "In2.Cu")
		(net "UART_EXP_BMC_TX_R")
	)
	(segment
		(start 44.093892 -150.993602)
		(end 43.700192 -150.599902)
		(width 0.127)
		(layer "In2.Cu")
		(net "UART_EXP_BMC_TX_R")
	)
	(segment
		(start 36.573206 -158.793942)
		(end 39.309294 -158.793942)
		(width 0.127)
		(layer "In2.Cu")
		(net "UART_EXP_BMC_TX_R")
	)
	(via
		(at 79.502 -167.259)
		(size 0.6096)
		(drill 0.3048)
		(layers "F.Cu" "B.Cu")
		(net "UART_EXP_BMC_TX")
	)
	(segment
		(start 79.502 -167.259)
		(end 78.9051 -167.259)
		(width 0.127)
		(layer "B.Cu")
		(net "UART_EXP_BMC_TX")
	)
	(segment
		(start 78.193646 -167.970454)
		(end 78.1939 -167.9702)
		(width 0.127)
		(layer "B.Cu")
		(net "UART_EXP_BMC_TX")
	)
	(segment
		(start 78.9051 -167.259)
		(end 78.1939 -167.9702)
		(width 0.127)
		(layer "B.Cu")
		(net "UART_EXP_BMC_TX")
	)
	(segment
		(start 82.051906 -168.069006)
		(end 81.404206 -168.069006)
		(width 0.127)
		(layer "B.Cu")
		(net "UART_EXP_BMC_TX")
	)
	(segment
		(start 81.404206 -168.069006)
		(end 80.5942 -167.259)
		(width 0.127)
		(layer "B.Cu")
		(net "UART_EXP_BMC_TX")
	)
	(segment
		(start 78.193646 -169.0243)
		(end 78.193646 -167.970454)
		(width 0.127)
		(layer "B.Cu")
		(net "UART_EXP_BMC_TX")
	)
	(segment
		(start 80.5942 -167.259)
		(end 79.502 -167.259)
		(width 0.127)
		(layer "B.Cu")
		(net "UART_EXP_BMC_TX")
	)
	(segment
		(start 44.899834 -150.200106)
		(end 44.500038 -150.599902)
		(width 0.127)
		(layer "F.Cu")
		(net "UART_EXP_BMC_RX_R")
	)
	(segment
		(start 44.899834 -150.199852)
		(end 44.899834 -150.200106)
		(width 0.127)
		(layer "F.Cu")
		(net "UART_EXP_BMC_RX_R")
	)
	(via
		(at 36.366196 -169.312844)
		(size 0.508)
		(drill 0.254)
		(layers "F.Cu" "B.Cu")
		(net "UART_EXP_BMC_RX_R")
	)
	(via
		(at 44.500038 -150.599902)
		(size 0.4572)
		(drill 0.2032)
		(layers "F.Cu" "B.Cu")
		(net "UART_EXP_BMC_RX_R")
	)
	(via
		(at 75.52182 -173.478444)
		(size 0.6096)
		(drill 0.3048)
		(layers "F.Cu" "B.Cu")
		(net "UART_EXP_BMC_RX_R")
	)
	(segment
		(start 63.913512 -171.413932)
		(end 62.116208 -171.413932)
		(width 0.127)
		(layer "B.Cu")
		(net "UART_EXP_BMC_RX_R")
	)
	(segment
		(start 71.763382 -173.478444)
		(end 71.0311 -172.746162)
		(width 0.127)
		(layer "B.Cu")
		(net "UART_EXP_BMC_RX_R")
	)
	(segment
		(start 46.788578 -171.21378)
		(end 43.444922 -174.557436)
		(width 0.127)
		(layer "B.Cu")
		(net "UART_EXP_BMC_RX_R")
	)
	(segment
		(start 39.616634 -174.557436)
		(end 36.38169 -171.322492)
		(width 0.127)
		(layer "B.Cu")
		(net "UART_EXP_BMC_RX_R")
	)
	(segment
		(start 61.916056 -171.21378)
		(end 46.788578 -171.21378)
		(width 0.127)
		(layer "B.Cu")
		(net "UART_EXP_BMC_RX_R")
	)
	(segment
		(start 64.156844 -171.1706)
		(end 63.913512 -171.413932)
		(width 0.127)
		(layer "B.Cu")
		(net "UART_EXP_BMC_RX_R")
	)
	(segment
		(start 43.444922 -174.557436)
		(end 39.616634 -174.557436)
		(width 0.127)
		(layer "B.Cu")
		(net "UART_EXP_BMC_RX_R")
	)
	(segment
		(start 71.0311 -172.411644)
		(end 69.790056 -171.1706)
		(width 0.127)
		(layer "B.Cu")
		(net "UART_EXP_BMC_RX_R")
	)
	(segment
		(start 36.38169 -169.328338)
		(end 36.366196 -169.312844)
		(width 0.127)
		(layer "B.Cu")
		(net "UART_EXP_BMC_RX_R")
	)
	(segment
		(start 77.65796 -173.478444)
		(end 77.664818 -173.471586)
		(width 0.127)
		(layer "B.Cu")
		(net "UART_EXP_BMC_RX_R")
	)
	(segment
		(start 62.116208 -171.413932)
		(end 61.916056 -171.21378)
		(width 0.127)
		(layer "B.Cu")
		(net "UART_EXP_BMC_RX_R")
	)
	(segment
		(start 36.38169 -171.322492)
		(end 36.38169 -169.328338)
		(width 0.127)
		(layer "B.Cu")
		(net "UART_EXP_BMC_RX_R")
	)
	(segment
		(start 75.52182 -173.478444)
		(end 71.763382 -173.478444)
		(width 0.127)
		(layer "B.Cu")
		(net "UART_EXP_BMC_RX_R")
	)
	(segment
		(start 71.0311 -172.746162)
		(end 71.0311 -172.411644)
		(width 0.127)
		(layer "B.Cu")
		(net "UART_EXP_BMC_RX_R")
	)
	(segment
		(start 75.52182 -173.478444)
		(end 77.65796 -173.478444)
		(width 0.127)
		(layer "B.Cu")
		(net "UART_EXP_BMC_RX_R")
	)
	(segment
		(start 69.790056 -171.1706)
		(end 64.156844 -171.1706)
		(width 0.127)
		(layer "B.Cu")
		(net "UART_EXP_BMC_RX_R")
	)
	(segment
		(start 34.7599 -160.47212)
		(end 35.127184 -160.104836)
		(width 0.127)
		(layer "In2.Cu")
		(net "UART_EXP_BMC_RX_R")
	)
	(segment
		(start 44.893738 -154.107642)
		(end 44.893738 -150.993602)
		(width 0.127)
		(layer "In2.Cu")
		(net "UART_EXP_BMC_RX_R")
	)
	(segment
		(start 44.893738 -150.993602)
		(end 44.500038 -150.599902)
		(width 0.127)
		(layer "In2.Cu")
		(net "UART_EXP_BMC_RX_R")
	)
	(segment
		(start 36.88207 -159.428942)
		(end 39.572438 -159.428942)
		(width 0.127)
		(layer "In2.Cu")
		(net "UART_EXP_BMC_RX_R")
	)
	(segment
		(start 36.366196 -169.312844)
		(end 36.287202 -169.23385)
		(width 0.127)
		(layer "In2.Cu")
		(net "UART_EXP_BMC_RX_R")
	)
	(segment
		(start 36.287202 -169.23385)
		(end 36.287202 -164.313108)
		(width 0.127)
		(layer "In2.Cu")
		(net "UART_EXP_BMC_RX_R")
	)
	(segment
		(start 39.572438 -159.428942)
		(end 44.893738 -154.107642)
		(width 0.127)
		(layer "In2.Cu")
		(net "UART_EXP_BMC_RX_R")
	)
	(segment
		(start 35.127184 -160.104836)
		(end 36.206176 -160.104836)
		(width 0.127)
		(layer "In2.Cu")
		(net "UART_EXP_BMC_RX_R")
	)
	(segment
		(start 34.7599 -162.785806)
		(end 34.7599 -160.47212)
		(width 0.127)
		(layer "In2.Cu")
		(net "UART_EXP_BMC_RX_R")
	)
	(segment
		(start 36.287202 -164.313108)
		(end 34.7599 -162.785806)
		(width 0.127)
		(layer "In2.Cu")
		(net "UART_EXP_BMC_RX_R")
	)
	(segment
		(start 36.206176 -160.104836)
		(end 36.88207 -159.428942)
		(width 0.127)
		(layer "In2.Cu")
		(net "UART_EXP_BMC_RX_R")
	)
	(via
		(at 78.7654 -172.1993)
		(size 0.6096)
		(drill 0.3048)
		(layers "F.Cu" "B.Cu")
		(net "UART_EXP_BMC_RX")
	)
	(segment
		(start 78.553818 -172.410882)
		(end 78.7654 -172.1993)
		(width 0.127)
		(layer "B.Cu")
		(net "UART_EXP_BMC_RX")
	)
	(segment
		(start 81.492852 -170.669966)
		(end 82.051906 -170.669966)
		(width 0.127)
		(layer "B.Cu")
		(net "UART_EXP_BMC_RX")
	)
	(segment
		(start 79.9592 -172.1993)
		(end 80.1751 -172.1993)
		(width 0.127)
		(layer "B.Cu")
		(net "UART_EXP_BMC_RX")
	)
	(segment
		(start 80.1751 -172.1993)
		(end 80.645 -171.7294)
		(width 0.127)
		(layer "B.Cu")
		(net "UART_EXP_BMC_RX")
	)
	(segment
		(start 78.7654 -172.1993)
		(end 79.9592 -172.1993)
		(width 0.127)
		(layer "B.Cu")
		(net "UART_EXP_BMC_RX")
	)
	(segment
		(start 80.645 -171.517818)
		(end 81.492852 -170.669966)
		(width 0.127)
		(layer "B.Cu")
		(net "UART_EXP_BMC_RX")
	)
	(segment
		(start 78.553818 -173.471586)
		(end 78.553818 -172.410882)
		(width 0.127)
		(layer "B.Cu")
		(net "UART_EXP_BMC_RX")
	)
	(segment
		(start 80.645 -171.7294)
		(end 80.645 -171.517818)
		(width 0.127)
		(layer "B.Cu")
		(net "UART_EXP_BMC_RX")
	)
	(segment
		(start 98.018092 -176.293526)
		(end 98.057208 -176.332642)
		(width 0.127)
		(layer "F.Cu")
		(net "PWRGD_P3V3_STBY_N_R2")
	)
	(segment
		(start 95.0722 -176.31664)
		(end 96.901508 -176.31664)
		(width 0.127)
		(layer "F.Cu")
		(net "PWRGD_P3V3_STBY_N_R2")
	)
	(segment
		(start 96.901508 -176.31664)
		(end 96.924622 -176.293526)
		(width 0.127)
		(layer "F.Cu")
		(net "PWRGD_P3V3_STBY_N_R2")
	)
	(segment
		(start 96.924622 -176.293526)
		(end 98.018092 -176.293526)
		(width 0.127)
		(layer "F.Cu")
		(net "PWRGD_P3V3_STBY_N_R2")
	)
	(via
		(at 96.924622 -176.293526)
		(size 0.6604)
		(drill 0.3302)
		(layers "F.Cu" "B.Cu")
		(net "PWRGD_P3V3_STBY_N_R2")
	)
	(segment
		(start 80.161384 -146.030442)
		(end 81.616296 -146.030442)
		(width 0.127)
		(layer "F.Cu")
		(net "PWRGD_P3V3_STBY_N_R1")
	)
	(segment
		(start 80.09001 -146.101816)
		(end 80.161384 -146.030442)
		(width 0.127)
		(layer "F.Cu")
		(net "PWRGD_P3V3_STBY_N_R1")
	)
	(via
		(at 80.09001 -146.101816)
		(size 0.508)
		(drill 0.254)
		(layers "F.Cu" "B.Cu")
		(net "PWRGD_P3V3_STBY_N_R1")
	)
	(via
		(at 81.237074 -145.74266)
		(size 0.6096)
		(drill 0.3048)
		(layers "F.Cu" "B.Cu")
		(net "PWRGD_P3V3_STBY_N_R1")
	)
	(segment
		(start 80.877918 -146.101816)
		(end 81.237074 -145.74266)
		(width 0.127)
		(layer "B.Cu")
		(net "PWRGD_P3V3_STBY_N_R1")
	)
	(segment
		(start 82.475324 -145.101818)
		(end 81.877916 -145.101818)
		(width 0.127)
		(layer "B.Cu")
		(net "PWRGD_P3V3_STBY_N_R1")
	)
	(segment
		(start 81.877916 -145.101818)
		(end 81.237074 -145.74266)
		(width 0.127)
		(layer "B.Cu")
		(net "PWRGD_P3V3_STBY_N_R1")
	)
	(segment
		(start 80.09001 -146.101816)
		(end 80.877918 -146.101816)
		(width 0.127)
		(layer "B.Cu")
		(net "PWRGD_P3V3_STBY_N_R1")
	)
	(segment
		(start 98.946208 -175.699166)
		(end 99.15017 -175.495204)
		(width 0.127)
		(layer "F.Cu")
		(net "PWRGD_P3V3_STBY_N")
	)
	(segment
		(start 98.946208 -176.332642)
		(end 98.946208 -175.699166)
		(width 0.127)
		(layer "F.Cu")
		(net "PWRGD_P3V3_STBY_N")
	)
	(segment
		(start 93.1672 -178.55184)
		(end 94.75724 -178.55184)
		(width 0.127)
		(layer "F.Cu")
		(net "PWRGD_P3V3_STBY_N")
	)
	(via
		(at 85.041994 -140.074904)
		(size 0.508)
		(drill 0.254)
		(layers "F.Cu" "B.Cu")
		(net "PWRGD_P3V3_STBY_N")
	)
	(via
		(at 85.0646 -141.6304)
		(size 0.6096)
		(drill 0.3048)
		(layers "F.Cu" "B.Cu")
		(net "PWRGD_P3V3_STBY_N")
	)
	(via
		(at 99.15017 -175.495204)
		(size 0.508)
		(drill 0.254)
		(layers "F.Cu" "B.Cu")
		(net "PWRGD_P3V3_STBY_N")
	)
	(via
		(at 100.6856 -138.557)
		(size 0.508)
		(drill 0.254)
		(layers "F.Cu" "B.Cu")
		(net "PWRGD_P3V3_STBY_N")
	)
	(via
		(at 94.75724 -178.55184)
		(size 0.508)
		(drill 0.254)
		(layers "F.Cu" "B.Cu")
		(net "PWRGD_P3V3_STBY_N")
	)
	(segment
		(start 85.0646 -140.09751)
		(end 85.041994 -140.074904)
		(width 0.127)
		(layer "B.Cu")
		(net "PWRGD_P3V3_STBY_N")
	)
	(segment
		(start 83.978496 -145.101818)
		(end 85.0646 -144.015714)
		(width 0.127)
		(layer "B.Cu")
		(net "PWRGD_P3V3_STBY_N")
	)
	(segment
		(start 83.364324 -145.101818)
		(end 83.978496 -145.101818)
		(width 0.127)
		(layer "B.Cu")
		(net "PWRGD_P3V3_STBY_N")
	)
	(segment
		(start 85.0646 -144.015714)
		(end 85.0646 -141.6304)
		(width 0.127)
		(layer "B.Cu")
		(net "PWRGD_P3V3_STBY_N")
	)
	(segment
		(start 85.0646 -141.6304)
		(end 85.0646 -140.09751)
		(width 0.127)
		(layer "B.Cu")
		(net "PWRGD_P3V3_STBY_N")
	)
	(segment
		(start 100.2919 -146.9263)
		(end 99.9998 -147.2184)
		(width 0.127)
		(layer "In2.Cu")
		(net "PWRGD_P3V3_STBY_N")
	)
	(segment
		(start 100.95611 -146.26209)
		(end 100.6221 -146.5961)
		(width 0.127)
		(layer "In2.Cu")
		(net "PWRGD_P3V3_STBY_N")
	)
	(segment
		(start 100.95611 -138.82751)
		(end 100.95611 -146.26209)
		(width 0.127)
		(layer "In2.Cu")
		(net "PWRGD_P3V3_STBY_N")
	)
	(segment
		(start 99.15017 -175.495204)
		(end 97.480374 -177.165)
		(width 0.127)
		(layer "In2.Cu")
		(net "PWRGD_P3V3_STBY_N")
	)
	(segment
		(start 100.076 -169.093388)
		(end 100.076 -174.569374)
		(width 0.127)
		(layer "In2.Cu")
		(net "PWRGD_P3V3_STBY_N")
	)
	(segment
		(start 100.6221 -146.5961)
		(end 100.6221 -146.651218)
		(width 0.127)
		(layer "In2.Cu")
		(net "PWRGD_P3V3_STBY_N")
	)
	(segment
		(start 99.9998 -147.2184)
		(end 99.9998 -152.6286)
		(width 0.127)
		(layer "In2.Cu")
		(net "PWRGD_P3V3_STBY_N")
	)
	(segment
		(start 100.6221 -146.651218)
		(end 100.347018 -146.9263)
		(width 0.127)
		(layer "In2.Cu")
		(net "PWRGD_P3V3_STBY_N")
	)
	(segment
		(start 100.6856 -138.557)
		(end 100.95611 -138.82751)
		(width 0.127)
		(layer "In2.Cu")
		(net "PWRGD_P3V3_STBY_N")
	)
	(segment
		(start 94.77756 -178.55184)
		(end 94.75724 -178.55184)
		(width 0.127)
		(layer "In2.Cu")
		(net "PWRGD_P3V3_STBY_N")
	)
	(segment
		(start 100.95611 -153.58491)
		(end 100.95611 -165.842696)
		(width 0.127)
		(layer "In2.Cu")
		(net "PWRGD_P3V3_STBY_N")
	)
	(segment
		(start 99.695 -168.712388)
		(end 100.076 -169.093388)
		(width 0.127)
		(layer "In2.Cu")
		(net "PWRGD_P3V3_STBY_N")
	)
	(segment
		(start 100.95611 -165.842696)
		(end 99.695 -167.103806)
		(width 0.127)
		(layer "In2.Cu")
		(net "PWRGD_P3V3_STBY_N")
	)
	(segment
		(start 99.695 -167.103806)
		(end 99.695 -168.712388)
		(width 0.127)
		(layer "In2.Cu")
		(net "PWRGD_P3V3_STBY_N")
	)
	(segment
		(start 97.480374 -177.165)
		(end 96.1644 -177.165)
		(width 0.127)
		(layer "In2.Cu")
		(net "PWRGD_P3V3_STBY_N")
	)
	(segment
		(start 96.1644 -177.165)
		(end 94.77756 -178.55184)
		(width 0.127)
		(layer "In2.Cu")
		(net "PWRGD_P3V3_STBY_N")
	)
	(segment
		(start 100.076 -174.569374)
		(end 99.15017 -175.495204)
		(width 0.127)
		(layer "In2.Cu")
		(net "PWRGD_P3V3_STBY_N")
	)
	(segment
		(start 99.9998 -152.6286)
		(end 100.95611 -153.58491)
		(width 0.127)
		(layer "In2.Cu")
		(net "PWRGD_P3V3_STBY_N")
	)
	(segment
		(start 100.347018 -146.9263)
		(end 100.2919 -146.9263)
		(width 0.127)
		(layer "In2.Cu")
		(net "PWRGD_P3V3_STBY_N")
	)
	(segment
		(start 92.265246 -141.82344)
		(end 90.571066 -141.82344)
		(width 0.127)
		(layer "In5.Cu")
		(net "PWRGD_P3V3_STBY_N")
	)
	(segment
		(start 96.776794 -139.954)
		(end 94.986094 -141.7447)
		(width 0.127)
		(layer "In5.Cu")
		(net "PWRGD_P3V3_STBY_N")
	)
	(segment
		(start 92.61094 -141.477746)
		(end 92.265246 -141.82344)
		(width 0.127)
		(layer "In5.Cu")
		(net "PWRGD_P3V3_STBY_N")
	)
	(segment
		(start 100.6856 -138.557)
		(end 100.386134 -138.557)
		(width 0.127)
		(layer "In5.Cu")
		(net "PWRGD_P3V3_STBY_N")
	)
	(segment
		(start 100.386134 -138.557)
		(end 98.989134 -139.954)
		(width 0.127)
		(layer "In5.Cu")
		(net "PWRGD_P3V3_STBY_N")
	)
	(segment
		(start 85.73135 -140.074904)
		(end 85.041994 -140.074904)
		(width 0.127)
		(layer "In5.Cu")
		(net "PWRGD_P3V3_STBY_N")
	)
	(segment
		(start 86.064344 -139.74191)
		(end 85.73135 -140.074904)
		(width 0.127)
		(layer "In5.Cu")
		(net "PWRGD_P3V3_STBY_N")
	)
	(segment
		(start 87.647526 -139.741656)
		(end 87.647272 -139.74191)
		(width 0.127)
		(layer "In5.Cu")
		(net "PWRGD_P3V3_STBY_N")
	)
	(segment
		(start 93.830394 -141.7447)
		(end 93.56344 -141.477746)
		(width 0.127)
		(layer "In5.Cu")
		(net "PWRGD_P3V3_STBY_N")
	)
	(segment
		(start 98.989134 -139.954)
		(end 96.776794 -139.954)
		(width 0.127)
		(layer "In5.Cu")
		(net "PWRGD_P3V3_STBY_N")
	)
	(segment
		(start 93.56344 -141.477746)
		(end 92.61094 -141.477746)
		(width 0.127)
		(layer "In5.Cu")
		(net "PWRGD_P3V3_STBY_N")
	)
	(segment
		(start 94.986094 -141.7447)
		(end 93.830394 -141.7447)
		(width 0.127)
		(layer "In5.Cu")
		(net "PWRGD_P3V3_STBY_N")
	)
	(segment
		(start 90.571066 -141.82344)
		(end 88.489282 -139.741656)
		(width 0.127)
		(layer "In5.Cu")
		(net "PWRGD_P3V3_STBY_N")
	)
	(segment
		(start 88.489282 -139.741656)
		(end 87.647526 -139.741656)
		(width 0.127)
		(layer "In5.Cu")
		(net "PWRGD_P3V3_STBY_N")
	)
	(segment
		(start 87.647272 -139.74191)
		(end 86.064344 -139.74191)
		(width 0.127)
		(layer "In5.Cu")
		(net "PWRGD_P3V3_STBY_N")
	)
	(segment
		(start 85.0646 -169.1259)
		(end 85.19795 -169.25925)
		(width 0.127)
		(layer "F.Cu")
		(net "P1V15_STBY_PG_G")
	)
	(segment
		(start 85.006942 -172.077888)
		(end 85.006942 -170.913044)
		(width 0.127)
		(layer "F.Cu")
		(net "P1V15_STBY_PG_G")
	)
	(segment
		(start 83.4644 -169.1259)
		(end 85.0646 -169.1259)
		(width 0.127)
		(layer "F.Cu")
		(net "P1V15_STBY_PG_G")
	)
	(segment
		(start 85.006942 -170.913044)
		(end 85.006942 -170.579542)
		(width 0.127)
		(layer "F.Cu")
		(net "P1V15_STBY_PG_G")
	)
	(segment
		(start 85.006942 -170.579542)
		(end 84.3534 -169.926)
		(width 0.127)
		(layer "F.Cu")
		(net "P1V15_STBY_PG_G")
	)
	(segment
		(start 83.4644 -169.5958)
		(end 83.4644 -169.1259)
		(width 0.127)
		(layer "F.Cu")
		(net "P1V15_STBY_PG_G")
	)
	(segment
		(start 85.19795 -169.25925)
		(end 86.1949 -169.25925)
		(width 0.127)
		(layer "F.Cu")
		(net "P1V15_STBY_PG_G")
	)
	(segment
		(start 83.7946 -169.926)
		(end 83.4644 -169.5958)
		(width 0.127)
		(layer "F.Cu")
		(net "P1V15_STBY_PG_G")
	)
	(segment
		(start 84.3534 -169.926)
		(end 83.7946 -169.926)
		(width 0.127)
		(layer "F.Cu")
		(net "P1V15_STBY_PG_G")
	)
	(via
		(at 85.006942 -170.913044)
		(size 0.6604)
		(drill 0.3302)
		(layers "F.Cu" "B.Cu")
		(net "P1V15_STBY_PG_G")
	)
	(segment
		(start 82.48015 -166.87165)
		(end 83.25612 -166.09568)
		(width 0.127)
		(layer "F.Cu")
		(net "P1V15_STBY_PG")
	)
	(segment
		(start 76.9874 -166.302944)
		(end 76.9874 -167.13962)
		(width 0.127)
		(layer "F.Cu")
		(net "P1V15_STBY_PG")
	)
	(segment
		(start 82.48015 -167.2209)
		(end 82.48015 -166.87165)
		(width 0.127)
		(layer "F.Cu")
		(net "P1V15_STBY_PG")
	)
	(segment
		(start 77.150214 -164.679122)
		(end 77.150214 -166.14013)
		(width 0.127)
		(layer "F.Cu")
		(net "P1V15_STBY_PG")
	)
	(segment
		(start 83.25612 -166.09568)
		(end 83.817206 -166.09568)
		(width 0.127)
		(layer "F.Cu")
		(net "P1V15_STBY_PG")
	)
	(segment
		(start 77.150214 -166.14013)
		(end 76.9874 -166.302944)
		(width 0.127)
		(layer "F.Cu")
		(net "P1V15_STBY_PG")
	)
	(segment
		(start 76.98232 -167.1447)
		(end 76.9874 -167.13962)
		(width 0.127)
		(layer "F.Cu")
		(net "P1V15_STBY_PG")
	)
	(segment
		(start 75.946 -167.1447)
		(end 76.98232 -167.1447)
		(width 0.127)
		(layer "F.Cu")
		(net "P1V15_STBY_PG")
	)
	(via
		(at 77.150214 -166.14013)
		(size 0.508)
		(drill 0.254)
		(layers "F.Cu" "B.Cu")
		(net "P1V15_STBY_PG")
	)
	(via
		(at 83.817206 -166.09568)
		(size 0.508)
		(drill 0.254)
		(layers "F.Cu" "B.Cu")
		(net "P1V15_STBY_PG")
	)
	(via
		(at 83.151472 -165.429946)
		(size 0.6096)
		(drill 0.3048)
		(layers "F.Cu" "B.Cu")
		(net "P1V15_STBY_PG")
	)
	(segment
		(start 82.966052 -165.244526)
		(end 83.151472 -165.429946)
		(width 0.127)
		(layer "B.Cu")
		(net "P1V15_STBY_PG")
	)
	(segment
		(start 83.151472 -165.429946)
		(end 83.817206 -166.09568)
		(width 0.127)
		(layer "B.Cu")
		(net "P1V15_STBY_PG")
	)
	(segment
		(start 77.150214 -165.704266)
		(end 77.609954 -165.244526)
		(width 0.127)
		(layer "B.Cu")
		(net "P1V15_STBY_PG")
	)
	(segment
		(start 77.150214 -166.14013)
		(end 77.150214 -165.704266)
		(width 0.127)
		(layer "B.Cu")
		(net "P1V15_STBY_PG")
	)
	(segment
		(start 77.609954 -165.244526)
		(end 82.966052 -165.244526)
		(width 0.127)
		(layer "B.Cu")
		(net "P1V15_STBY_PG")
	)
	(segment
		(start 53.0098 -136.975088)
		(end 52.774342 -136.975088)
		(width 0.127)
		(layer "F.Cu")
		(net "LPC_CPU_FRAME_N")
	)
	(segment
		(start 54.1147 -133.7564)
		(end 54.3433 -133.985)
		(width 0.127)
		(layer "F.Cu")
		(net "LPC_CPU_FRAME_N")
	)
	(segment
		(start 54.3433 -133.985)
		(end 54.3433 -135.429244)
		(width 0.127)
		(layer "F.Cu")
		(net "LPC_CPU_FRAME_N")
	)
	(segment
		(start 54.3433 -135.429244)
		(end 53.310028 -136.462516)
		(width 0.127)
		(layer "F.Cu")
		(net "LPC_CPU_FRAME_N")
	)
	(segment
		(start 53.310028 -136.462516)
		(end 53.310028 -136.67486)
		(width 0.127)
		(layer "F.Cu")
		(net "LPC_CPU_FRAME_N")
	)
	(segment
		(start 52.774342 -136.975088)
		(end 52.3494 -137.40003)
		(width 0.127)
		(layer "F.Cu")
		(net "LPC_CPU_FRAME_N")
	)
	(segment
		(start 52.3494 -137.40003)
		(end 52.099972 -137.40003)
		(width 0.127)
		(layer "F.Cu")
		(net "LPC_CPU_FRAME_N")
	)
	(segment
		(start 53.310028 -136.67486)
		(end 53.0098 -136.975088)
		(width 0.127)
		(layer "F.Cu")
		(net "LPC_CPU_FRAME_N")
	)
	(segment
		(start 54.0004 -132.1943)
		(end 54.1147 -132.3086)
		(width 0.127)
		(layer "F.Cu")
		(net "LPC_CPU_FRAME_N")
	)
	(segment
		(start 54.1147 -132.3086)
		(end 54.1147 -133.35)
		(width 0.127)
		(layer "F.Cu")
		(net "LPC_CPU_FRAME_N")
	)
	(segment
		(start 54.1147 -133.35)
		(end 54.1147 -133.7564)
		(width 0.127)
		(layer "F.Cu")
		(net "LPC_CPU_FRAME_N")
	)
	(via
		(at 54.1147 -133.35)
		(size 0.6604)
		(drill 0.3302)
		(layers "F.Cu" "B.Cu")
		(net "LPC_CPU_FRAME_N")
	)
	(segment
		(start 54.500018 -136.50468)
		(end 54.500018 -136.59993)
		(width 0.127)
		(layer "F.Cu")
		(net "LPC_CPU_CLKOUT0")
	)
	(segment
		(start 55.616856 -135.387842)
		(end 54.500018 -136.50468)
		(width 0.127)
		(layer "F.Cu")
		(net "LPC_CPU_CLKOUT0")
	)
	(segment
		(start 55.6895 -131.2037)
		(end 55.8292 -131.3434)
		(width 0.127)
		(layer "F.Cu")
		(net "LPC_CPU_CLKOUT0")
	)
	(segment
		(start 55.616856 -132.894324)
		(end 55.616856 -135.387842)
		(width 0.127)
		(layer "F.Cu")
		(net "LPC_CPU_CLKOUT0")
	)
	(segment
		(start 56.098948 -132.412232)
		(end 55.616856 -132.894324)
		(width 0.127)
		(layer "F.Cu")
		(net "LPC_CPU_CLKOUT0")
	)
	(segment
		(start 55.6895 -130.064764)
		(end 55.6895 -131.2037)
		(width 0.127)
		(layer "F.Cu")
		(net "LPC_CPU_CLKOUT0")
	)
	(segment
		(start 56.098948 -131.613148)
		(end 56.098948 -132.412232)
		(width 0.127)
		(layer "F.Cu")
		(net "LPC_CPU_CLKOUT0")
	)
	(segment
		(start 55.8292 -131.3434)
		(end 56.098948 -131.613148)
		(width 0.127)
		(layer "F.Cu")
		(net "LPC_CPU_CLKOUT0")
	)
	(via
		(at 55.8292 -131.3434)
		(size 0.6604)
		(drill 0.3302)
		(layers "F.Cu" "B.Cu")
		(net "LPC_CPU_CLKOUT0")
	)
	(segment
		(start 51.29784 -134.255256)
		(end 52.064666 -133.48843)
		(width 0.127)
		(layer "F.Cu")
		(net "IRQ_CPU_SERIAL")
	)
	(segment
		(start 51.29784 -135.533892)
		(end 51.29784 -134.255256)
		(width 0.127)
		(layer "F.Cu")
		(net "IRQ_CPU_SERIAL")
	)
	(segment
		(start 52.099972 -136.59993)
		(end 52.099972 -136.336024)
		(width 0.127)
		(layer "F.Cu")
		(net "IRQ_CPU_SERIAL")
	)
	(segment
		(start 52.064666 -132.544566)
		(end 51.689 -132.1689)
		(width 0.127)
		(layer "F.Cu")
		(net "IRQ_CPU_SERIAL")
	)
	(segment
		(start 52.099972 -136.336024)
		(end 51.29784 -135.533892)
		(width 0.127)
		(layer "F.Cu")
		(net "IRQ_CPU_SERIAL")
	)
	(segment
		(start 52.064666 -133.48843)
		(end 52.064666 -132.544566)
		(width 0.127)
		(layer "F.Cu")
		(net "IRQ_CPU_SERIAL")
	)
	(via
		(at 52.064666 -133.48843)
		(size 0.6604)
		(drill 0.3302)
		(layers "F.Cu" "B.Cu")
		(net "IRQ_CPU_SERIAL")
	)
	(segment
		(start 83.970622 -170.438826)
		(end 83.970622 -170.888152)
		(width 0.127)
		(layer "F.Cu")
		(net "EXP_UART_EN_R")
	)
	(segment
		(start 82.177382 -171.970954)
		(end 82.53095 -172.324522)
		(width 0.127)
		(layer "F.Cu")
		(net "EXP_UART_EN_R")
	)
	(segment
		(start 83.495642 -171.363132)
		(end 83.49234 -171.363132)
		(width 0.127)
		(layer "F.Cu")
		(net "EXP_UART_EN_R")
	)
	(segment
		(start 83.970622 -170.888152)
		(end 83.495642 -171.363132)
		(width 0.127)
		(layer "F.Cu")
		(net "EXP_UART_EN_R")
	)
	(segment
		(start 83.49234 -171.363132)
		(end 82.53095 -172.324522)
		(width 0.127)
		(layer "F.Cu")
		(net "EXP_UART_EN_R")
	)
	(segment
		(start 82.177382 -171.299378)
		(end 82.177382 -171.970954)
		(width 0.127)
		(layer "F.Cu")
		(net "EXP_UART_EN_R")
	)
	(via
		(at 83.970622 -170.438826)
		(size 0.508)
		(drill 0.254)
		(layers "F.Cu" "B.Cu")
		(net "EXP_UART_EN_R")
	)
	(via
		(at 83.495642 -171.363132)
		(size 0.6604)
		(drill 0.3302)
		(layers "F.Cu" "B.Cu")
		(net "EXP_UART_EN_R")
	)
	(segment
		(start 83.73618 -171.320206)
		(end 83.973416 -171.08297)
		(width 0.127)
		(layer "B.Cu")
		(net "EXP_UART_EN_R")
	)
	(segment
		(start 83.970622 -169.873422)
		(end 83.466686 -169.369486)
		(width 0.127)
		(layer "B.Cu")
		(net "EXP_UART_EN_R")
	)
	(segment
		(start 83.973416 -171.08297)
		(end 83.973416 -170.44162)
		(width 0.127)
		(layer "B.Cu")
		(net "EXP_UART_EN_R")
	)
	(segment
		(start 83.970622 -170.438826)
		(end 83.970622 -169.873422)
		(width 0.127)
		(layer "B.Cu")
		(net "EXP_UART_EN_R")
	)
	(segment
		(start 83.973416 -170.44162)
		(end 83.970622 -170.438826)
		(width 0.127)
		(layer "B.Cu")
		(net "EXP_UART_EN_R")
	)
	(segment
		(start 82.051906 -171.320206)
		(end 83.73618 -171.320206)
		(width 0.127)
		(layer "B.Cu")
		(net "EXP_UART_EN_R")
	)
	(segment
		(start 83.466686 -169.369486)
		(end 82.051906 -169.369486)
		(width 0.127)
		(layer "B.Cu")
		(net "EXP_UART_EN_R")
	)
	(segment
		(start 42.500042 -138.199622)
		(end 42.500042 -138.199876)
		(width 0.127)
		(layer "F.Cu")
		(net "EXP_UART_EN")
	)
	(segment
		(start 42.10685 -137.80643)
		(end 42.500042 -138.199622)
		(width 0.127)
		(layer "F.Cu")
		(net "EXP_UART_EN")
	)
	(segment
		(start 76.3778 -169.646092)
		(end 77.032866 -170.301158)
		(width 0.127)
		(layer "F.Cu")
		(net "EXP_UART_EN")
	)
	(segment
		(start 42.10685 -137.80897)
		(end 42.10685 -137.80643)
		(width 0.127)
		(layer "F.Cu")
		(net "EXP_UART_EN")
	)
	(segment
		(start 77.032866 -170.301158)
		(end 79.013304 -170.301158)
		(width 0.127)
		(layer "F.Cu")
		(net "EXP_UART_EN")
	)
	(segment
		(start 42.107358 -137.80897)
		(end 42.10685 -137.80897)
		(width 0.127)
		(layer "F.Cu")
		(net "EXP_UART_EN")
	)
	(segment
		(start 80.26527 -170.911012)
		(end 80.653636 -171.299378)
		(width 0.127)
		(layer "F.Cu")
		(net "EXP_UART_EN")
	)
	(segment
		(start 76.3778 -169.418)
		(end 76.3778 -169.646092)
		(width 0.127)
		(layer "F.Cu")
		(net "EXP_UART_EN")
	)
	(segment
		(start 79.623158 -170.911012)
		(end 80.26527 -170.911012)
		(width 0.127)
		(layer "F.Cu")
		(net "EXP_UART_EN")
	)
	(segment
		(start 79.013304 -170.301158)
		(end 79.623158 -170.911012)
		(width 0.127)
		(layer "F.Cu")
		(net "EXP_UART_EN")
	)
	(segment
		(start 80.653636 -171.299378)
		(end 81.288382 -171.299378)
		(width 0.127)
		(layer "F.Cu")
		(net "EXP_UART_EN")
	)
	(via
		(at 74.549 -132.7404)
		(size 0.508)
		(drill 0.254)
		(layers "F.Cu" "B.Cu")
		(net "EXP_UART_EN")
	)
	(via
		(at 77.032866 -170.301158)
		(size 0.6604)
		(drill 0.3302)
		(layers "F.Cu" "B.Cu")
		(net "EXP_UART_EN")
	)
	(via
		(at 76.3778 -169.418)
		(size 0.508)
		(drill 0.254)
		(layers "F.Cu" "B.Cu")
		(net "EXP_UART_EN")
	)
	(via
		(at 42.107358 -137.80897)
		(size 0.4572)
		(drill 0.2032)
		(layers "F.Cu" "B.Cu")
		(net "EXP_UART_EN")
	)
	(segment
		(start 73.7489 -143.73479)
		(end 73.7489 -136.756648)
		(width 0.127)
		(layer "In2.Cu")
		(net "EXP_UART_EN")
	)
	(segment
		(start 74.129138 -147.943316)
		(end 74.639424 -147.43303)
		(width 0.127)
		(layer "In2.Cu")
		(net "EXP_UART_EN")
	)
	(segment
		(start 74.3458 -166.19982)
		(end 72.86498 -164.719)
		(width 0.127)
		(layer "In2.Cu")
		(net "EXP_UART_EN")
	)
	(segment
		(start 74.639424 -147.43303)
		(end 74.639424 -144.625314)
		(width 0.127)
		(layer "In2.Cu")
		(net "EXP_UART_EN")
	)
	(segment
		(start 72.86498 -164.719)
		(end 72.86498 -159.57042)
		(width 0.127)
		(layer "In2.Cu")
		(net "EXP_UART_EN")
	)
	(segment
		(start 74.3458 -136.159748)
		(end 74.3458 -132.9436)
		(width 0.127)
		(layer "In2.Cu")
		(net "EXP_UART_EN")
	)
	(segment
		(start 74.3458 -168.4528)
		(end 74.3458 -166.19982)
		(width 0.127)
		(layer "In2.Cu")
		(net "EXP_UART_EN")
	)
	(segment
		(start 76.3778 -169.418)
		(end 75.311 -169.418)
		(width 0.127)
		(layer "In2.Cu")
		(net "EXP_UART_EN")
	)
	(segment
		(start 75.311 -169.418)
		(end 74.3458 -168.4528)
		(width 0.127)
		(layer "In2.Cu")
		(net "EXP_UART_EN")
	)
	(segment
		(start 74.129138 -158.306262)
		(end 74.129138 -147.943316)
		(width 0.127)
		(layer "In2.Cu")
		(net "EXP_UART_EN")
	)
	(segment
		(start 73.7489 -136.756648)
		(end 74.3458 -136.159748)
		(width 0.127)
		(layer "In2.Cu")
		(net "EXP_UART_EN")
	)
	(segment
		(start 72.86498 -159.57042)
		(end 74.129138 -158.306262)
		(width 0.127)
		(layer "In2.Cu")
		(net "EXP_UART_EN")
	)
	(segment
		(start 74.3458 -132.9436)
		(end 74.549 -132.7404)
		(width 0.127)
		(layer "In2.Cu")
		(net "EXP_UART_EN")
	)
	(segment
		(start 74.639424 -144.625314)
		(end 73.7489 -143.73479)
		(width 0.127)
		(layer "In2.Cu")
		(net "EXP_UART_EN")
	)
	(segment
		(start 74.097388 -132.8166)
		(end 65.532 -132.8166)
		(width 0.127)
		(layer "In5.Cu")
		(net "EXP_UART_EN")
	)
	(segment
		(start 58.363612 -134.4676)
		(end 55.8038 -134.4676)
		(width 0.127)
		(layer "In5.Cu")
		(net "EXP_UART_EN")
	)
	(segment
		(start 74.549 -132.7404)
		(end 74.173588 -132.7404)
		(width 0.127)
		(layer "In5.Cu")
		(net "EXP_UART_EN")
	)
	(segment
		(start 74.173588 -132.7404)
		(end 74.097388 -132.8166)
		(width 0.127)
		(layer "In5.Cu")
		(net "EXP_UART_EN")
	)
	(segment
		(start 55.385462 -134.885938)
		(end 50.727102 -134.885938)
		(width 0.127)
		(layer "In5.Cu")
		(net "EXP_UART_EN")
	)
	(segment
		(start 59.292744 -133.538468)
		(end 58.363612 -134.4676)
		(width 0.127)
		(layer "In5.Cu")
		(net "EXP_UART_EN")
	)
	(segment
		(start 64.810132 -133.538468)
		(end 59.292744 -133.538468)
		(width 0.127)
		(layer "In5.Cu")
		(net "EXP_UART_EN")
	)
	(segment
		(start 55.8038 -134.4676)
		(end 55.385462 -134.885938)
		(width 0.127)
		(layer "In5.Cu")
		(net "EXP_UART_EN")
	)
	(segment
		(start 43.829478 -134.5819)
		(end 42.107358 -136.30402)
		(width 0.127)
		(layer "In5.Cu")
		(net "EXP_UART_EN")
	)
	(segment
		(start 65.532 -132.8166)
		(end 64.810132 -133.538468)
		(width 0.127)
		(layer "In5.Cu")
		(net "EXP_UART_EN")
	)
	(segment
		(start 50.423064 -134.5819)
		(end 43.829478 -134.5819)
		(width 0.127)
		(layer "In5.Cu")
		(net "EXP_UART_EN")
	)
	(segment
		(start 50.727102 -134.885938)
		(end 50.423064 -134.5819)
		(width 0.127)
		(layer "In5.Cu")
		(net "EXP_UART_EN")
	)
	(segment
		(start 42.107358 -136.30402)
		(end 42.107358 -137.80897)
		(width 0.127)
		(layer "In5.Cu")
		(net "EXP_UART_EN")
	)
	(segment
		(start 96.6724 -171.6024)
		(end 95.8596 -172.4152)
		(width 0.127)
		(layer "F.Cu")
		(net "DPB_MISC_ALERT_OUT_R")
	)
	(segment
		(start 96.7232 -171.6024)
		(end 96.6724 -171.6024)
		(width 0.127)
		(layer "F.Cu")
		(net "DPB_MISC_ALERT_OUT_R")
	)
	(segment
		(start 95.8596 -172.4152)
		(end 95.0722 -172.4152)
		(width 0.127)
		(layer "F.Cu")
		(net "DPB_MISC_ALERT_OUT_R")
	)
	(segment
		(start 97.8535 -171.6024)
		(end 96.7232 -171.6024)
		(width 0.127)
		(layer "F.Cu")
		(net "DPB_MISC_ALERT_OUT_R")
	)
	(via
		(at 96.7232 -171.6024)
		(size 0.6604)
		(drill 0.3302)
		(layers "F.Cu" "B.Cu")
		(net "DPB_MISC_ALERT_OUT_R")
	)
	(segment
		(start 34.356548 -120.834404)
		(end 34.356548 -124.741686)
		(width 0.127)
		(layer "F.Cu")
		(net "CONN_A_PRSNTA")
	)
	(segment
		(start 42.078148 -136.977882)
		(end 42.500042 -137.399776)
		(width 0.127)
		(layer "F.Cu")
		(net "CONN_A_PRSNTA")
	)
	(segment
		(start 38.75659 -129.141728)
		(end 38.75659 -130.93319)
		(width 0.127)
		(layer "F.Cu")
		(net "CONN_A_PRSNTA")
	)
	(segment
		(start 40.308022 -133.310376)
		(end 40.308022 -134.273544)
		(width 0.127)
		(layer "F.Cu")
		(net "CONN_A_PRSNTA")
	)
	(segment
		(start 34.356548 -124.741686)
		(end 38.75659 -129.141728)
		(width 0.127)
		(layer "F.Cu")
		(net "CONN_A_PRSNTA")
	)
	(segment
		(start 38.75659 -130.93319)
		(end 39.3192 -131.4958)
		(width 0.127)
		(layer "F.Cu")
		(net "CONN_A_PRSNTA")
	)
	(segment
		(start 40.308022 -134.273544)
		(end 42.078148 -136.04367)
		(width 0.127)
		(layer "F.Cu")
		(net "CONN_A_PRSNTA")
	)
	(segment
		(start 42.500042 -137.399776)
		(end 42.500042 -137.40003)
		(width 0.127)
		(layer "F.Cu")
		(net "CONN_A_PRSNTA")
	)
	(segment
		(start 39.3192 -132.321554)
		(end 40.308022 -133.310376)
		(width 0.127)
		(layer "F.Cu")
		(net "CONN_A_PRSNTA")
	)
	(segment
		(start 39.3192 -131.4958)
		(end 39.3192 -132.321554)
		(width 0.127)
		(layer "F.Cu")
		(net "CONN_A_PRSNTA")
	)
	(segment
		(start 42.078148 -136.04367)
		(end 42.078148 -136.977882)
		(width 0.127)
		(layer "F.Cu")
		(net "CONN_A_PRSNTA")
	)
	(via
		(at 60.3504 -115.697)
		(size 0.508)
		(drill 0.254)
		(layers "F.Cu" "B.Cu")
		(net "CONN_A_PRSNTA")
	)
	(via
		(at 34.356548 -120.834404)
		(size 0.508)
		(drill 0.254)
		(layers "F.Cu" "B.Cu")
		(net "CONN_A_PRSNTA")
	)
	(via
		(at 60.7314 -114.427)
		(size 0.6096)
		(drill 0.3048)
		(layers "F.Cu" "B.Cu")
		(net "CONN_A_PRSNTA")
	)
	(segment
		(start 87.226648 -97.038922)
		(end 87.036148 -97.038922)
		(width 0.127)
		(layer "B.Cu")
		(net "CONN_A_PRSNTA")
	)
	(segment
		(start 89.9414 -96.896682)
		(end 88.866218 -95.8215)
		(width 0.127)
		(layer "B.Cu")
		(net "CONN_A_PRSNTA")
	)
	(segment
		(start 60.3504 -114.812572)
		(end 60.7314 -114.431572)
		(width 0.127)
		(layer "B.Cu")
		(net "CONN_A_PRSNTA")
	)
	(segment
		(start 60.3504 -115.697)
		(end 60.3504 -114.812572)
		(width 0.127)
		(layer "B.Cu")
		(net "CONN_A_PRSNTA")
	)
	(segment
		(start 86.520274 -97.554796)
		(end 86.520274 -97.745296)
		(width 0.127)
		(layer "B.Cu")
		(net "CONN_A_PRSNTA")
	)
	(segment
		(start 88.2523 -95.9612)
		(end 87.7951 -95.9612)
		(width 0.127)
		(layer "B.Cu")
		(net "CONN_A_PRSNTA")
	)
	(segment
		(start 88.866218 -95.8215)
		(end 88.392 -95.8215)
		(width 0.127)
		(layer "B.Cu")
		(net "CONN_A_PRSNTA")
	)
	(segment
		(start 89.9414 -105.664)
		(end 89.9414 -96.896682)
		(width 0.127)
		(layer "B.Cu")
		(net "CONN_A_PRSNTA")
	)
	(segment
		(start 66.003932 -113.665)
		(end 66.207132 -113.8682)
		(width 0.127)
		(layer "B.Cu")
		(net "CONN_A_PRSNTA")
	)
	(segment
		(start 60.7314 -114.427)
		(end 60.735972 -114.427)
		(width 0.127)
		(layer "B.Cu")
		(net "CONN_A_PRSNTA")
	)
	(segment
		(start 87.036148 -97.038922)
		(end 86.520274 -97.554796)
		(width 0.127)
		(layer "B.Cu")
		(net "CONN_A_PRSNTA")
	)
	(segment
		(start 60.7314 -114.431572)
		(end 60.7314 -114.427)
		(width 0.127)
		(layer "B.Cu")
		(net "CONN_A_PRSNTA")
	)
	(segment
		(start 69.019166 -112.8522)
		(end 74.295 -112.8522)
		(width 0.127)
		(layer "B.Cu")
		(net "CONN_A_PRSNTA")
	)
	(segment
		(start 87.7951 -95.9612)
		(end 87.7824 -95.9739)
		(width 0.127)
		(layer "B.Cu")
		(net "CONN_A_PRSNTA")
	)
	(segment
		(start 87.7824 -96.48317)
		(end 87.226648 -97.038922)
		(width 0.127)
		(layer "B.Cu")
		(net "CONN_A_PRSNTA")
	)
	(segment
		(start 68.003166 -113.8682)
		(end 69.019166 -112.8522)
		(width 0.127)
		(layer "B.Cu")
		(net "CONN_A_PRSNTA")
	)
	(segment
		(start 60.735972 -114.427)
		(end 61.497972 -113.665)
		(width 0.127)
		(layer "B.Cu")
		(net "CONN_A_PRSNTA")
	)
	(segment
		(start 66.207132 -113.8682)
		(end 68.003166 -113.8682)
		(width 0.127)
		(layer "B.Cu")
		(net "CONN_A_PRSNTA")
	)
	(segment
		(start 88.392 -95.8215)
		(end 88.2523 -95.9612)
		(width 0.127)
		(layer "B.Cu")
		(net "CONN_A_PRSNTA")
	)
	(segment
		(start 83.961986 -111.643414)
		(end 89.9414 -105.664)
		(width 0.127)
		(layer "B.Cu")
		(net "CONN_A_PRSNTA")
	)
	(segment
		(start 87.7824 -95.9739)
		(end 87.7824 -96.48317)
		(width 0.127)
		(layer "B.Cu")
		(net "CONN_A_PRSNTA")
	)
	(segment
		(start 61.497972 -113.665)
		(end 66.003932 -113.665)
		(width 0.127)
		(layer "B.Cu")
		(net "CONN_A_PRSNTA")
	)
	(segment
		(start 74.295 -112.8522)
		(end 75.503786 -111.643414)
		(width 0.127)
		(layer "B.Cu")
		(net "CONN_A_PRSNTA")
	)
	(segment
		(start 75.503786 -111.643414)
		(end 83.961986 -111.643414)
		(width 0.127)
		(layer "B.Cu")
		(net "CONN_A_PRSNTA")
	)
	(segment
		(start 35.308032 -119.88292)
		(end 34.356548 -120.834404)
		(width 0.127)
		(layer "In5.Cu")
		(net "CONN_A_PRSNTA")
	)
	(segment
		(start 57.94756 -115.436904)
		(end 46.996096 -115.436904)
		(width 0.127)
		(layer "In5.Cu")
		(net "CONN_A_PRSNTA")
	)
	(segment
		(start 46.0502 -116.3828)
		(end 42.76852 -116.3828)
		(width 0.127)
		(layer "In5.Cu")
		(net "CONN_A_PRSNTA")
	)
	(segment
		(start 58.207656 -115.697)
		(end 57.94756 -115.436904)
		(width 0.127)
		(layer "In5.Cu")
		(net "CONN_A_PRSNTA")
	)
	(segment
		(start 46.996096 -115.436904)
		(end 46.0502 -116.3828)
		(width 0.127)
		(layer "In5.Cu")
		(net "CONN_A_PRSNTA")
	)
	(segment
		(start 39.2684 -119.88292)
		(end 35.308032 -119.88292)
		(width 0.127)
		(layer "In5.Cu")
		(net "CONN_A_PRSNTA")
	)
	(segment
		(start 42.76852 -116.3828)
		(end 39.2684 -119.88292)
		(width 0.127)
		(layer "In5.Cu")
		(net "CONN_A_PRSNTA")
	)
	(segment
		(start 60.3504 -115.697)
		(end 58.207656 -115.697)
		(width 0.127)
		(layer "In5.Cu")
		(net "CONN_A_PRSNTA")
	)
	(segment
		(start 90.7669 -169.05732)
		(end 89.110566 -169.05732)
		(width 0.127)
		(layer "B.Cu")
		(net "UART_COMP_IN_RX_AND_R")
	)
	(segment
		(start 89.110566 -169.05732)
		(end 88.7984 -169.369486)
		(width 0.127)
		(layer "B.Cu")
		(net "UART_COMP_IN_RX_AND_R")
	)
	(segment
		(start 88.7984 -169.369486)
		(end 87.690706 -169.369486)
		(width 0.127)
		(layer "B.Cu")
		(net "UART_COMP_IN_RX_AND_R")
	)
	(segment
		(start 93.2307 -127.841756)
		(end 93.2307 -128.515618)
		(width 0.127)
		(layer "F.Cu")
		(net "UART_COMP_IN_RX_AND")
	)
	(segment
		(start 95.31604 -125.756416)
		(end 93.2307 -127.841756)
		(width 0.127)
		(layer "F.Cu")
		(net "UART_COMP_IN_RX_AND")
	)
	(segment
		(start 93.2307 -128.515618)
		(end 94.109032 -129.39395)
		(width 0.127)
		(layer "F.Cu")
		(net "UART_COMP_IN_RX_AND")
	)
	(segment
		(start 94.109032 -132.615432)
		(end 94.629732 -133.136132)
		(width 0.127)
		(layer "F.Cu")
		(net "UART_COMP_IN_RX_AND")
	)
	(segment
		(start 94.629732 -136.742932)
		(end 94.7166 -136.8298)
		(width 0.127)
		(layer "F.Cu")
		(net "UART_COMP_IN_RX_AND")
	)
	(segment
		(start 94.109032 -129.39395)
		(end 94.109032 -132.615432)
		(width 0.127)
		(layer "F.Cu")
		(net "UART_COMP_IN_RX_AND")
	)
	(segment
		(start 95.31604 -125.4125)
		(end 95.31604 -125.756416)
		(width 0.127)
		(layer "F.Cu")
		(net "UART_COMP_IN_RX_AND")
	)
	(segment
		(start 94.629732 -133.136132)
		(end 94.629732 -136.742932)
		(width 0.127)
		(layer "F.Cu")
		(net "UART_COMP_IN_RX_AND")
	)
	(via
		(at 94.7166 -136.8298)
		(size 0.508)
		(drill 0.254)
		(layers "F.Cu" "B.Cu")
		(net "UART_COMP_IN_RX_AND")
	)
	(via
		(at 95.675704 -144.3736)
		(size 0.6096)
		(drill 0.3048)
		(layers "F.Cu" "B.Cu")
		(net "UART_COMP_IN_RX_AND")
	)
	(segment
		(start 93.5482 -141.351)
		(end 95.675704 -143.478504)
		(width 0.127)
		(layer "B.Cu")
		(net "UART_COMP_IN_RX_AND")
	)
	(segment
		(start 93.5482 -137.85469)
		(end 93.5482 -141.351)
		(width 0.127)
		(layer "B.Cu")
		(net "UART_COMP_IN_RX_AND")
	)
	(segment
		(start 95.675704 -143.478504)
		(end 95.675704 -144.3736)
		(width 0.127)
		(layer "B.Cu")
		(net "UART_COMP_IN_RX_AND")
	)
	(segment
		(start 96.816164 -159.613092)
		(end 96.816164 -159.723836)
		(width 0.127)
		(layer "B.Cu")
		(net "UART_COMP_IN_RX_AND")
	)
	(segment
		(start 95.675704 -144.3736)
		(end 95.675704 -144.824704)
		(width 0.127)
		(layer "B.Cu")
		(net "UART_COMP_IN_RX_AND")
	)
	(segment
		(start 96.14027 -168.65727)
		(end 93.29293 -168.65727)
		(width 0.127)
		(layer "B.Cu")
		(net "UART_COMP_IN_RX_AND")
	)
	(segment
		(start 93.29293 -168.65727)
		(end 92.89288 -169.05732)
		(width 0.127)
		(layer "B.Cu")
		(net "UART_COMP_IN_RX_AND")
	)
	(segment
		(start 98.1837 -156.163518)
		(end 98.1837 -158.245556)
		(width 0.127)
		(layer "B.Cu")
		(net "UART_COMP_IN_RX_AND")
	)
	(segment
		(start 96.816164 -159.723836)
		(end 96.803718 -159.736282)
		(width 0.127)
		(layer "B.Cu")
		(net "UART_COMP_IN_RX_AND")
	)
	(segment
		(start 94.57309 -136.8298)
		(end 93.5482 -137.85469)
		(width 0.127)
		(layer "B.Cu")
		(net "UART_COMP_IN_RX_AND")
	)
	(segment
		(start 95.675704 -144.824704)
		(end 96.156272 -145.305272)
		(width 0.127)
		(layer "B.Cu")
		(net "UART_COMP_IN_RX_AND")
	)
	(segment
		(start 92.89288 -169.05732)
		(end 91.6559 -169.05732)
		(width 0.127)
		(layer "B.Cu")
		(net "UART_COMP_IN_RX_AND")
	)
	(segment
		(start 97.878392 -155.85821)
		(end 98.1837 -156.163518)
		(width 0.127)
		(layer "B.Cu")
		(net "UART_COMP_IN_RX_AND")
	)
	(segment
		(start 97.878392 -150.456392)
		(end 97.878392 -155.85821)
		(width 0.127)
		(layer "B.Cu")
		(net "UART_COMP_IN_RX_AND")
	)
	(segment
		(start 96.156272 -148.734272)
		(end 97.878392 -150.456392)
		(width 0.127)
		(layer "B.Cu")
		(net "UART_COMP_IN_RX_AND")
	)
	(segment
		(start 94.7166 -136.8298)
		(end 94.57309 -136.8298)
		(width 0.127)
		(layer "B.Cu")
		(net "UART_COMP_IN_RX_AND")
	)
	(segment
		(start 96.803718 -159.736282)
		(end 96.803718 -167.993822)
		(width 0.127)
		(layer "B.Cu")
		(net "UART_COMP_IN_RX_AND")
	)
	(segment
		(start 96.803718 -167.993822)
		(end 96.14027 -168.65727)
		(width 0.127)
		(layer "B.Cu")
		(net "UART_COMP_IN_RX_AND")
	)
	(segment
		(start 98.1837 -158.245556)
		(end 96.816164 -159.613092)
		(width 0.127)
		(layer "B.Cu")
		(net "UART_COMP_IN_RX_AND")
	)
	(segment
		(start 96.156272 -145.305272)
		(end 96.156272 -148.734272)
		(width 0.127)
		(layer "B.Cu")
		(net "UART_COMP_IN_RX_AND")
	)
	(segment
		(start 93.328744 -121.911872)
		(end 92.316808 -121.911872)
		(width 0.127)
		(layer "F.Cu")
		(net "UART_COMP_IN_R_RX")
	)
	(segment
		(start 93.671644 -123.7615)
		(end 93.358208 -123.448064)
		(width 0.127)
		(layer "F.Cu")
		(net "UART_COMP_IN_R_RX")
	)
	(segment
		(start 93.358208 -121.941336)
		(end 93.328744 -121.911872)
		(width 0.127)
		(layer "F.Cu")
		(net "UART_COMP_IN_R_RX")
	)
	(segment
		(start 92.316808 -121.911872)
		(end 92.215208 -122.013472)
		(width 0.127)
		(layer "F.Cu")
		(net "UART_COMP_IN_R_RX")
	)
	(segment
		(start 94.01556 -123.7615)
		(end 93.671644 -123.7615)
		(width 0.127)
		(layer "F.Cu")
		(net "UART_COMP_IN_R_RX")
	)
	(segment
		(start 93.358208 -123.448064)
		(end 93.358208 -121.941336)
		(width 0.127)
		(layer "F.Cu")
		(net "UART_COMP_IN_R_RX")
	)
	(via
		(at 93.358208 -121.941336)
		(size 0.6604)
		(drill 0.3302)
		(layers "F.Cu" "B.Cu")
		(net "UART_COMP_IN_R_RX")
	)
	(segment
		(start 94.5642 -121.6406)
		(end 94.5642 -122.158506)
		(width 0.127)
		(layer "F.Cu")
		(net "UART_BMC_COMP_IN_RX_R")
	)
	(segment
		(start 94.5642 -122.158506)
		(end 94.447106 -122.2756)
		(width 0.127)
		(layer "F.Cu")
		(net "UART_BMC_COMP_IN_RX_R")
	)
	(segment
		(start 94.447106 -122.2756)
		(end 94.447106 -123.022106)
		(width 0.127)
		(layer "F.Cu")
		(net "UART_BMC_COMP_IN_RX_R")
	)
	(segment
		(start 93.398594 -120.774714)
		(end 93.80728 -121.1834)
		(width 0.127)
		(layer "F.Cu")
		(net "UART_BMC_COMP_IN_RX_R")
	)
	(segment
		(start 94.107 -121.1834)
		(end 94.5642 -121.6406)
		(width 0.127)
		(layer "F.Cu")
		(net "UART_BMC_COMP_IN_RX_R")
	)
	(segment
		(start 93.80728 -121.1834)
		(end 94.107 -121.1834)
		(width 0.127)
		(layer "F.Cu")
		(net "UART_BMC_COMP_IN_RX_R")
	)
	(segment
		(start 94.6658 -123.2408)
		(end 94.6658 -123.7615)
		(width 0.127)
		(layer "F.Cu")
		(net "UART_BMC_COMP_IN_RX_R")
	)
	(segment
		(start 94.447106 -123.022106)
		(end 94.6658 -123.2408)
		(width 0.127)
		(layer "F.Cu")
		(net "UART_BMC_COMP_IN_RX_R")
	)
	(via
		(at 94.5642 -121.6406)
		(size 0.6604)
		(drill 0.3302)
		(layers "F.Cu" "B.Cu")
		(net "UART_BMC_COMP_IN_RX_R")
	)
	(segment
		(start 39.243 -160.033716)
		(end 39.243 -159.9184)
		(width 0.127)
		(layer "F.Cu")
		(net "UART_BMC_COMP_IN_RX")
	)
	(segment
		(start 40.259 -155.2448)
		(end 41.656 -153.8478)
		(width 0.127)
		(layer "F.Cu")
		(net "UART_BMC_COMP_IN_RX")
	)
	(segment
		(start 40.259 -157.283912)
		(end 40.259 -155.2448)
		(width 0.127)
		(layer "F.Cu")
		(net "UART_BMC_COMP_IN_RX")
	)
	(segment
		(start 38.321488 -160.955228)
		(end 39.243 -160.033716)
		(width 0.127)
		(layer "F.Cu")
		(net "UART_BMC_COMP_IN_RX")
	)
	(segment
		(start 92.509594 -120.774714)
		(end 91.789504 -120.774714)
		(width 0.127)
		(layer "F.Cu")
		(net "UART_BMC_COMP_IN_RX")
	)
	(segment
		(start 41.656 -153.8478)
		(end 42.05224 -153.8478)
		(width 0.127)
		(layer "F.Cu")
		(net "UART_BMC_COMP_IN_RX")
	)
	(segment
		(start 39.9923 -157.550612)
		(end 40.259 -157.283912)
		(width 0.127)
		(layer "F.Cu")
		(net "UART_BMC_COMP_IN_RX")
	)
	(segment
		(start 91.789504 -120.774714)
		(end 91.697302 -120.682512)
		(width 0.127)
		(layer "F.Cu")
		(net "UART_BMC_COMP_IN_RX")
	)
	(segment
		(start 42.05224 -153.8478)
		(end 42.500042 -153.399998)
		(width 0.127)
		(layer "F.Cu")
		(net "UART_BMC_COMP_IN_RX")
	)
	(segment
		(start 39.9923 -159.1691)
		(end 39.9923 -157.550612)
		(width 0.127)
		(layer "F.Cu")
		(net "UART_BMC_COMP_IN_RX")
	)
	(segment
		(start 39.243 -159.9184)
		(end 39.9923 -159.1691)
		(width 0.127)
		(layer "F.Cu")
		(net "UART_BMC_COMP_IN_RX")
	)
	(via
		(at 39.243 -159.9184)
		(size 0.508)
		(drill 0.254)
		(layers "F.Cu" "B.Cu")
		(net "UART_BMC_COMP_IN_RX")
	)
	(via
		(at 57.285128 -114.311938)
		(size 0.508)
		(drill 0.254)
		(layers "F.Cu" "B.Cu")
		(net "UART_BMC_COMP_IN_RX")
	)
	(via
		(at 17.9578 -159.766)
		(size 0.508)
		(drill 0.254)
		(layers "F.Cu" "B.Cu")
		(net "UART_BMC_COMP_IN_RX")
	)
	(via
		(at 39.9923 -159.1691)
		(size 0.6604)
		(drill 0.3302)
		(layers "F.Cu" "B.Cu")
		(net "UART_BMC_COMP_IN_RX")
	)
	(via
		(at 91.697302 -120.682512)
		(size 0.508)
		(drill 0.254)
		(layers "F.Cu" "B.Cu")
		(net "UART_BMC_COMP_IN_RX")
	)
	(segment
		(start 39.243 -159.9184)
		(end 39.13251 -159.9184)
		(width 0.127)
		(layer "B.Cu")
		(net "UART_BMC_COMP_IN_RX")
	)
	(segment
		(start 81.880202 -125.143514)
		(end 86.341204 -120.682512)
		(width 0.127)
		(layer "B.Cu")
		(net "UART_BMC_COMP_IN_RX")
	)
	(segment
		(start 63.270638 -118.144798)
		(end 63.33744 -118.2116)
		(width 0.127)
		(layer "B.Cu")
		(net "UART_BMC_COMP_IN_RX")
	)
	(segment
		(start 34.6964 -162.3568)
		(end 33.8582 -163.195)
		(width 0.127)
		(layer "B.Cu")
		(net "UART_BMC_COMP_IN_RX")
	)
	(segment
		(start 35.0139 -161.18967)
		(end 34.6964 -161.50717)
		(width 0.127)
		(layer "B.Cu")
		(net "UART_BMC_COMP_IN_RX")
	)
	(segment
		(start 39.13251 -159.9184)
		(end 38.08984 -160.96107)
		(width 0.127)
		(layer "B.Cu")
		(net "UART_BMC_COMP_IN_RX")
	)
	(segment
		(start 33.8582 -163.195)
		(end 25.9588 -163.195)
		(width 0.127)
		(layer "B.Cu")
		(net "UART_BMC_COMP_IN_RX")
	)
	(segment
		(start 86.341204 -120.682512)
		(end 91.697302 -120.682512)
		(width 0.127)
		(layer "B.Cu")
		(net "UART_BMC_COMP_IN_RX")
	)
	(segment
		(start 19.361658 -161.169858)
		(end 17.9578 -159.766)
		(width 0.127)
		(layer "B.Cu")
		(net "UART_BMC_COMP_IN_RX")
	)
	(segment
		(start 25.9588 -163.195)
		(end 23.933658 -161.169858)
		(width 0.127)
		(layer "B.Cu")
		(net "UART_BMC_COMP_IN_RX")
	)
	(segment
		(start 36.647374 -160.96107)
		(end 36.418774 -161.18967)
		(width 0.127)
		(layer "B.Cu")
		(net "UART_BMC_COMP_IN_RX")
	)
	(segment
		(start 34.6964 -161.50717)
		(end 34.6964 -162.3568)
		(width 0.127)
		(layer "B.Cu")
		(net "UART_BMC_COMP_IN_RX")
	)
	(segment
		(start 71.0438 -118.2116)
		(end 77.975714 -125.143514)
		(width 0.127)
		(layer "B.Cu")
		(net "UART_BMC_COMP_IN_RX")
	)
	(segment
		(start 63.33744 -118.2116)
		(end 71.0438 -118.2116)
		(width 0.127)
		(layer "B.Cu")
		(net "UART_BMC_COMP_IN_RX")
	)
	(segment
		(start 57.285128 -114.311938)
		(end 61.117988 -118.144798)
		(width 0.127)
		(layer "B.Cu")
		(net "UART_BMC_COMP_IN_RX")
	)
	(segment
		(start 36.418774 -161.18967)
		(end 35.0139 -161.18967)
		(width 0.127)
		(layer "B.Cu")
		(net "UART_BMC_COMP_IN_RX")
	)
	(segment
		(start 61.117988 -118.144798)
		(end 63.270638 -118.144798)
		(width 0.127)
		(layer "B.Cu")
		(net "UART_BMC_COMP_IN_RX")
	)
	(segment
		(start 23.933658 -161.169858)
		(end 19.361658 -161.169858)
		(width 0.127)
		(layer "B.Cu")
		(net "UART_BMC_COMP_IN_RX")
	)
	(segment
		(start 38.08984 -160.96107)
		(end 36.647374 -160.96107)
		(width 0.127)
		(layer "B.Cu")
		(net "UART_BMC_COMP_IN_RX")
	)
	(segment
		(start 77.975714 -125.143514)
		(end 81.880202 -125.143514)
		(width 0.127)
		(layer "B.Cu")
		(net "UART_BMC_COMP_IN_RX")
	)
	(segment
		(start 3.58648 -124.033026)
		(end 3.58648 -149.310852)
		(width 0.127)
		(layer "In5.Cu")
		(net "UART_BMC_COMP_IN_RX")
	)
	(segment
		(start 57.285128 -114.311938)
		(end 56.89219 -113.919)
		(width 0.127)
		(layer "In5.Cu")
		(net "UART_BMC_COMP_IN_RX")
	)
	(segment
		(start 3.586226 -124.032772)
		(end 3.58648 -124.033026)
		(width 0.127)
		(layer "In5.Cu")
		(net "UART_BMC_COMP_IN_RX")
	)
	(segment
		(start 39.1668 -112.903)
		(end 33.13938 -112.903)
		(width 0.127)
		(layer "In5.Cu")
		(net "UART_BMC_COMP_IN_RX")
	)
	(segment
		(start 3.58648 -123.506738)
		(end 3.586226 -123.506992)
		(width 0.127)
		(layer "In5.Cu")
		(net "UART_BMC_COMP_IN_RX")
	)
	(segment
		(start 56.89219 -113.919)
		(end 40.1828 -113.919)
		(width 0.127)
		(layer "In5.Cu")
		(net "UART_BMC_COMP_IN_RX")
	)
	(segment
		(start 13.69695 -112.4204)
		(end 3.58648 -122.53087)
		(width 0.127)
		(layer "In5.Cu")
		(net "UART_BMC_COMP_IN_RX")
	)
	(segment
		(start 3.58648 -149.310852)
		(end 14.041628 -159.766)
		(width 0.127)
		(layer "In5.Cu")
		(net "UART_BMC_COMP_IN_RX")
	)
	(segment
		(start 40.1828 -113.919)
		(end 39.1668 -112.903)
		(width 0.127)
		(layer "In5.Cu")
		(net "UART_BMC_COMP_IN_RX")
	)
	(segment
		(start 33.13938 -112.903)
		(end 30.7975 -115.24488)
		(width 0.127)
		(layer "In5.Cu")
		(net "UART_BMC_COMP_IN_RX")
	)
	(segment
		(start 29.366464 -115.24488)
		(end 26.410158 -112.288574)
		(width 0.127)
		(layer "In5.Cu")
		(net "UART_BMC_COMP_IN_RX")
	)
	(segment
		(start 14.672818 -112.4204)
		(end 13.69695 -112.4204)
		(width 0.127)
		(layer "In5.Cu")
		(net "UART_BMC_COMP_IN_RX")
	)
	(segment
		(start 3.58648 -122.53087)
		(end 3.58648 -123.506738)
		(width 0.127)
		(layer "In5.Cu")
		(net "UART_BMC_COMP_IN_RX")
	)
	(segment
		(start 14.804644 -112.288574)
		(end 14.672818 -112.4204)
		(width 0.127)
		(layer "In5.Cu")
		(net "UART_BMC_COMP_IN_RX")
	)
	(segment
		(start 26.410158 -112.288574)
		(end 14.804644 -112.288574)
		(width 0.127)
		(layer "In5.Cu")
		(net "UART_BMC_COMP_IN_RX")
	)
	(segment
		(start 3.586226 -123.506992)
		(end 3.586226 -124.032772)
		(width 0.127)
		(layer "In5.Cu")
		(net "UART_BMC_COMP_IN_RX")
	)
	(segment
		(start 14.041628 -159.766)
		(end 17.9578 -159.766)
		(width 0.127)
		(layer "In5.Cu")
		(net "UART_BMC_COMP_IN_RX")
	)
	(segment
		(start 30.7975 -115.24488)
		(end 29.366464 -115.24488)
		(width 0.127)
		(layer "In5.Cu")
		(net "UART_BMC_COMP_IN_RX")
	)
	(via
		(at 80.4037 -168.4655)
		(size 0.6096)
		(drill 0.3048)
		(layers "F.Cu" "B.Cu")
		(net "UART_SDB_TX_R")
	)
	(segment
		(start 79.248 -168.4655)
		(end 80.4037 -168.4655)
		(width 0.127)
		(layer "B.Cu")
		(net "UART_SDB_TX_R")
	)
	(segment
		(start 80.4037 -168.4655)
		(end 80.8863 -168.4655)
		(width 0.127)
		(layer "B.Cu")
		(net "UART_SDB_TX_R")
	)
	(segment
		(start 80.8863 -168.4655)
		(end 81.140046 -168.719246)
		(width 0.127)
		(layer "B.Cu")
		(net "UART_SDB_TX_R")
	)
	(segment
		(start 81.140046 -168.719246)
		(end 82.051906 -168.719246)
		(width 0.127)
		(layer "B.Cu")
		(net "UART_SDB_TX_R")
	)
	(segment
		(start 56.22417 -138.596624)
		(end 55.703216 -138.596624)
		(width 0.127)
		(layer "F.Cu")
		(net "TP_BMC_EXT2_LED_G")
	)
	(segment
		(start 59.857132 -135.702548)
		(end 59.118246 -135.702548)
		(width 0.127)
		(layer "F.Cu")
		(net "TP_BMC_EXT2_LED_G")
	)
	(segment
		(start 59.118246 -135.702548)
		(end 56.22417 -138.596624)
		(width 0.127)
		(layer "F.Cu")
		(net "TP_BMC_EXT2_LED_G")
	)
	(segment
		(start 55.703216 -138.596624)
		(end 55.299864 -138.999976)
		(width 0.127)
		(layer "F.Cu")
		(net "TP_BMC_EXT2_LED_G")
	)
	(segment
		(start 57.9374 -136.36244)
		(end 56.099964 -138.199876)
		(width 0.127)
		(layer "F.Cu")
		(net "TP_BMC_EXT2_LED_B")
	)
	(segment
		(start 59.294776 -134.434326)
		(end 57.9374 -135.791702)
		(width 0.127)
		(layer "F.Cu")
		(net "TP_BMC_EXT2_LED_B")
	)
	(segment
		(start 57.9374 -135.791702)
		(end 57.9374 -136.36244)
		(width 0.127)
		(layer "F.Cu")
		(net "TP_BMC_EXT2_LED_B")
	)
	(segment
		(start 60.494672 -134.434326)
		(end 59.294776 -134.434326)
		(width 0.127)
		(layer "F.Cu")
		(net "TP_BMC_EXT2_LED_B")
	)
	(segment
		(start 53.699918 -138.999976)
		(end 54.099968 -138.599926)
		(width 0.127)
		(layer "F.Cu")
		(net "TP_BMC_EXT1_LED_G")
	)
	(via
		(at 54.099968 -138.599926)
		(size 0.4572)
		(drill 0.2032)
		(layers "F.Cu" "B.Cu")
		(net "TP_BMC_EXT1_LED_G")
	)
	(segment
		(start 55.866284 -137.406126)
		(end 55.536592 -137.406126)
		(width 0.127)
		(layer "B.Cu")
		(net "TP_BMC_EXT1_LED_G")
	)
	(segment
		(start 57.837578 -136.828022)
		(end 57.2008 -137.4648)
		(width 0.127)
		(layer "B.Cu")
		(net "TP_BMC_EXT1_LED_G")
	)
	(segment
		(start 55.063136 -138.193526)
		(end 54.749446 -138.193526)
		(width 0.127)
		(layer "B.Cu")
		(net "TP_BMC_EXT1_LED_G")
	)
	(segment
		(start 54.140862 -138.559032)
		(end 54.099968 -138.599926)
		(width 0.127)
		(layer "B.Cu")
		(net "TP_BMC_EXT1_LED_G")
	)
	(segment
		(start 54.749446 -138.193526)
		(end 54.38394 -138.559032)
		(width 0.127)
		(layer "B.Cu")
		(net "TP_BMC_EXT1_LED_G")
	)
	(segment
		(start 55.536592 -137.406126)
		(end 55.306214 -137.636504)
		(width 0.127)
		(layer "B.Cu")
		(net "TP_BMC_EXT1_LED_G")
	)
	(segment
		(start 57.2008 -137.4648)
		(end 55.924958 -137.4648)
		(width 0.127)
		(layer "B.Cu")
		(net "TP_BMC_EXT1_LED_G")
	)
	(segment
		(start 60.01004 -134.96036)
		(end 58.142378 -136.828022)
		(width 0.127)
		(layer "B.Cu")
		(net "TP_BMC_EXT1_LED_G")
	)
	(segment
		(start 54.38394 -138.559032)
		(end 54.140862 -138.559032)
		(width 0.127)
		(layer "B.Cu")
		(net "TP_BMC_EXT1_LED_G")
	)
	(segment
		(start 55.306214 -137.950448)
		(end 55.063136 -138.193526)
		(width 0.127)
		(layer "B.Cu")
		(net "TP_BMC_EXT1_LED_G")
	)
	(segment
		(start 60.01004 -134.410958)
		(end 60.01004 -134.96036)
		(width 0.127)
		(layer "B.Cu")
		(net "TP_BMC_EXT1_LED_G")
	)
	(segment
		(start 55.306214 -137.636504)
		(end 55.306214 -137.950448)
		(width 0.127)
		(layer "B.Cu")
		(net "TP_BMC_EXT1_LED_G")
	)
	(segment
		(start 58.142378 -136.828022)
		(end 57.837578 -136.828022)
		(width 0.127)
		(layer "B.Cu")
		(net "TP_BMC_EXT1_LED_G")
	)
	(segment
		(start 55.924958 -137.4648)
		(end 55.866284 -137.406126)
		(width 0.127)
		(layer "B.Cu")
		(net "TP_BMC_EXT1_LED_G")
	)
	(segment
		(start 52.899818 -139.800076)
		(end 53.299868 -139.400026)
		(width 0.127)
		(layer "F.Cu")
		(net "TP_BMC_EXT1_LED_B")
	)
	(via
		(at 53.299868 -139.400026)
		(size 0.4572)
		(drill 0.2032)
		(layers "F.Cu" "B.Cu")
		(net "TP_BMC_EXT1_LED_B")
	)
	(segment
		(start 57.410604 -137.6934)
		(end 56.363362 -137.6934)
		(width 0.127)
		(layer "B.Cu")
		(net "TP_BMC_EXT1_LED_B")
	)
	(segment
		(start 55.293768 -138.762994)
		(end 55.293768 -138.763248)
		(width 0.127)
		(layer "B.Cu")
		(net "TP_BMC_EXT1_LED_B")
	)
	(segment
		(start 53.380132 -139.400026)
		(end 53.299868 -139.400026)
		(width 0.127)
		(layer "B.Cu")
		(net "TP_BMC_EXT1_LED_B")
	)
	(segment
		(start 55.06339 -138.993626)
		(end 53.786532 -138.993626)
		(width 0.127)
		(layer "B.Cu")
		(net "TP_BMC_EXT1_LED_B")
	)
	(segment
		(start 56.363362 -137.6934)
		(end 55.293768 -138.762994)
		(width 0.127)
		(layer "B.Cu")
		(net "TP_BMC_EXT1_LED_B")
	)
	(segment
		(start 59.962796 -136.357614)
		(end 59.171586 -136.357614)
		(width 0.127)
		(layer "B.Cu")
		(net "TP_BMC_EXT1_LED_B")
	)
	(segment
		(start 53.786532 -138.993626)
		(end 53.380132 -139.400026)
		(width 0.127)
		(layer "B.Cu")
		(net "TP_BMC_EXT1_LED_B")
	)
	(segment
		(start 57.842404 -137.2616)
		(end 57.410604 -137.6934)
		(width 0.127)
		(layer "B.Cu")
		(net "TP_BMC_EXT1_LED_B")
	)
	(segment
		(start 55.293768 -138.763248)
		(end 55.06339 -138.993626)
		(width 0.127)
		(layer "B.Cu")
		(net "TP_BMC_EXT1_LED_B")
	)
	(segment
		(start 59.171586 -136.357614)
		(end 58.2676 -137.2616)
		(width 0.127)
		(layer "B.Cu")
		(net "TP_BMC_EXT1_LED_B")
	)
	(segment
		(start 58.2676 -137.2616)
		(end 57.842404 -137.2616)
		(width 0.127)
		(layer "B.Cu")
		(net "TP_BMC_EXT1_LED_B")
	)
	(segment
		(start 88.000078 -21.480018)
		(end 88.000078 -22.369526)
		(width 0.508)
		(layer "F.Cu")
		(net "P5V_VBUS_CONN")
	)
	(segment
		(start 87.11057 -21.480018)
		(end 88.000078 -21.480018)
		(width 0.508)
		(layer "F.Cu")
		(net "P5V_VBUS_CONN")
	)
	(segment
		(start 88.000078 -21.480018)
		(end 88.889586 -21.480018)
		(width 0.508)
		(layer "F.Cu")
		(net "P5V_VBUS_CONN")
	)
	(segment
		(start 88.000078 -20.59051)
		(end 88.000078 -21.480018)
		(width 0.508)
		(layer "F.Cu")
		(net "P5V_VBUS_CONN")
	)
	(segment
		(start 212.085936 -94.238826)
		(end 211.025486 -94.238826)
		(width 0.254)
		(layer "F.Cu")
		(net "P3V3_M2_VFB_R")
	)
	(segment
		(start 213.098888 -94.238826)
		(end 212.085936 -94.238826)
		(width 0.254)
		(layer "F.Cu")
		(net "P3V3_M2_VFB_R")
	)
	(segment
		(start 211.025486 -94.238826)
		(end 209.948272 -94.238826)
		(width 0.254)
		(layer "F.Cu")
		(net "P3V3_M2_VFB_R")
	)
	(via
		(at 211.025486 -94.238826)
		(size 0.6604)
		(drill 0.3302)
		(layers "F.Cu" "B.Cu")
		(net "P3V3_M2_VFB_R")
	)
	(segment
		(start 96.58604 -172.6692)
		(end 96.1898 -173.06544)
		(width 0.127)
		(layer "F.Cu")
		(net "I2C_DPB_MISC_SDA_R")
	)
	(segment
		(start 96.7232 -172.6692)
		(end 96.58604 -172.6692)
		(width 0.127)
		(layer "F.Cu")
		(net "I2C_DPB_MISC_SDA_R")
	)
	(segment
		(start 97.8535 -172.6692)
		(end 96.7232 -172.6692)
		(width 0.127)
		(layer "F.Cu")
		(net "I2C_DPB_MISC_SDA_R")
	)
	(segment
		(start 96.1898 -173.06544)
		(end 95.0722 -173.06544)
		(width 0.127)
		(layer "F.Cu")
		(net "I2C_DPB_MISC_SDA_R")
	)
	(via
		(at 96.7232 -172.6692)
		(size 0.6604)
		(drill 0.3302)
		(layers "F.Cu" "B.Cu")
		(net "I2C_DPB_MISC_SDA_R")
	)
	(segment
		(start 88.376506 -173.007528)
		(end 88.376506 -173.482254)
		(width 0.127)
		(layer "F.Cu")
		(net "I2C_DPB_MISC_SDA_OUT")
	)
	(segment
		(start 87.620094 -172.76826)
		(end 87.03183 -173.356524)
		(width 0.127)
		(layer "F.Cu")
		(net "I2C_DPB_MISC_SDA_OUT")
	)
	(segment
		(start 48.05299 -159.0421)
		(end 48.0187 -159.0421)
		(width 0.127)
		(layer "F.Cu")
		(net "I2C_DPB_MISC_SDA_OUT")
	)
	(segment
		(start 88.609932 -173.71568)
		(end 89.4334 -173.71568)
		(width 0.127)
		(layer "F.Cu")
		(net "I2C_DPB_MISC_SDA_OUT")
	)
	(segment
		(start 87.800434 -172.76826)
		(end 88.137238 -172.76826)
		(width 0.127)
		(layer "F.Cu")
		(net "I2C_DPB_MISC_SDA_OUT")
	)
	(segment
		(start 88.376506 -173.482254)
		(end 88.609932 -173.71568)
		(width 0.127)
		(layer "F.Cu")
		(net "I2C_DPB_MISC_SDA_OUT")
	)
	(segment
		(start 88.137238 -172.76826)
		(end 88.376506 -173.007528)
		(width 0.127)
		(layer "F.Cu")
		(net "I2C_DPB_MISC_SDA_OUT")
	)
	(segment
		(start 47.491904 -160.786572)
		(end 47.491904 -160.318704)
		(width 0.127)
		(layer "F.Cu")
		(net "I2C_DPB_MISC_SDA_OUT")
	)
	(segment
		(start 48.0187 -159.0421)
		(end 47.117 -159.9438)
		(width 0.127)
		(layer "F.Cu")
		(net "I2C_DPB_MISC_SDA_OUT")
	)
	(segment
		(start 47.491904 -160.318704)
		(end 47.117 -159.9438)
		(width 0.127)
		(layer "F.Cu")
		(net "I2C_DPB_MISC_SDA_OUT")
	)
	(segment
		(start 87.800434 -172.76826)
		(end 87.620094 -172.76826)
		(width 0.127)
		(layer "F.Cu")
		(net "I2C_DPB_MISC_SDA_OUT")
	)
	(via
		(at 87.03183 -173.356524)
		(size 0.508)
		(drill 0.254)
		(layers "F.Cu" "B.Cu")
		(net "I2C_DPB_MISC_SDA_OUT")
	)
	(via
		(at 47.117 -159.9438)
		(size 0.508)
		(drill 0.254)
		(layers "F.Cu" "B.Cu")
		(net "I2C_DPB_MISC_SDA_OUT")
	)
	(via
		(at 85.720174 -182.833772)
		(size 0.508)
		(drill 0.254)
		(layers "F.Cu" "B.Cu")
		(net "I2C_DPB_MISC_SDA_OUT")
	)
	(via
		(at 46.2788 -180.1876)
		(size 0.508)
		(drill 0.254)
		(layers "F.Cu" "B.Cu")
		(net "I2C_DPB_MISC_SDA_OUT")
	)
	(via
		(at 87.800434 -172.76826)
		(size 0.6604)
		(drill 0.3302)
		(layers "F.Cu" "B.Cu")
		(net "I2C_DPB_MISC_SDA_OUT")
	)
	(segment
		(start 47.5996 -161.163)
		(end 47.117 -160.6804)
		(width 0.127)
		(layer "In2.Cu")
		(net "I2C_DPB_MISC_SDA_OUT")
	)
	(segment
		(start 46.2788 -173.7106)
		(end 47.5996 -172.3898)
		(width 0.127)
		(layer "In2.Cu")
		(net "I2C_DPB_MISC_SDA_OUT")
	)
	(segment
		(start 47.117 -160.6804)
		(end 47.117 -159.9438)
		(width 0.127)
		(layer "In2.Cu")
		(net "I2C_DPB_MISC_SDA_OUT")
	)
	(segment
		(start 87.03183 -173.356524)
		(end 86.4235 -173.964854)
		(width 0.127)
		(layer "In2.Cu")
		(net "I2C_DPB_MISC_SDA_OUT")
	)
	(segment
		(start 46.2788 -180.1876)
		(end 46.2788 -173.7106)
		(width 0.127)
		(layer "In2.Cu")
		(net "I2C_DPB_MISC_SDA_OUT")
	)
	(segment
		(start 86.4235 -182.130446)
		(end 85.720174 -182.833772)
		(width 0.127)
		(layer "In2.Cu")
		(net "I2C_DPB_MISC_SDA_OUT")
	)
	(segment
		(start 47.5996 -172.3898)
		(end 47.5996 -161.163)
		(width 0.127)
		(layer "In2.Cu")
		(net "I2C_DPB_MISC_SDA_OUT")
	)
	(segment
		(start 86.4235 -173.964854)
		(end 86.4235 -182.130446)
		(width 0.127)
		(layer "In2.Cu")
		(net "I2C_DPB_MISC_SDA_OUT")
	)
	(segment
		(start 63.586106 -181.2925)
		(end 47.3837 -181.2925)
		(width 0.127)
		(layer "In5.Cu")
		(net "I2C_DPB_MISC_SDA_OUT")
	)
	(segment
		(start 83.019646 -185.5343)
		(end 67.827906 -185.5343)
		(width 0.127)
		(layer "In5.Cu")
		(net "I2C_DPB_MISC_SDA_OUT")
	)
	(segment
		(start 47.3837 -181.2925)
		(end 46.2788 -180.1876)
		(width 0.127)
		(layer "In5.Cu")
		(net "I2C_DPB_MISC_SDA_OUT")
	)
	(segment
		(start 67.827906 -185.5343)
		(end 63.586106 -181.2925)
		(width 0.127)
		(layer "In5.Cu")
		(net "I2C_DPB_MISC_SDA_OUT")
	)
	(segment
		(start 85.720174 -182.833772)
		(end 83.019646 -185.5343)
		(width 0.127)
		(layer "In5.Cu")
		(net "I2C_DPB_MISC_SDA_OUT")
	)
	(segment
		(start 97.0534 -173.760384)
		(end 97.103184 -173.7106)
		(width 0.127)
		(layer "F.Cu")
		(net "I2C_DPB_MISC_SCL_R")
	)
	(segment
		(start 96.1136 -173.71568)
		(end 96.158304 -173.760384)
		(width 0.127)
		(layer "F.Cu")
		(net "I2C_DPB_MISC_SCL_R")
	)
	(segment
		(start 96.6978 -173.760384)
		(end 97.0534 -173.760384)
		(width 0.127)
		(layer "F.Cu")
		(net "I2C_DPB_MISC_SCL_R")
	)
	(segment
		(start 96.158304 -173.760384)
		(end 96.6978 -173.760384)
		(width 0.127)
		(layer "F.Cu")
		(net "I2C_DPB_MISC_SCL_R")
	)
	(segment
		(start 95.0722 -173.71568)
		(end 96.1136 -173.71568)
		(width 0.127)
		(layer "F.Cu")
		(net "I2C_DPB_MISC_SCL_R")
	)
	(segment
		(start 97.103184 -173.7106)
		(end 97.8789 -173.7106)
		(width 0.127)
		(layer "F.Cu")
		(net "I2C_DPB_MISC_SCL_R")
	)
	(via
		(at 96.6978 -173.760384)
		(size 0.6604)
		(drill 0.3302)
		(layers "F.Cu" "B.Cu")
		(net "I2C_DPB_MISC_SCL_R")
	)
	(segment
		(start 88.532716 -174.36592)
		(end 89.4334 -174.36592)
		(width 0.127)
		(layer "F.Cu")
		(net "I2C_DPB_MISC_SCL_OUT")
	)
	(segment
		(start 49.09439 -159.0421)
		(end 48.855884 -159.0421)
		(width 0.127)
		(layer "F.Cu")
		(net "I2C_DPB_MISC_SCL_OUT")
	)
	(segment
		(start 88.006936 -173.84014)
		(end 88.532716 -174.36592)
		(width 0.127)
		(layer "F.Cu")
		(net "I2C_DPB_MISC_SCL_OUT")
	)
	(segment
		(start 48.855884 -159.0421)
		(end 47.980346 -159.917638)
		(width 0.127)
		(layer "F.Cu")
		(net "I2C_DPB_MISC_SCL_OUT")
	)
	(segment
		(start 48.533304 -160.470596)
		(end 47.980346 -159.917638)
		(width 0.127)
		(layer "F.Cu")
		(net "I2C_DPB_MISC_SCL_OUT")
	)
	(segment
		(start 87.878158 -173.84014)
		(end 88.006936 -173.84014)
		(width 0.127)
		(layer "F.Cu")
		(net "I2C_DPB_MISC_SCL_OUT")
	)
	(segment
		(start 87.005668 -174.239682)
		(end 87.40521 -173.84014)
		(width 0.127)
		(layer "F.Cu")
		(net "I2C_DPB_MISC_SCL_OUT")
	)
	(segment
		(start 48.533304 -160.819592)
		(end 48.533304 -160.470596)
		(width 0.127)
		(layer "F.Cu")
		(net "I2C_DPB_MISC_SCL_OUT")
	)
	(segment
		(start 87.40521 -173.84014)
		(end 87.878158 -173.84014)
		(width 0.127)
		(layer "F.Cu")
		(net "I2C_DPB_MISC_SCL_OUT")
	)
	(via
		(at 47.141892 -180.155596)
		(size 0.508)
		(drill 0.254)
		(layers "F.Cu" "B.Cu")
		(net "I2C_DPB_MISC_SCL_OUT")
	)
	(via
		(at 87.005668 -174.239682)
		(size 0.508)
		(drill 0.254)
		(layers "F.Cu" "B.Cu")
		(net "I2C_DPB_MISC_SCL_OUT")
	)
	(via
		(at 47.980346 -159.917638)
		(size 0.508)
		(drill 0.254)
		(layers "F.Cu" "B.Cu")
		(net "I2C_DPB_MISC_SCL_OUT")
	)
	(via
		(at 87.878158 -173.84014)
		(size 0.6604)
		(drill 0.3302)
		(layers "F.Cu" "B.Cu")
		(net "I2C_DPB_MISC_SCL_OUT")
	)
	(via
		(at 86.920832 -181.5973)
		(size 0.508)
		(drill 0.254)
		(layers "F.Cu" "B.Cu")
		(net "I2C_DPB_MISC_SCL_OUT")
	)
	(segment
		(start 47.141892 -180.155596)
		(end 47.141892 -173.566074)
		(width 0.127)
		(layer "In2.Cu")
		(net "I2C_DPB_MISC_SCL_OUT")
	)
	(segment
		(start 48.641 -161.0614)
		(end 47.980346 -160.400746)
		(width 0.127)
		(layer "In2.Cu")
		(net "I2C_DPB_MISC_SCL_OUT")
	)
	(segment
		(start 48.641 -163.1696)
		(end 48.641 -161.0614)
		(width 0.127)
		(layer "In2.Cu")
		(net "I2C_DPB_MISC_SCL_OUT")
	)
	(segment
		(start 48.1076 -172.600366)
		(end 48.1076 -163.703)
		(width 0.127)
		(layer "In2.Cu")
		(net "I2C_DPB_MISC_SCL_OUT")
	)
	(segment
		(start 48.1076 -163.703)
		(end 48.641 -163.1696)
		(width 0.127)
		(layer "In2.Cu")
		(net "I2C_DPB_MISC_SCL_OUT")
	)
	(segment
		(start 87.005668 -181.512464)
		(end 87.005668 -174.239682)
		(width 0.127)
		(layer "In2.Cu")
		(net "I2C_DPB_MISC_SCL_OUT")
	)
	(segment
		(start 47.141892 -173.566074)
		(end 48.1076 -172.600366)
		(width 0.127)
		(layer "In2.Cu")
		(net "I2C_DPB_MISC_SCL_OUT")
	)
	(segment
		(start 47.980346 -160.400746)
		(end 47.980346 -159.917638)
		(width 0.127)
		(layer "In2.Cu")
		(net "I2C_DPB_MISC_SCL_OUT")
	)
	(segment
		(start 86.920832 -181.5973)
		(end 87.005668 -181.512464)
		(width 0.127)
		(layer "In2.Cu")
		(net "I2C_DPB_MISC_SCL_OUT")
	)
	(segment
		(start 63.796672 -180.7845)
		(end 47.820072 -180.7845)
		(width 0.127)
		(layer "In5.Cu")
		(net "I2C_DPB_MISC_SCL_OUT")
	)
	(segment
		(start 85.229192 -182.232808)
		(end 82.4357 -185.0263)
		(width 0.127)
		(layer "In5.Cu")
		(net "I2C_DPB_MISC_SCL_OUT")
	)
	(segment
		(start 47.820072 -180.7845)
		(end 47.191168 -180.155596)
		(width 0.127)
		(layer "In5.Cu")
		(net "I2C_DPB_MISC_SCL_OUT")
	)
	(segment
		(start 82.4357 -185.0263)
		(end 68.038472 -185.0263)
		(width 0.127)
		(layer "In5.Cu")
		(net "I2C_DPB_MISC_SCL_OUT")
	)
	(segment
		(start 47.191168 -180.155596)
		(end 47.141892 -180.155596)
		(width 0.127)
		(layer "In5.Cu")
		(net "I2C_DPB_MISC_SCL_OUT")
	)
	(segment
		(start 86.920832 -181.5973)
		(end 86.285324 -182.232808)
		(width 0.127)
		(layer "In5.Cu")
		(net "I2C_DPB_MISC_SCL_OUT")
	)
	(segment
		(start 68.038472 -185.0263)
		(end 63.796672 -180.7845)
		(width 0.127)
		(layer "In5.Cu")
		(net "I2C_DPB_MISC_SCL_OUT")
	)
	(segment
		(start 86.285324 -182.232808)
		(end 85.229192 -182.232808)
		(width 0.127)
		(layer "In5.Cu")
		(net "I2C_DPB_MISC_SCL_OUT")
	)
	(segment
		(start 42.500042 -150.199852)
		(end 42.099992 -150.599902)
		(width 0.127)
		(layer "F.Cu")
		(net "FLA0_WP_N_R")
	)
	(segment
		(start 28.8036 -156.8196)
		(end 28.591002 -156.8196)
		(width 0.127)
		(layer "F.Cu")
		(net "FLA0_WP_N_R")
	)
	(segment
		(start 28.591002 -156.8196)
		(end 27.863546 -157.547056)
		(width 0.127)
		(layer "F.Cu")
		(net "FLA0_WP_N_R")
	)
	(via
		(at 42.099992 -150.599902)
		(size 0.4572)
		(drill 0.2032)
		(layers "F.Cu" "B.Cu")
		(net "FLA0_WP_N_R")
	)
	(via
		(at 28.8036 -156.8196)
		(size 0.508)
		(drill 0.254)
		(layers "F.Cu" "B.Cu")
		(net "FLA0_WP_N_R")
	)
	(segment
		(start 30.225746 -156.8196)
		(end 31.698946 -158.2928)
		(width 0.127)
		(layer "In2.Cu")
		(net "FLA0_WP_N_R")
	)
	(segment
		(start 38.383464 -155.4353)
		(end 38.730936 -155.4353)
		(width 0.127)
		(layer "In2.Cu")
		(net "FLA0_WP_N_R")
	)
	(segment
		(start 34.978594 -158.2928)
		(end 36.251388 -157.020006)
		(width 0.127)
		(layer "In2.Cu")
		(net "FLA0_WP_N_R")
	)
	(segment
		(start 36.251388 -157.020006)
		(end 36.798758 -157.020006)
		(width 0.127)
		(layer "In2.Cu")
		(net "FLA0_WP_N_R")
	)
	(segment
		(start 31.698946 -158.2928)
		(end 34.978594 -158.2928)
		(width 0.127)
		(layer "In2.Cu")
		(net "FLA0_WP_N_R")
	)
	(segment
		(start 41.463214 -151.793702)
		(end 41.694354 -151.562562)
		(width 0.127)
		(layer "In2.Cu")
		(net "FLA0_WP_N_R")
	)
	(segment
		(start 36.798758 -157.020006)
		(end 38.383464 -155.4353)
		(width 0.127)
		(layer "In2.Cu")
		(net "FLA0_WP_N_R")
	)
	(segment
		(start 40.906192 -153.260044)
		(end 40.906192 -152.03678)
		(width 0.127)
		(layer "In2.Cu")
		(net "FLA0_WP_N_R")
	)
	(segment
		(start 41.694354 -151.00554)
		(end 42.099992 -150.599902)
		(width 0.127)
		(layer "In2.Cu")
		(net "FLA0_WP_N_R")
	)
	(segment
		(start 28.8036 -156.8196)
		(end 30.225746 -156.8196)
		(width 0.127)
		(layer "In2.Cu")
		(net "FLA0_WP_N_R")
	)
	(segment
		(start 41.14927 -151.793702)
		(end 41.463214 -151.793702)
		(width 0.127)
		(layer "In2.Cu")
		(net "FLA0_WP_N_R")
	)
	(segment
		(start 41.694354 -151.562562)
		(end 41.694354 -151.00554)
		(width 0.127)
		(layer "In2.Cu")
		(net "FLA0_WP_N_R")
	)
	(segment
		(start 40.906192 -152.03678)
		(end 41.14927 -151.793702)
		(width 0.127)
		(layer "In2.Cu")
		(net "FLA0_WP_N_R")
	)
	(segment
		(start 38.730936 -155.4353)
		(end 40.906192 -153.260044)
		(width 0.127)
		(layer "In2.Cu")
		(net "FLA0_WP_N_R")
	)
	(segment
		(start 28.8036 -157.8356)
		(end 28.616402 -157.8356)
		(width 0.127)
		(layer "F.Cu")
		(net "DEBUG_GPIO_BMC_R_6")
	)
	(segment
		(start 28.616402 -157.8356)
		(end 27.863546 -158.588456)
		(width 0.127)
		(layer "F.Cu")
		(net "DEBUG_GPIO_BMC_R_6")
	)
	(segment
		(start 42.500042 -150.999952)
		(end 42.099992 -151.400002)
		(width 0.127)
		(layer "F.Cu")
		(net "DEBUG_GPIO_BMC_R_6")
	)
	(via
		(at 28.8036 -157.8356)
		(size 0.508)
		(drill 0.254)
		(layers "F.Cu" "B.Cu")
		(net "DEBUG_GPIO_BMC_R_6")
	)
	(via
		(at 42.099992 -151.400002)
		(size 0.4572)
		(drill 0.2032)
		(layers "F.Cu" "B.Cu")
		(net "DEBUG_GPIO_BMC_R_6")
	)
	(segment
		(start 38.27272 -157.78988)
		(end 39.1668 -156.8958)
		(width 0.127)
		(layer "In2.Cu")
		(net "DEBUG_GPIO_BMC_R_6")
	)
	(segment
		(start 42.099992 -151.575008)
		(end 42.099992 -151.400002)
		(width 0.127)
		(layer "In2.Cu")
		(net "DEBUG_GPIO_BMC_R_6")
	)
	(segment
		(start 41.693592 -152.795986)
		(end 41.693592 -151.981408)
		(width 0.127)
		(layer "In2.Cu")
		(net "DEBUG_GPIO_BMC_R_6")
	)
	(segment
		(start 39.1668 -155.322778)
		(end 41.693592 -152.795986)
		(width 0.127)
		(layer "In2.Cu")
		(net "DEBUG_GPIO_BMC_R_6")
	)
	(segment
		(start 36.20008 -157.78988)
		(end 38.27272 -157.78988)
		(width 0.127)
		(layer "In2.Cu")
		(net "DEBUG_GPIO_BMC_R_6")
	)
	(segment
		(start 29.6164 -157.8356)
		(end 30.5816 -158.8008)
		(width 0.127)
		(layer "In2.Cu")
		(net "DEBUG_GPIO_BMC_R_6")
	)
	(segment
		(start 35.18916 -158.8008)
		(end 36.20008 -157.78988)
		(width 0.127)
		(layer "In2.Cu")
		(net "DEBUG_GPIO_BMC_R_6")
	)
	(segment
		(start 30.5816 -158.8008)
		(end 35.18916 -158.8008)
		(width 0.127)
		(layer "In2.Cu")
		(net "DEBUG_GPIO_BMC_R_6")
	)
	(segment
		(start 28.8036 -157.8356)
		(end 29.6164 -157.8356)
		(width 0.127)
		(layer "In2.Cu")
		(net "DEBUG_GPIO_BMC_R_6")
	)
	(segment
		(start 39.1668 -156.8958)
		(end 39.1668 -155.322778)
		(width 0.127)
		(layer "In2.Cu")
		(net "DEBUG_GPIO_BMC_R_6")
	)
	(segment
		(start 41.693592 -151.981408)
		(end 42.099992 -151.575008)
		(width 0.127)
		(layer "In2.Cu")
		(net "DEBUG_GPIO_BMC_R_6")
	)
	(segment
		(start 27.863546 -155.464256)
		(end 27.863546 -156.034232)
		(width 0.127)
		(layer "F.Cu")
		(net "DEBUG_GPIO_BMC_R_5")
	)
	(segment
		(start 42.500042 -149.400006)
		(end 42.099992 -149.800056)
		(width 0.127)
		(layer "F.Cu")
		(net "DEBUG_GPIO_BMC_R_5")
	)
	(segment
		(start 27.863546 -156.034232)
		(end 27.466798 -156.43098)
		(width 0.127)
		(layer "F.Cu")
		(net "DEBUG_GPIO_BMC_R_5")
	)
	(via
		(at 27.466798 -156.43098)
		(size 0.508)
		(drill 0.254)
		(layers "F.Cu" "B.Cu")
		(net "DEBUG_GPIO_BMC_R_5")
	)
	(via
		(at 42.099992 -149.800056)
		(size 0.4572)
		(drill 0.2032)
		(layers "F.Cu" "B.Cu")
		(net "DEBUG_GPIO_BMC_R_5")
	)
	(segment
		(start 38.789356 -154.467814)
		(end 38.243764 -154.467814)
		(width 0.127)
		(layer "In2.Cu")
		(net "DEBUG_GPIO_BMC_R_5")
	)
	(segment
		(start 40.894 -150.448772)
		(end 40.894 -151.562816)
		(width 0.127)
		(layer "In2.Cu")
		(net "DEBUG_GPIO_BMC_R_5")
	)
	(segment
		(start 41.149016 -150.193756)
		(end 40.894 -150.448772)
		(width 0.127)
		(layer "In2.Cu")
		(net "DEBUG_GPIO_BMC_R_5")
	)
	(segment
		(start 41.856914 -149.800056)
		(end 41.463214 -150.193756)
		(width 0.127)
		(layer "In2.Cu")
		(net "DEBUG_GPIO_BMC_R_5")
	)
	(segment
		(start 33.505394 -156.512006)
		(end 32.7152 -157.3022)
		(width 0.127)
		(layer "In2.Cu")
		(net "DEBUG_GPIO_BMC_R_5")
	)
	(segment
		(start 40.894 -151.562816)
		(end 40.650414 -151.806402)
		(width 0.127)
		(layer "In2.Cu")
		(net "DEBUG_GPIO_BMC_R_5")
	)
	(segment
		(start 38.243764 -154.467814)
		(end 37.783262 -154.928316)
		(width 0.127)
		(layer "In2.Cu")
		(net "DEBUG_GPIO_BMC_R_5")
	)
	(segment
		(start 37.783262 -155.316936)
		(end 36.588192 -156.512006)
		(width 0.127)
		(layer "In2.Cu")
		(net "DEBUG_GPIO_BMC_R_5")
	)
	(segment
		(start 27.624024 -156.273754)
		(end 27.466798 -156.43098)
		(width 0.127)
		(layer "In2.Cu")
		(net "DEBUG_GPIO_BMC_R_5")
	)
	(segment
		(start 30.398466 -156.273754)
		(end 27.624024 -156.273754)
		(width 0.127)
		(layer "In2.Cu")
		(net "DEBUG_GPIO_BMC_R_5")
	)
	(segment
		(start 40.106092 -152.03678)
		(end 40.106092 -153.151078)
		(width 0.127)
		(layer "In2.Cu")
		(net "DEBUG_GPIO_BMC_R_5")
	)
	(segment
		(start 40.650414 -151.806402)
		(end 40.33647 -151.806402)
		(width 0.127)
		(layer "In2.Cu")
		(net "DEBUG_GPIO_BMC_R_5")
	)
	(segment
		(start 31.426912 -157.3022)
		(end 30.398466 -156.273754)
		(width 0.127)
		(layer "In2.Cu")
		(net "DEBUG_GPIO_BMC_R_5")
	)
	(segment
		(start 40.106092 -153.151078)
		(end 38.789356 -154.467814)
		(width 0.127)
		(layer "In2.Cu")
		(net "DEBUG_GPIO_BMC_R_5")
	)
	(segment
		(start 41.463214 -150.193756)
		(end 41.149016 -150.193756)
		(width 0.127)
		(layer "In2.Cu")
		(net "DEBUG_GPIO_BMC_R_5")
	)
	(segment
		(start 42.099992 -149.800056)
		(end 41.856914 -149.800056)
		(width 0.127)
		(layer "In2.Cu")
		(net "DEBUG_GPIO_BMC_R_5")
	)
	(segment
		(start 36.588192 -156.512006)
		(end 33.505394 -156.512006)
		(width 0.127)
		(layer "In2.Cu")
		(net "DEBUG_GPIO_BMC_R_5")
	)
	(segment
		(start 40.33647 -151.806402)
		(end 40.106092 -152.03678)
		(width 0.127)
		(layer "In2.Cu")
		(net "DEBUG_GPIO_BMC_R_5")
	)
	(segment
		(start 37.783262 -154.928316)
		(end 37.783262 -155.316936)
		(width 0.127)
		(layer "In2.Cu")
		(net "DEBUG_GPIO_BMC_R_5")
	)
	(segment
		(start 32.7152 -157.3022)
		(end 31.426912 -157.3022)
		(width 0.127)
		(layer "In2.Cu")
		(net "DEBUG_GPIO_BMC_R_5")
	)
	(segment
		(start 28.810204 -154.745436)
		(end 28.810204 -154.519122)
		(width 0.127)
		(layer "F.Cu")
		(net "DEBUG_GPIO_BMC_R_4")
	)
	(segment
		(start 41.699942 -149.400006)
		(end 41.299892 -149.800056)
		(width 0.127)
		(layer "F.Cu")
		(net "DEBUG_GPIO_BMC_R_4")
	)
	(segment
		(start 28.810204 -154.519122)
		(end 27.863546 -153.572464)
		(width 0.127)
		(layer "F.Cu")
		(net "DEBUG_GPIO_BMC_R_4")
	)
	(segment
		(start 27.863546 -153.572464)
		(end 27.863546 -153.381456)
		(width 0.127)
		(layer "F.Cu")
		(net "DEBUG_GPIO_BMC_R_4")
	)
	(via
		(at 41.299892 -149.800056)
		(size 0.4572)
		(drill 0.2032)
		(layers "F.Cu" "B.Cu")
		(net "DEBUG_GPIO_BMC_R_4")
	)
	(via
		(at 28.810204 -154.745436)
		(size 0.508)
		(drill 0.254)
		(layers "F.Cu" "B.Cu")
		(net "DEBUG_GPIO_BMC_R_4")
	)
	(segment
		(start 38.121336 -153.823924)
		(end 38.121336 -153.079958)
		(width 0.127)
		(layer "In2.Cu")
		(net "DEBUG_GPIO_BMC_R_4")
	)
	(segment
		(start 33.250632 -154.9527)
		(end 34.047938 -155.750006)
		(width 0.127)
		(layer "In2.Cu")
		(net "DEBUG_GPIO_BMC_R_4")
	)
	(segment
		(start 28.810204 -154.745436)
		(end 29.487622 -155.422854)
		(width 0.127)
		(layer "In2.Cu")
		(net "DEBUG_GPIO_BMC_R_4")
	)
	(segment
		(start 29.487622 -155.422854)
		(end 31.013146 -155.422854)
		(width 0.127)
		(layer "In2.Cu")
		(net "DEBUG_GPIO_BMC_R_4")
	)
	(segment
		(start 31.013146 -155.422854)
		(end 31.4833 -154.9527)
		(width 0.127)
		(layer "In2.Cu")
		(net "DEBUG_GPIO_BMC_R_4")
	)
	(segment
		(start 39.877492 -150.66518)
		(end 40.33647 -150.206202)
		(width 0.127)
		(layer "In2.Cu")
		(net "DEBUG_GPIO_BMC_R_4")
	)
	(segment
		(start 34.047938 -155.750006)
		(end 36.195254 -155.750006)
		(width 0.127)
		(layer "In2.Cu")
		(net "DEBUG_GPIO_BMC_R_4")
	)
	(segment
		(start 41.080944 -149.800056)
		(end 41.299892 -149.800056)
		(width 0.127)
		(layer "In2.Cu")
		(net "DEBUG_GPIO_BMC_R_4")
	)
	(segment
		(start 36.195254 -155.750006)
		(end 38.121336 -153.823924)
		(width 0.127)
		(layer "In2.Cu")
		(net "DEBUG_GPIO_BMC_R_4")
	)
	(segment
		(start 39.877492 -151.323802)
		(end 39.877492 -150.66518)
		(width 0.127)
		(layer "In2.Cu")
		(net "DEBUG_GPIO_BMC_R_4")
	)
	(segment
		(start 40.33647 -150.206202)
		(end 40.674798 -150.206202)
		(width 0.127)
		(layer "In2.Cu")
		(net "DEBUG_GPIO_BMC_R_4")
	)
	(segment
		(start 31.4833 -154.9527)
		(end 33.250632 -154.9527)
		(width 0.127)
		(layer "In2.Cu")
		(net "DEBUG_GPIO_BMC_R_4")
	)
	(segment
		(start 38.121336 -153.079958)
		(end 39.877492 -151.323802)
		(width 0.127)
		(layer "In2.Cu")
		(net "DEBUG_GPIO_BMC_R_4")
	)
	(segment
		(start 40.674798 -150.206202)
		(end 41.080944 -149.800056)
		(width 0.127)
		(layer "In2.Cu")
		(net "DEBUG_GPIO_BMC_R_4")
	)
	(segment
		(start 28.832048 -155.635706)
		(end 28.832048 -155.803854)
		(width 0.127)
		(layer "F.Cu")
		(net "DEBUG_GPIO_BMC_R_3")
	)
	(segment
		(start 27.863546 -154.422856)
		(end 27.863546 -154.667204)
		(width 0.127)
		(layer "F.Cu")
		(net "DEBUG_GPIO_BMC_R_3")
	)
	(segment
		(start 40.899842 -150.199852)
		(end 40.499792 -150.599902)
		(width 0.127)
		(layer "F.Cu")
		(net "DEBUG_GPIO_BMC_R_3")
	)
	(segment
		(start 27.863546 -154.667204)
		(end 28.832048 -155.635706)
		(width 0.127)
		(layer "F.Cu")
		(net "DEBUG_GPIO_BMC_R_3")
	)
	(via
		(at 28.832048 -155.803854)
		(size 0.508)
		(drill 0.254)
		(layers "F.Cu" "B.Cu")
		(net "DEBUG_GPIO_BMC_R_3")
	)
	(via
		(at 40.499792 -150.599902)
		(size 0.4572)
		(drill 0.2032)
		(layers "F.Cu" "B.Cu")
		(net "DEBUG_GPIO_BMC_R_3")
	)
	(segment
		(start 28.832048 -155.803854)
		(end 31.171134 -155.803854)
		(width 0.127)
		(layer "In2.Cu")
		(net "DEBUG_GPIO_BMC_R_3")
	)
	(segment
		(start 31.641288 -155.3337)
		(end 33.092644 -155.3337)
		(width 0.127)
		(layer "In2.Cu")
		(net "DEBUG_GPIO_BMC_R_3")
	)
	(segment
		(start 40.499792 -150.84298)
		(end 40.499792 -150.599902)
		(width 0.127)
		(layer "In2.Cu")
		(net "DEBUG_GPIO_BMC_R_3")
	)
	(segment
		(start 36.25723 -156.131006)
		(end 38.349936 -154.0383)
		(width 0.127)
		(layer "In2.Cu")
		(net "DEBUG_GPIO_BMC_R_3")
	)
	(segment
		(start 40.106092 -151.23668)
		(end 40.499792 -150.84298)
		(width 0.127)
		(layer "In2.Cu")
		(net "DEBUG_GPIO_BMC_R_3")
	)
	(segment
		(start 40.106092 -151.418544)
		(end 40.106092 -151.23668)
		(width 0.127)
		(layer "In2.Cu")
		(net "DEBUG_GPIO_BMC_R_3")
	)
	(segment
		(start 33.092644 -155.3337)
		(end 33.88995 -156.131006)
		(width 0.127)
		(layer "In2.Cu")
		(net "DEBUG_GPIO_BMC_R_3")
	)
	(segment
		(start 38.349936 -154.0383)
		(end 38.349936 -153.1747)
		(width 0.127)
		(layer "In2.Cu")
		(net "DEBUG_GPIO_BMC_R_3")
	)
	(segment
		(start 31.171134 -155.803854)
		(end 31.641288 -155.3337)
		(width 0.127)
		(layer "In2.Cu")
		(net "DEBUG_GPIO_BMC_R_3")
	)
	(segment
		(start 38.349936 -153.1747)
		(end 40.106092 -151.418544)
		(width 0.127)
		(layer "In2.Cu")
		(net "DEBUG_GPIO_BMC_R_3")
	)
	(segment
		(start 33.88995 -156.131006)
		(end 36.25723 -156.131006)
		(width 0.127)
		(layer "In2.Cu")
		(net "DEBUG_GPIO_BMC_R_3")
	)
	(segment
		(start 28.872688 -153.349198)
		(end 28.872688 -153.704036)
		(width 0.127)
		(layer "F.Cu")
		(net "DEBUG_GPIO_BMC_R_2")
	)
	(segment
		(start 27.863546 -152.340056)
		(end 28.872688 -153.349198)
		(width 0.127)
		(layer "F.Cu")
		(net "DEBUG_GPIO_BMC_R_2")
	)
	(segment
		(start 40.899842 -149.400006)
		(end 40.499792 -149.800056)
		(width 0.127)
		(layer "F.Cu")
		(net "DEBUG_GPIO_BMC_R_2")
	)
	(via
		(at 40.499792 -149.800056)
		(size 0.4572)
		(drill 0.2032)
		(layers "F.Cu" "B.Cu")
		(net "DEBUG_GPIO_BMC_R_2")
	)
	(via
		(at 28.872688 -153.704036)
		(size 0.508)
		(drill 0.254)
		(layers "F.Cu" "B.Cu")
		(net "DEBUG_GPIO_BMC_R_2")
	)
	(segment
		(start 37.706808 -153.035)
		(end 39.816024 -150.925784)
		(width 0.127)
		(layer "In5.Cu")
		(net "DEBUG_GPIO_BMC_R_2")
	)
	(segment
		(start 39.816024 -150.925784)
		(end 39.816024 -150.483824)
		(width 0.127)
		(layer "In5.Cu")
		(net "DEBUG_GPIO_BMC_R_2")
	)
	(segment
		(start 39.816024 -150.483824)
		(end 40.499792 -149.800056)
		(width 0.127)
		(layer "In5.Cu")
		(net "DEBUG_GPIO_BMC_R_2")
	)
	(segment
		(start 28.872688 -153.704036)
		(end 29.541724 -153.035)
		(width 0.127)
		(layer "In5.Cu")
		(net "DEBUG_GPIO_BMC_R_2")
	)
	(segment
		(start 29.541724 -153.035)
		(end 37.706808 -153.035)
		(width 0.127)
		(layer "In5.Cu")
		(net "DEBUG_GPIO_BMC_R_2")
	)
	(segment
		(start 39.157148 -150.199852)
		(end 37.9984 -151.3586)
		(width 0.127)
		(layer "F.Cu")
		(net "DEBUG_GPIO_BMC_R_1")
	)
	(segment
		(start 34.051748 -151.044148)
		(end 32.324802 -151.044148)
		(width 0.127)
		(layer "F.Cu")
		(net "DEBUG_GPIO_BMC_R_1")
	)
	(segment
		(start 32.324802 -151.044148)
		(end 30.356302 -151.044148)
		(width 0.127)
		(layer "F.Cu")
		(net "DEBUG_GPIO_BMC_R_1")
	)
	(segment
		(start 34.3662 -151.3586)
		(end 34.051748 -151.044148)
		(width 0.127)
		(layer "F.Cu")
		(net "DEBUG_GPIO_BMC_R_1")
	)
	(segment
		(start 30.356302 -151.044148)
		(end 29.901134 -151.499316)
		(width 0.127)
		(layer "F.Cu")
		(net "DEBUG_GPIO_BMC_R_1")
	)
	(segment
		(start 39.299896 -150.199852)
		(end 39.157148 -150.199852)
		(width 0.127)
		(layer "F.Cu")
		(net "DEBUG_GPIO_BMC_R_1")
	)
	(segment
		(start 37.9984 -151.3586)
		(end 34.3662 -151.3586)
		(width 0.127)
		(layer "F.Cu")
		(net "DEBUG_GPIO_BMC_R_1")
	)
	(via
		(at 32.324802 -151.044148)
		(size 0.6604)
		(drill 0.3302)
		(layers "F.Cu" "B.Cu")
		(net "DEBUG_GPIO_BMC_R_1")
	)
	(segment
		(start 26.974546 -158.588456)
		(end 26.186892 -158.588456)
		(width 0.127)
		(layer "F.Cu")
		(net "DEBUG_GPIO_BMC_6")
	)
	(segment
		(start 96.963992 -142.978886)
		(end 95.996506 -142.978886)
		(width 0.127)
		(layer "F.Cu")
		(net "DEBUG_GPIO_BMC_6")
	)
	(segment
		(start 97.262188 -142.68069)
		(end 96.963992 -142.978886)
		(width 0.127)
		(layer "F.Cu")
		(net "DEBUG_GPIO_BMC_6")
	)
	(via
		(at 26.186892 -158.588456)
		(size 0.508)
		(drill 0.254)
		(layers "F.Cu" "B.Cu")
		(net "DEBUG_GPIO_BMC_6")
	)
	(via
		(at 39.592758 -114.411506)
		(size 0.508)
		(drill 0.254)
		(layers "F.Cu" "B.Cu")
		(net "DEBUG_GPIO_BMC_6")
	)
	(via
		(at 48.513746 -113.4491)
		(size 0.6096)
		(drill 0.3048)
		(layers "F.Cu" "B.Cu")
		(net "DEBUG_GPIO_BMC_6")
	)
	(via
		(at 97.262188 -142.68069)
		(size 0.508)
		(drill 0.254)
		(layers "F.Cu" "B.Cu")
		(net "DEBUG_GPIO_BMC_6")
	)
	(segment
		(start 54.206648 -113.4491)
		(end 48.513746 -113.4491)
		(width 0.127)
		(layer "B.Cu")
		(net "DEBUG_GPIO_BMC_6")
	)
	(segment
		(start 85.765894 -123.233942)
		(end 82.459322 -126.540514)
		(width 0.127)
		(layer "B.Cu")
		(net "DEBUG_GPIO_BMC_6")
	)
	(segment
		(start 96.8629 -137.055098)
		(end 96.8629 -128.89738)
		(width 0.127)
		(layer "B.Cu")
		(net "DEBUG_GPIO_BMC_6")
	)
	(segment
		(start 97.262188 -142.68069)
		(end 96.4057 -141.824202)
		(width 0.127)
		(layer "B.Cu")
		(net "DEBUG_GPIO_BMC_6")
	)
	(segment
		(start 96.8629 -128.89738)
		(end 94.8055 -126.83998)
		(width 0.127)
		(layer "B.Cu")
		(net "DEBUG_GPIO_BMC_6")
	)
	(segment
		(start 94.805754 -125.471428)
		(end 92.568268 -123.233942)
		(width 0.127)
		(layer "B.Cu")
		(net "DEBUG_GPIO_BMC_6")
	)
	(segment
		(start 96.4057 -141.824202)
		(end 96.4057 -137.512298)
		(width 0.127)
		(layer "B.Cu")
		(net "DEBUG_GPIO_BMC_6")
	)
	(segment
		(start 94.805754 -125.786896)
		(end 94.805754 -125.471428)
		(width 0.127)
		(layer "B.Cu")
		(net "DEBUG_GPIO_BMC_6")
	)
	(segment
		(start 94.8055 -125.78715)
		(end 94.805754 -125.786896)
		(width 0.127)
		(layer "B.Cu")
		(net "DEBUG_GPIO_BMC_6")
	)
	(segment
		(start 40.555164 -113.4491)
		(end 39.592758 -114.411506)
		(width 0.127)
		(layer "B.Cu")
		(net "DEBUG_GPIO_BMC_6")
	)
	(segment
		(start 60.315348 -119.5578)
		(end 54.206648 -113.4491)
		(width 0.127)
		(layer "B.Cu")
		(net "DEBUG_GPIO_BMC_6")
	)
	(segment
		(start 62.576964 -119.5578)
		(end 60.315348 -119.5578)
		(width 0.127)
		(layer "B.Cu")
		(net "DEBUG_GPIO_BMC_6")
	)
	(segment
		(start 76.800964 -126.540514)
		(end 71.82485 -121.5644)
		(width 0.127)
		(layer "B.Cu")
		(net "DEBUG_GPIO_BMC_6")
	)
	(segment
		(start 82.459322 -126.540514)
		(end 76.800964 -126.540514)
		(width 0.127)
		(layer "B.Cu")
		(net "DEBUG_GPIO_BMC_6")
	)
	(segment
		(start 92.568268 -123.233942)
		(end 85.765894 -123.233942)
		(width 0.127)
		(layer "B.Cu")
		(net "DEBUG_GPIO_BMC_6")
	)
	(segment
		(start 71.82485 -121.5644)
		(end 64.583564 -121.5644)
		(width 0.127)
		(layer "B.Cu")
		(net "DEBUG_GPIO_BMC_6")
	)
	(segment
		(start 96.4057 -137.512298)
		(end 96.8629 -137.055098)
		(width 0.127)
		(layer "B.Cu")
		(net "DEBUG_GPIO_BMC_6")
	)
	(segment
		(start 94.8055 -126.83998)
		(end 94.8055 -125.78715)
		(width 0.127)
		(layer "B.Cu")
		(net "DEBUG_GPIO_BMC_6")
	)
	(segment
		(start 64.583564 -121.5644)
		(end 62.576964 -119.5578)
		(width 0.127)
		(layer "B.Cu")
		(net "DEBUG_GPIO_BMC_6")
	)
	(segment
		(start 48.513746 -113.4491)
		(end 40.555164 -113.4491)
		(width 0.127)
		(layer "B.Cu")
		(net "DEBUG_GPIO_BMC_6")
	)
	(segment
		(start 31.060644 -115.87988)
		(end 29.10332 -115.87988)
		(width 0.127)
		(layer "In5.Cu")
		(net "DEBUG_GPIO_BMC_6")
	)
	(segment
		(start 26.147014 -112.923574)
		(end 15.067788 -112.923574)
		(width 0.127)
		(layer "In5.Cu")
		(net "DEBUG_GPIO_BMC_6")
	)
	(segment
		(start 23.096982 -155.498546)
		(end 26.186892 -158.588456)
		(width 0.127)
		(layer "In5.Cu")
		(net "DEBUG_GPIO_BMC_6")
	)
	(segment
		(start 33.402524 -113.538)
		(end 31.060644 -115.87988)
		(width 0.127)
		(layer "In5.Cu")
		(net "DEBUG_GPIO_BMC_6")
	)
	(segment
		(start 22.290278 -155.684474)
		(end 22.476206 -155.498546)
		(width 0.127)
		(layer "In5.Cu")
		(net "DEBUG_GPIO_BMC_6")
	)
	(segment
		(start 4.22148 -123.769882)
		(end 4.22148 -149.047708)
		(width 0.127)
		(layer "In5.Cu")
		(net "DEBUG_GPIO_BMC_6")
	)
	(segment
		(start 10.858246 -155.684474)
		(end 22.290278 -155.684474)
		(width 0.127)
		(layer "In5.Cu")
		(net "DEBUG_GPIO_BMC_6")
	)
	(segment
		(start 29.10332 -115.87988)
		(end 26.147014 -112.923574)
		(width 0.127)
		(layer "In5.Cu")
		(net "DEBUG_GPIO_BMC_6")
	)
	(segment
		(start 38.719252 -113.538)
		(end 33.402524 -113.538)
		(width 0.127)
		(layer "In5.Cu")
		(net "DEBUG_GPIO_BMC_6")
	)
	(segment
		(start 15.067788 -112.923574)
		(end 4.22148 -123.769882)
		(width 0.127)
		(layer "In5.Cu")
		(net "DEBUG_GPIO_BMC_6")
	)
	(segment
		(start 39.592758 -114.411506)
		(end 38.719252 -113.538)
		(width 0.127)
		(layer "In5.Cu")
		(net "DEBUG_GPIO_BMC_6")
	)
	(segment
		(start 4.22148 -149.047708)
		(end 10.858246 -155.684474)
		(width 0.127)
		(layer "In5.Cu")
		(net "DEBUG_GPIO_BMC_6")
	)
	(segment
		(start 22.476206 -155.498546)
		(end 23.096982 -155.498546)
		(width 0.127)
		(layer "In5.Cu")
		(net "DEBUG_GPIO_BMC_6")
	)
	(segment
		(start 97.066862 -141.896338)
		(end 96.634554 -142.328646)
		(width 0.127)
		(layer "F.Cu")
		(net "DEBUG_GPIO_BMC_5")
	)
	(segment
		(start 96.634554 -142.328646)
		(end 95.996506 -142.328646)
		(width 0.127)
		(layer "F.Cu")
		(net "DEBUG_GPIO_BMC_5")
	)
	(segment
		(start 26.974546 -155.464256)
		(end 26.186892 -155.464256)
		(width 0.127)
		(layer "F.Cu")
		(net "DEBUG_GPIO_BMC_5")
	)
	(segment
		(start 97.624138 -141.896338)
		(end 97.066862 -141.896338)
		(width 0.127)
		(layer "F.Cu")
		(net "DEBUG_GPIO_BMC_5")
	)
	(via
		(at 46.212252 -112.9284)
		(size 0.6096)
		(drill 0.3048)
		(layers "F.Cu" "B.Cu")
		(net "DEBUG_GPIO_BMC_5")
	)
	(via
		(at 38.576758 -114.411506)
		(size 0.508)
		(drill 0.254)
		(layers "F.Cu" "B.Cu")
		(net "DEBUG_GPIO_BMC_5")
	)
	(via
		(at 97.624138 -141.896338)
		(size 0.508)
		(drill 0.254)
		(layers "F.Cu" "B.Cu")
		(net "DEBUG_GPIO_BMC_5")
	)
	(via
		(at 26.186892 -155.464256)
		(size 0.508)
		(drill 0.254)
		(layers "F.Cu" "B.Cu")
		(net "DEBUG_GPIO_BMC_5")
	)
	(segment
		(start 71.55561 -120.506998)
		(end 64.06515 -120.506998)
		(width 0.127)
		(layer "B.Cu")
		(net "DEBUG_GPIO_BMC_5")
	)
	(segment
		(start 97.395538 -141.896338)
		(end 96.7867 -141.2875)
		(width 0.127)
		(layer "B.Cu")
		(net "DEBUG_GPIO_BMC_5")
	)
	(segment
		(start 38.576758 -114.411506)
		(end 39.920164 -113.0681)
		(width 0.127)
		(layer "B.Cu")
		(net "DEBUG_GPIO_BMC_5")
	)
	(segment
		(start 54.459632 -112.9284)
		(end 46.212252 -112.9284)
		(width 0.127)
		(layer "B.Cu")
		(net "DEBUG_GPIO_BMC_5")
	)
	(segment
		(start 85.607906 -122.852942)
		(end 82.301334 -126.159514)
		(width 0.127)
		(layer "B.Cu")
		(net "DEBUG_GPIO_BMC_5")
	)
	(segment
		(start 39.920164 -113.0681)
		(end 42.073322 -113.0681)
		(width 0.127)
		(layer "B.Cu")
		(net "DEBUG_GPIO_BMC_5")
	)
	(segment
		(start 77.208126 -126.159514)
		(end 71.55561 -120.506998)
		(width 0.127)
		(layer "B.Cu")
		(net "DEBUG_GPIO_BMC_5")
	)
	(segment
		(start 95.186754 -125.629416)
		(end 95.187008 -125.629162)
		(width 0.127)
		(layer "B.Cu")
		(net "DEBUG_GPIO_BMC_5")
	)
	(segment
		(start 42.073322 -113.0681)
		(end 42.213022 -112.9284)
		(width 0.127)
		(layer "B.Cu")
		(net "DEBUG_GPIO_BMC_5")
	)
	(segment
		(start 95.186754 -125.944884)
		(end 95.186754 -125.629416)
		(width 0.127)
		(layer "B.Cu")
		(net "DEBUG_GPIO_BMC_5")
	)
	(segment
		(start 95.187008 -125.313694)
		(end 92.726256 -122.852942)
		(width 0.127)
		(layer "B.Cu")
		(net "DEBUG_GPIO_BMC_5")
	)
	(segment
		(start 62.734952 -119.1768)
		(end 60.708032 -119.1768)
		(width 0.127)
		(layer "B.Cu")
		(net "DEBUG_GPIO_BMC_5")
	)
	(segment
		(start 60.708032 -119.1768)
		(end 54.459632 -112.9284)
		(width 0.127)
		(layer "B.Cu")
		(net "DEBUG_GPIO_BMC_5")
	)
	(segment
		(start 92.726256 -122.852942)
		(end 85.607906 -122.852942)
		(width 0.127)
		(layer "B.Cu")
		(net "DEBUG_GPIO_BMC_5")
	)
	(segment
		(start 96.7867 -137.670286)
		(end 97.2439 -137.213086)
		(width 0.127)
		(layer "B.Cu")
		(net "DEBUG_GPIO_BMC_5")
	)
	(segment
		(start 42.213022 -112.9284)
		(end 46.212252 -112.9284)
		(width 0.127)
		(layer "B.Cu")
		(net "DEBUG_GPIO_BMC_5")
	)
	(segment
		(start 82.301334 -126.159514)
		(end 77.208126 -126.159514)
		(width 0.127)
		(layer "B.Cu")
		(net "DEBUG_GPIO_BMC_5")
	)
	(segment
		(start 64.06515 -120.506998)
		(end 62.734952 -119.1768)
		(width 0.127)
		(layer "B.Cu")
		(net "DEBUG_GPIO_BMC_5")
	)
	(segment
		(start 95.1865 -126.681992)
		(end 95.1865 -125.945138)
		(width 0.127)
		(layer "B.Cu")
		(net "DEBUG_GPIO_BMC_5")
	)
	(segment
		(start 97.624138 -141.896338)
		(end 97.395538 -141.896338)
		(width 0.127)
		(layer "B.Cu")
		(net "DEBUG_GPIO_BMC_5")
	)
	(segment
		(start 96.7867 -141.2875)
		(end 96.7867 -137.670286)
		(width 0.127)
		(layer "B.Cu")
		(net "DEBUG_GPIO_BMC_5")
	)
	(segment
		(start 95.1865 -125.945138)
		(end 95.186754 -125.944884)
		(width 0.127)
		(layer "B.Cu")
		(net "DEBUG_GPIO_BMC_5")
	)
	(segment
		(start 97.2439 -128.739392)
		(end 95.1865 -126.681992)
		(width 0.127)
		(layer "B.Cu")
		(net "DEBUG_GPIO_BMC_5")
	)
	(segment
		(start 97.2439 -137.213086)
		(end 97.2439 -128.739392)
		(width 0.127)
		(layer "B.Cu")
		(net "DEBUG_GPIO_BMC_5")
	)
	(segment
		(start 95.187008 -125.629162)
		(end 95.187008 -125.313694)
		(width 0.127)
		(layer "B.Cu")
		(net "DEBUG_GPIO_BMC_5")
	)
	(segment
		(start 38.576758 -114.411506)
		(end 38.135052 -113.9698)
		(width 0.127)
		(layer "In5.Cu")
		(net "DEBUG_GPIO_BMC_5")
	)
	(segment
		(start 33.509712 -113.9698)
		(end 31.185612 -116.2939)
		(width 0.127)
		(layer "In5.Cu")
		(net "DEBUG_GPIO_BMC_5")
	)
	(segment
		(start 28.978352 -116.2939)
		(end 25.989026 -113.304574)
		(width 0.127)
		(layer "In5.Cu")
		(net "DEBUG_GPIO_BMC_5")
	)
	(segment
		(start 4.738878 -123.791472)
		(end 4.738878 -149.026118)
		(width 0.127)
		(layer "In5.Cu")
		(net "DEBUG_GPIO_BMC_5")
	)
	(segment
		(start 4.738878 -149.026118)
		(end 10.830306 -155.117546)
		(width 0.127)
		(layer "In5.Cu")
		(net "DEBUG_GPIO_BMC_5")
	)
	(segment
		(start 31.185612 -116.2939)
		(end 28.978352 -116.2939)
		(width 0.127)
		(layer "In5.Cu")
		(net "DEBUG_GPIO_BMC_5")
	)
	(segment
		(start 10.830306 -155.117546)
		(end 25.840182 -155.117546)
		(width 0.127)
		(layer "In5.Cu")
		(net "DEBUG_GPIO_BMC_5")
	)
	(segment
		(start 15.225776 -113.304574)
		(end 4.738878 -123.791472)
		(width 0.127)
		(layer "In5.Cu")
		(net "DEBUG_GPIO_BMC_5")
	)
	(segment
		(start 25.840182 -155.117546)
		(end 26.186892 -155.464256)
		(width 0.127)
		(layer "In5.Cu")
		(net "DEBUG_GPIO_BMC_5")
	)
	(segment
		(start 38.135052 -113.9698)
		(end 33.509712 -113.9698)
		(width 0.127)
		(layer "In5.Cu")
		(net "DEBUG_GPIO_BMC_5")
	)
	(segment
		(start 25.989026 -113.304574)
		(end 15.225776 -113.304574)
		(width 0.127)
		(layer "In5.Cu")
		(net "DEBUG_GPIO_BMC_5")
	)
	(segment
		(start 26.974546 -153.381456)
		(end 26.520902 -153.381456)
		(width 0.127)
		(layer "F.Cu")
		(net "DEBUG_GPIO_BMC_4")
	)
	(segment
		(start 26.520902 -153.381456)
		(end 26.193496 -153.708862)
		(width 0.127)
		(layer "F.Cu")
		(net "DEBUG_GPIO_BMC_4")
	)
	(segment
		(start 97.30232 -140.943838)
		(end 97.30232 -140.95476)
		(width 0.127)
		(layer "F.Cu")
		(net "DEBUG_GPIO_BMC_4")
	)
	(segment
		(start 96.578674 -141.678406)
		(end 95.996506 -141.678406)
		(width 0.127)
		(layer "F.Cu")
		(net "DEBUG_GPIO_BMC_4")
	)
	(segment
		(start 97.30232 -140.95476)
		(end 96.578674 -141.678406)
		(width 0.127)
		(layer "F.Cu")
		(net "DEBUG_GPIO_BMC_4")
	)
	(via
		(at 26.193496 -153.708862)
		(size 0.508)
		(drill 0.254)
		(layers "F.Cu" "B.Cu")
		(net "DEBUG_GPIO_BMC_4")
	)
	(via
		(at 97.30232 -140.943838)
		(size 0.508)
		(drill 0.254)
		(layers "F.Cu" "B.Cu")
		(net "DEBUG_GPIO_BMC_4")
	)
	(via
		(at 38.358064 -113.12652)
		(size 0.6096)
		(drill 0.3048)
		(layers "F.Cu" "B.Cu")
		(net "DEBUG_GPIO_BMC_4")
	)
	(via
		(at 36.63823 -114.895376)
		(size 0.508)
		(drill 0.254)
		(layers "F.Cu" "B.Cu")
		(net "DEBUG_GPIO_BMC_4")
	)
	(segment
		(start 97.1677 -140.5763)
		(end 97.1677 -137.828274)
		(width 0.127)
		(layer "B.Cu")
		(net "DEBUG_GPIO_BMC_4")
	)
	(segment
		(start 38.358064 -113.12652)
		(end 38.358064 -113.175542)
		(width 0.127)
		(layer "B.Cu")
		(net "DEBUG_GPIO_BMC_4")
	)
	(segment
		(start 95.567754 -125.787404)
		(end 95.568008 -125.78715)
		(width 0.127)
		(layer "B.Cu")
		(net "DEBUG_GPIO_BMC_4")
	)
	(segment
		(start 95.567754 -126.102872)
		(end 95.567754 -125.787404)
		(width 0.127)
		(layer "B.Cu")
		(net "DEBUG_GPIO_BMC_4")
	)
	(segment
		(start 38.358064 -113.175542)
		(end 36.63823 -114.895376)
		(width 0.127)
		(layer "B.Cu")
		(net "DEBUG_GPIO_BMC_4")
	)
	(segment
		(start 97.30232 -140.71092)
		(end 97.1677 -140.5763)
		(width 0.127)
		(layer "B.Cu")
		(net "DEBUG_GPIO_BMC_4")
	)
	(segment
		(start 82.143346 -125.778514)
		(end 77.366114 -125.778514)
		(width 0.127)
		(layer "B.Cu")
		(net "DEBUG_GPIO_BMC_4")
	)
	(segment
		(start 95.568008 -125.155706)
		(end 92.884244 -122.471942)
		(width 0.127)
		(layer "B.Cu")
		(net "DEBUG_GPIO_BMC_4")
	)
	(segment
		(start 65.4812 -119.3546)
		(end 65.2018 -119.634)
		(width 0.127)
		(layer "B.Cu")
		(net "DEBUG_GPIO_BMC_4")
	)
	(segment
		(start 77.366114 -125.778514)
		(end 70.9422 -119.3546)
		(width 0.127)
		(layer "B.Cu")
		(net "DEBUG_GPIO_BMC_4")
	)
	(segment
		(start 97.30232 -140.943838)
		(end 97.30232 -140.71092)
		(width 0.127)
		(layer "B.Cu")
		(net "DEBUG_GPIO_BMC_4")
	)
	(segment
		(start 95.5675 -126.103126)
		(end 95.567754 -126.102872)
		(width 0.127)
		(layer "B.Cu")
		(net "DEBUG_GPIO_BMC_4")
	)
	(segment
		(start 63.861696 -119.634)
		(end 63.007494 -118.779798)
		(width 0.127)
		(layer "B.Cu")
		(net "DEBUG_GPIO_BMC_4")
	)
	(segment
		(start 97.1677 -137.828274)
		(end 97.6249 -137.371074)
		(width 0.127)
		(layer "B.Cu")
		(net "DEBUG_GPIO_BMC_4")
	)
	(segment
		(start 92.884244 -122.471942)
		(end 85.449918 -122.471942)
		(width 0.127)
		(layer "B.Cu")
		(net "DEBUG_GPIO_BMC_4")
	)
	(segment
		(start 97.6249 -128.581404)
		(end 95.5675 -126.524004)
		(width 0.127)
		(layer "B.Cu")
		(net "DEBUG_GPIO_BMC_4")
	)
	(segment
		(start 38.797484 -112.6871)
		(end 38.358064 -113.12652)
		(width 0.127)
		(layer "B.Cu")
		(net "DEBUG_GPIO_BMC_4")
	)
	(segment
		(start 85.449918 -122.471942)
		(end 82.143346 -125.778514)
		(width 0.127)
		(layer "B.Cu")
		(net "DEBUG_GPIO_BMC_4")
	)
	(segment
		(start 41.950386 -112.4077)
		(end 41.670986 -112.6871)
		(width 0.127)
		(layer "B.Cu")
		(net "DEBUG_GPIO_BMC_4")
	)
	(segment
		(start 54.47792 -112.4077)
		(end 41.950386 -112.4077)
		(width 0.127)
		(layer "B.Cu")
		(net "DEBUG_GPIO_BMC_4")
	)
	(segment
		(start 63.007494 -118.779798)
		(end 60.850018 -118.779798)
		(width 0.127)
		(layer "B.Cu")
		(net "DEBUG_GPIO_BMC_4")
	)
	(segment
		(start 70.9422 -119.3546)
		(end 65.4812 -119.3546)
		(width 0.127)
		(layer "B.Cu")
		(net "DEBUG_GPIO_BMC_4")
	)
	(segment
		(start 65.2018 -119.634)
		(end 63.861696 -119.634)
		(width 0.127)
		(layer "B.Cu")
		(net "DEBUG_GPIO_BMC_4")
	)
	(segment
		(start 95.568008 -125.78715)
		(end 95.568008 -125.155706)
		(width 0.127)
		(layer "B.Cu")
		(net "DEBUG_GPIO_BMC_4")
	)
	(segment
		(start 97.6249 -137.371074)
		(end 97.6249 -128.581404)
		(width 0.127)
		(layer "B.Cu")
		(net "DEBUG_GPIO_BMC_4")
	)
	(segment
		(start 60.850018 -118.779798)
		(end 54.47792 -112.4077)
		(width 0.127)
		(layer "B.Cu")
		(net "DEBUG_GPIO_BMC_4")
	)
	(segment
		(start 41.670986 -112.6871)
		(end 38.797484 -112.6871)
		(width 0.127)
		(layer "B.Cu")
		(net "DEBUG_GPIO_BMC_4")
	)
	(segment
		(start 95.5675 -126.524004)
		(end 95.5675 -126.103126)
		(width 0.127)
		(layer "B.Cu")
		(net "DEBUG_GPIO_BMC_4")
	)
	(segment
		(start 36.63823 -114.895376)
		(end 33.662112 -114.895376)
		(width 0.127)
		(layer "In5.Cu")
		(net "DEBUG_GPIO_BMC_4")
	)
	(segment
		(start 10.541762 -153.751026)
		(end 26.151332 -153.751026)
		(width 0.127)
		(layer "In5.Cu")
		(net "DEBUG_GPIO_BMC_4")
	)
	(segment
		(start 25.67305 -114.066574)
		(end 15.541752 -114.066574)
		(width 0.127)
		(layer "In5.Cu")
		(net "DEBUG_GPIO_BMC_4")
	)
	(segment
		(start 5.500878 -148.710142)
		(end 10.541762 -153.751026)
		(width 0.127)
		(layer "In5.Cu")
		(net "DEBUG_GPIO_BMC_4")
	)
	(segment
		(start 28.662376 -117.0559)
		(end 25.67305 -114.066574)
		(width 0.127)
		(layer "In5.Cu")
		(net "DEBUG_GPIO_BMC_4")
	)
	(segment
		(start 15.541752 -114.066574)
		(end 5.500878 -124.107448)
		(width 0.127)
		(layer "In5.Cu")
		(net "DEBUG_GPIO_BMC_4")
	)
	(segment
		(start 31.501588 -117.0559)
		(end 28.662376 -117.0559)
		(width 0.127)
		(layer "In5.Cu")
		(net "DEBUG_GPIO_BMC_4")
	)
	(segment
		(start 5.500878 -124.107448)
		(end 5.500878 -148.710142)
		(width 0.127)
		(layer "In5.Cu")
		(net "DEBUG_GPIO_BMC_4")
	)
	(segment
		(start 26.151332 -153.751026)
		(end 26.193496 -153.708862)
		(width 0.127)
		(layer "In5.Cu")
		(net "DEBUG_GPIO_BMC_4")
	)
	(segment
		(start 33.662112 -114.895376)
		(end 31.501588 -117.0559)
		(width 0.127)
		(layer "In5.Cu")
		(net "DEBUG_GPIO_BMC_4")
	)
	(segment
		(start 26.974546 -154.422856)
		(end 26.344118 -154.422856)
		(width 0.127)
		(layer "F.Cu")
		(net "DEBUG_GPIO_BMC_3")
	)
	(segment
		(start 94.622366 -141.028166)
		(end 95.996506 -141.028166)
		(width 0.127)
		(layer "F.Cu")
		(net "DEBUG_GPIO_BMC_3")
	)
	(segment
		(start 94.488 -140.8938)
		(end 94.622366 -141.028166)
		(width 0.127)
		(layer "F.Cu")
		(net "DEBUG_GPIO_BMC_3")
	)
	(segment
		(start 26.344118 -154.422856)
		(end 26.189686 -154.577288)
		(width 0.127)
		(layer "F.Cu")
		(net "DEBUG_GPIO_BMC_3")
	)
	(segment
		(start 94.1832 -140.8938)
		(end 94.488 -140.8938)
		(width 0.127)
		(layer "F.Cu")
		(net "DEBUG_GPIO_BMC_3")
	)
	(via
		(at 44.205144 -113.9698)
		(size 0.6096)
		(drill 0.3048)
		(layers "F.Cu" "B.Cu")
		(net "DEBUG_GPIO_BMC_3")
	)
	(via
		(at 26.189686 -154.577288)
		(size 0.508)
		(drill 0.254)
		(layers "F.Cu" "B.Cu")
		(net "DEBUG_GPIO_BMC_3")
	)
	(via
		(at 37.71646 -114.626644)
		(size 0.508)
		(drill 0.254)
		(layers "F.Cu" "B.Cu")
		(net "DEBUG_GPIO_BMC_3")
	)
	(via
		(at 94.1832 -140.8938)
		(size 0.508)
		(drill 0.254)
		(layers "F.Cu" "B.Cu")
		(net "DEBUG_GPIO_BMC_3")
	)
	(segment
		(start 54.18836 -113.9698)
		(end 44.205144 -113.9698)
		(width 0.127)
		(layer "B.Cu")
		(net "DEBUG_GPIO_BMC_3")
	)
	(segment
		(start 71.666862 -121.9454)
		(end 64.425576 -121.9454)
		(width 0.127)
		(layer "B.Cu")
		(net "DEBUG_GPIO_BMC_3")
	)
	(segment
		(start 85.923882 -123.614942)
		(end 82.61731 -126.921514)
		(width 0.127)
		(layer "B.Cu")
		(net "DEBUG_GPIO_BMC_3")
	)
	(segment
		(start 60.15736 -119.9388)
		(end 54.18836 -113.9698)
		(width 0.127)
		(layer "B.Cu")
		(net "DEBUG_GPIO_BMC_3")
	)
	(segment
		(start 37.71646 -114.626644)
		(end 38.01745 -114.927634)
		(width 0.127)
		(layer "B.Cu")
		(net "DEBUG_GPIO_BMC_3")
	)
	(segment
		(start 38.01745 -114.927634)
		(end 40.336724 -114.927634)
		(width 0.127)
		(layer "B.Cu")
		(net "DEBUG_GPIO_BMC_3")
	)
	(segment
		(start 62.418976 -119.9388)
		(end 60.15736 -119.9388)
		(width 0.127)
		(layer "B.Cu")
		(net "DEBUG_GPIO_BMC_3")
	)
	(segment
		(start 82.61731 -126.921514)
		(end 76.642976 -126.921514)
		(width 0.127)
		(layer "B.Cu")
		(net "DEBUG_GPIO_BMC_3")
	)
	(segment
		(start 94.4245 -126.997968)
		(end 94.4245 -125.629162)
		(width 0.127)
		(layer "B.Cu")
		(net "DEBUG_GPIO_BMC_3")
	)
	(segment
		(start 94.4245 -125.629162)
		(end 92.41028 -123.614942)
		(width 0.127)
		(layer "B.Cu")
		(net "DEBUG_GPIO_BMC_3")
	)
	(segment
		(start 96.4819 -129.055368)
		(end 94.4245 -126.997968)
		(width 0.127)
		(layer "B.Cu")
		(net "DEBUG_GPIO_BMC_3")
	)
	(segment
		(start 40.336724 -114.927634)
		(end 41.294558 -113.9698)
		(width 0.127)
		(layer "B.Cu")
		(net "DEBUG_GPIO_BMC_3")
	)
	(segment
		(start 96.4819 -136.89711)
		(end 96.4819 -129.055368)
		(width 0.127)
		(layer "B.Cu")
		(net "DEBUG_GPIO_BMC_3")
	)
	(segment
		(start 95.025718 -140.051282)
		(end 95.025718 -138.353292)
		(width 0.127)
		(layer "B.Cu")
		(net "DEBUG_GPIO_BMC_3")
	)
	(segment
		(start 94.1832 -140.8938)
		(end 95.025718 -140.051282)
		(width 0.127)
		(layer "B.Cu")
		(net "DEBUG_GPIO_BMC_3")
	)
	(segment
		(start 64.425576 -121.9454)
		(end 62.418976 -119.9388)
		(width 0.127)
		(layer "B.Cu")
		(net "DEBUG_GPIO_BMC_3")
	)
	(segment
		(start 76.642976 -126.921514)
		(end 71.666862 -121.9454)
		(width 0.127)
		(layer "B.Cu")
		(net "DEBUG_GPIO_BMC_3")
	)
	(segment
		(start 41.294558 -113.9698)
		(end 44.205144 -113.9698)
		(width 0.127)
		(layer "B.Cu")
		(net "DEBUG_GPIO_BMC_3")
	)
	(segment
		(start 95.025718 -138.353292)
		(end 96.4819 -136.89711)
		(width 0.127)
		(layer "B.Cu")
		(net "DEBUG_GPIO_BMC_3")
	)
	(segment
		(start 92.41028 -123.614942)
		(end 85.923882 -123.614942)
		(width 0.127)
		(layer "B.Cu")
		(net "DEBUG_GPIO_BMC_3")
	)
	(segment
		(start 37.489892 -114.400076)
		(end 33.618424 -114.400076)
		(width 0.127)
		(layer "In5.Cu")
		(net "DEBUG_GPIO_BMC_3")
	)
	(segment
		(start 15.383764 -113.685574)
		(end 5.119878 -123.94946)
		(width 0.127)
		(layer "In5.Cu")
		(net "DEBUG_GPIO_BMC_3")
	)
	(segment
		(start 25.831038 -113.685574)
		(end 15.383764 -113.685574)
		(width 0.127)
		(layer "In5.Cu")
		(net "DEBUG_GPIO_BMC_3")
	)
	(segment
		(start 31.3436 -116.6749)
		(end 28.820364 -116.6749)
		(width 0.127)
		(layer "In5.Cu")
		(net "DEBUG_GPIO_BMC_3")
	)
	(segment
		(start 37.71646 -114.626644)
		(end 37.489892 -114.400076)
		(width 0.127)
		(layer "In5.Cu")
		(net "DEBUG_GPIO_BMC_3")
	)
	(segment
		(start 28.820364 -116.6749)
		(end 25.831038 -113.685574)
		(width 0.127)
		(layer "In5.Cu")
		(net "DEBUG_GPIO_BMC_3")
	)
	(segment
		(start 33.618424 -114.400076)
		(end 31.3436 -116.6749)
		(width 0.127)
		(layer "In5.Cu")
		(net "DEBUG_GPIO_BMC_3")
	)
	(segment
		(start 5.119878 -148.86813)
		(end 10.829036 -154.577288)
		(width 0.127)
		(layer "In5.Cu")
		(net "DEBUG_GPIO_BMC_3")
	)
	(segment
		(start 10.829036 -154.577288)
		(end 26.189686 -154.577288)
		(width 0.127)
		(layer "In5.Cu")
		(net "DEBUG_GPIO_BMC_3")
	)
	(segment
		(start 5.119878 -123.94946)
		(end 5.119878 -148.86813)
		(width 0.127)
		(layer "In5.Cu")
		(net "DEBUG_GPIO_BMC_3")
	)
	(segment
		(start 26.635202 -152.6794)
		(end 26.037286 -152.6794)
		(width 0.127)
		(layer "F.Cu")
		(net "DEBUG_GPIO_BMC_2")
	)
	(segment
		(start 94.1832 -140.0302)
		(end 94.530926 -140.377926)
		(width 0.127)
		(layer "F.Cu")
		(net "DEBUG_GPIO_BMC_2")
	)
	(segment
		(start 26.974546 -152.340056)
		(end 26.635202 -152.6794)
		(width 0.127)
		(layer "F.Cu")
		(net "DEBUG_GPIO_BMC_2")
	)
	(segment
		(start 94.530926 -140.377926)
		(end 95.996506 -140.377926)
		(width 0.127)
		(layer "F.Cu")
		(net "DEBUG_GPIO_BMC_2")
	)
	(via
		(at 35.81019 -115.3795)
		(size 0.508)
		(drill 0.254)
		(layers "F.Cu" "B.Cu")
		(net "DEBUG_GPIO_BMC_2")
	)
	(via
		(at 94.1832 -140.0302)
		(size 0.508)
		(drill 0.254)
		(layers "F.Cu" "B.Cu")
		(net "DEBUG_GPIO_BMC_2")
	)
	(via
		(at 26.037286 -152.6794)
		(size 0.508)
		(drill 0.254)
		(layers "F.Cu" "B.Cu")
		(net "DEBUG_GPIO_BMC_2")
	)
	(via
		(at 71.2978 -123.0884)
		(size 0.6096)
		(drill 0.3048)
		(layers "F.Cu" "B.Cu")
		(net "DEBUG_GPIO_BMC_2")
	)
	(segment
		(start 86.08187 -123.995942)
		(end 92.252292 -123.995942)
		(width 0.127)
		(layer "B.Cu")
		(net "DEBUG_GPIO_BMC_2")
	)
	(segment
		(start 96.1009 -134.072122)
		(end 96.1009 -136.739122)
		(width 0.127)
		(layer "B.Cu")
		(net "DEBUG_GPIO_BMC_2")
	)
	(segment
		(start 94.644718 -139.568682)
		(end 94.1832 -140.0302)
		(width 0.127)
		(layer "B.Cu")
		(net "DEBUG_GPIO_BMC_2")
	)
	(segment
		(start 54.15026 -114.4905)
		(end 54.170072 -114.4905)
		(width 0.127)
		(layer "B.Cu")
		(net "DEBUG_GPIO_BMC_2")
	)
	(segment
		(start 96.1009 -136.739122)
		(end 94.644718 -138.195304)
		(width 0.127)
		(layer "B.Cu")
		(net "DEBUG_GPIO_BMC_2")
	)
	(segment
		(start 82.775298 -127.302514)
		(end 86.08187 -123.995942)
		(width 0.127)
		(layer "B.Cu")
		(net "DEBUG_GPIO_BMC_2")
	)
	(segment
		(start 53.518308 -114.4905)
		(end 53.518562 -114.490246)
		(width 0.127)
		(layer "B.Cu")
		(net "DEBUG_GPIO_BMC_2")
	)
	(segment
		(start 40.423846 -115.3795)
		(end 41.312846 -114.4905)
		(width 0.127)
		(layer "B.Cu")
		(net "DEBUG_GPIO_BMC_2")
	)
	(segment
		(start 94.0435 -127.155956)
		(end 96.100646 -129.213102)
		(width 0.127)
		(layer "B.Cu")
		(net "DEBUG_GPIO_BMC_2")
	)
	(segment
		(start 54.170072 -114.4905)
		(end 62.005972 -122.3264)
		(width 0.127)
		(layer "B.Cu")
		(net "DEBUG_GPIO_BMC_2")
	)
	(segment
		(start 35.81019 -115.3795)
		(end 40.423846 -115.3795)
		(width 0.127)
		(layer "B.Cu")
		(net "DEBUG_GPIO_BMC_2")
	)
	(segment
		(start 92.252292 -123.995942)
		(end 94.0435 -125.78715)
		(width 0.127)
		(layer "B.Cu")
		(net "DEBUG_GPIO_BMC_2")
	)
	(segment
		(start 70.5358 -122.3264)
		(end 71.2978 -123.0884)
		(width 0.127)
		(layer "B.Cu")
		(net "DEBUG_GPIO_BMC_2")
	)
	(segment
		(start 53.518562 -114.490246)
		(end 54.150006 -114.490246)
		(width 0.127)
		(layer "B.Cu")
		(net "DEBUG_GPIO_BMC_2")
	)
	(segment
		(start 94.0435 -125.78715)
		(end 94.0435 -127.155956)
		(width 0.127)
		(layer "B.Cu")
		(net "DEBUG_GPIO_BMC_2")
	)
	(segment
		(start 71.2978 -123.0884)
		(end 75.511914 -127.302514)
		(width 0.127)
		(layer "B.Cu")
		(net "DEBUG_GPIO_BMC_2")
	)
	(segment
		(start 54.150006 -114.490246)
		(end 54.15026 -114.4905)
		(width 0.127)
		(layer "B.Cu")
		(net "DEBUG_GPIO_BMC_2")
	)
	(segment
		(start 41.312846 -114.4905)
		(end 53.518308 -114.4905)
		(width 0.127)
		(layer "B.Cu")
		(net "DEBUG_GPIO_BMC_2")
	)
	(segment
		(start 94.644718 -138.195304)
		(end 94.644718 -139.568682)
		(width 0.127)
		(layer "B.Cu")
		(net "DEBUG_GPIO_BMC_2")
	)
	(segment
		(start 96.100646 -134.071868)
		(end 96.1009 -134.072122)
		(width 0.127)
		(layer "B.Cu")
		(net "DEBUG_GPIO_BMC_2")
	)
	(segment
		(start 96.100646 -129.213102)
		(end 96.100646 -134.071868)
		(width 0.127)
		(layer "B.Cu")
		(net "DEBUG_GPIO_BMC_2")
	)
	(segment
		(start 75.511914 -127.302514)
		(end 82.775298 -127.302514)
		(width 0.127)
		(layer "B.Cu")
		(net "DEBUG_GPIO_BMC_2")
	)
	(segment
		(start 62.005972 -122.3264)
		(end 70.5358 -122.3264)
		(width 0.127)
		(layer "B.Cu")
		(net "DEBUG_GPIO_BMC_2")
	)
	(segment
		(start 31.659576 -117.4369)
		(end 28.504388 -117.4369)
		(width 0.127)
		(layer "In5.Cu")
		(net "DEBUG_GPIO_BMC_2")
	)
	(segment
		(start 33.716976 -115.3795)
		(end 31.659576 -117.4369)
		(width 0.127)
		(layer "In5.Cu")
		(net "DEBUG_GPIO_BMC_2")
	)
	(segment
		(start 25.515062 -114.447574)
		(end 15.69974 -114.447574)
		(width 0.127)
		(layer "In5.Cu")
		(net "DEBUG_GPIO_BMC_2")
	)
	(segment
		(start 5.881878 -124.265436)
		(end 5.881878 -148.552154)
		(width 0.127)
		(layer "In5.Cu")
		(net "DEBUG_GPIO_BMC_2")
	)
	(segment
		(start 15.69974 -114.447574)
		(end 5.881878 -124.265436)
		(width 0.127)
		(layer "In5.Cu")
		(net "DEBUG_GPIO_BMC_2")
	)
	(segment
		(start 28.504388 -117.4369)
		(end 25.515062 -114.447574)
		(width 0.127)
		(layer "In5.Cu")
		(net "DEBUG_GPIO_BMC_2")
	)
	(segment
		(start 5.881878 -148.552154)
		(end 10.69975 -153.370026)
		(width 0.127)
		(layer "In5.Cu")
		(net "DEBUG_GPIO_BMC_2")
	)
	(segment
		(start 35.81019 -115.3795)
		(end 33.716976 -115.3795)
		(width 0.127)
		(layer "In5.Cu")
		(net "DEBUG_GPIO_BMC_2")
	)
	(segment
		(start 10.69975 -153.370026)
		(end 25.34666 -153.370026)
		(width 0.127)
		(layer "In5.Cu")
		(net "DEBUG_GPIO_BMC_2")
	)
	(segment
		(start 25.34666 -153.370026)
		(end 26.037286 -152.6794)
		(width 0.127)
		(layer "In5.Cu")
		(net "DEBUG_GPIO_BMC_2")
	)
	(segment
		(start 26.777442 -151.75992)
		(end 28.75153 -151.75992)
		(width 0.127)
		(layer "F.Cu")
		(net "DEBUG_GPIO_BMC_1")
	)
	(segment
		(start 25.028398 -152.677876)
		(end 25.664668 -152.041606)
		(width 0.127)
		(layer "F.Cu")
		(net "DEBUG_GPIO_BMC_1")
	)
	(segment
		(start 25.664668 -152.041606)
		(end 26.495756 -152.041606)
		(width 0.127)
		(layer "F.Cu")
		(net "DEBUG_GPIO_BMC_1")
	)
	(segment
		(start 28.75153 -151.75992)
		(end 29.012134 -151.499316)
		(width 0.127)
		(layer "F.Cu")
		(net "DEBUG_GPIO_BMC_1")
	)
	(segment
		(start 94.615 -139.1666)
		(end 95.176086 -139.727686)
		(width 0.127)
		(layer "F.Cu")
		(net "DEBUG_GPIO_BMC_1")
	)
	(segment
		(start 95.176086 -139.727686)
		(end 95.996506 -139.727686)
		(width 0.127)
		(layer "F.Cu")
		(net "DEBUG_GPIO_BMC_1")
	)
	(segment
		(start 26.495756 -152.041606)
		(end 26.777442 -151.75992)
		(width 0.127)
		(layer "F.Cu")
		(net "DEBUG_GPIO_BMC_1")
	)
	(segment
		(start 94.173802 -139.1666)
		(end 94.615 -139.1666)
		(width 0.127)
		(layer "F.Cu")
		(net "DEBUG_GPIO_BMC_1")
	)
	(via
		(at 71.269098 -124.909072)
		(size 0.6096)
		(drill 0.3048)
		(layers "F.Cu" "B.Cu")
		(net "DEBUG_GPIO_BMC_1")
	)
	(via
		(at 35.057842 -115.871752)
		(size 0.508)
		(drill 0.254)
		(layers "F.Cu" "B.Cu")
		(net "DEBUG_GPIO_BMC_1")
	)
	(via
		(at 25.028398 -152.677876)
		(size 0.508)
		(drill 0.254)
		(layers "F.Cu" "B.Cu")
		(net "DEBUG_GPIO_BMC_1")
	)
	(via
		(at 94.173802 -139.1666)
		(size 0.508)
		(drill 0.254)
		(layers "F.Cu" "B.Cu")
		(net "DEBUG_GPIO_BMC_1")
	)
	(segment
		(start 95.719646 -134.229856)
		(end 95.719646 -129.37109)
		(width 0.127)
		(layer "B.Cu")
		(net "DEBUG_GPIO_BMC_1")
	)
	(segment
		(start 41.470834 -114.8715)
		(end 53.676296 -114.8715)
		(width 0.127)
		(layer "B.Cu")
		(net "DEBUG_GPIO_BMC_1")
	)
	(segment
		(start 95.719646 -129.37109)
		(end 93.6625 -127.313944)
		(width 0.127)
		(layer "B.Cu")
		(net "DEBUG_GPIO_BMC_1")
	)
	(segment
		(start 53.992018 -114.871246)
		(end 53.992272 -114.8715)
		(width 0.127)
		(layer "B.Cu")
		(net "DEBUG_GPIO_BMC_1")
	)
	(segment
		(start 95.7199 -136.581134)
		(end 95.7199 -134.23011)
		(width 0.127)
		(layer "B.Cu")
		(net "DEBUG_GPIO_BMC_1")
	)
	(segment
		(start 94.173802 -139.1666)
		(end 94.263718 -139.076684)
		(width 0.127)
		(layer "B.Cu")
		(net "DEBUG_GPIO_BMC_1")
	)
	(segment
		(start 54.012084 -114.8715)
		(end 62.025784 -122.8852)
		(width 0.127)
		(layer "B.Cu")
		(net "DEBUG_GPIO_BMC_1")
	)
	(segment
		(start 74.324718 -126.873)
		(end 73.233026 -126.873)
		(width 0.127)
		(layer "B.Cu")
		(net "DEBUG_GPIO_BMC_1")
	)
	(segment
		(start 53.992272 -114.8715)
		(end 54.012084 -114.8715)
		(width 0.127)
		(layer "B.Cu")
		(net "DEBUG_GPIO_BMC_1")
	)
	(segment
		(start 53.676296 -114.8715)
		(end 53.67655 -114.871246)
		(width 0.127)
		(layer "B.Cu")
		(net "DEBUG_GPIO_BMC_1")
	)
	(segment
		(start 35.057842 -115.871752)
		(end 40.470582 -115.871752)
		(width 0.127)
		(layer "B.Cu")
		(net "DEBUG_GPIO_BMC_1")
	)
	(segment
		(start 92.094304 -124.376942)
		(end 86.239858 -124.376942)
		(width 0.127)
		(layer "B.Cu")
		(net "DEBUG_GPIO_BMC_1")
	)
	(segment
		(start 75.135232 -127.683514)
		(end 74.324718 -126.873)
		(width 0.127)
		(layer "B.Cu")
		(net "DEBUG_GPIO_BMC_1")
	)
	(segment
		(start 73.233026 -126.873)
		(end 71.269098 -124.909072)
		(width 0.127)
		(layer "B.Cu")
		(net "DEBUG_GPIO_BMC_1")
	)
	(segment
		(start 62.025784 -122.8852)
		(end 69.245226 -122.8852)
		(width 0.127)
		(layer "B.Cu")
		(net "DEBUG_GPIO_BMC_1")
	)
	(segment
		(start 95.7199 -134.23011)
		(end 95.719646 -134.229856)
		(width 0.127)
		(layer "B.Cu")
		(net "DEBUG_GPIO_BMC_1")
	)
	(segment
		(start 40.470582 -115.871752)
		(end 41.470834 -114.8715)
		(width 0.127)
		(layer "B.Cu")
		(net "DEBUG_GPIO_BMC_1")
	)
	(segment
		(start 93.6625 -127.313944)
		(end 93.6625 -125.945138)
		(width 0.127)
		(layer "B.Cu")
		(net "DEBUG_GPIO_BMC_1")
	)
	(segment
		(start 53.67655 -114.871246)
		(end 53.992018 -114.871246)
		(width 0.127)
		(layer "B.Cu")
		(net "DEBUG_GPIO_BMC_1")
	)
	(segment
		(start 86.239858 -124.376942)
		(end 82.933286 -127.683514)
		(width 0.127)
		(layer "B.Cu")
		(net "DEBUG_GPIO_BMC_1")
	)
	(segment
		(start 93.6625 -125.945138)
		(end 92.094304 -124.376942)
		(width 0.127)
		(layer "B.Cu")
		(net "DEBUG_GPIO_BMC_1")
	)
	(segment
		(start 94.263718 -138.037316)
		(end 95.7199 -136.581134)
		(width 0.127)
		(layer "B.Cu")
		(net "DEBUG_GPIO_BMC_1")
	)
	(segment
		(start 82.933286 -127.683514)
		(end 75.135232 -127.683514)
		(width 0.127)
		(layer "B.Cu")
		(net "DEBUG_GPIO_BMC_1")
	)
	(segment
		(start 69.245226 -122.8852)
		(end 71.269098 -124.909072)
		(width 0.127)
		(layer "B.Cu")
		(net "DEBUG_GPIO_BMC_1")
	)
	(segment
		(start 94.263718 -139.076684)
		(end 94.263718 -138.037316)
		(width 0.127)
		(layer "B.Cu")
		(net "DEBUG_GPIO_BMC_1")
	)
	(segment
		(start 24.717248 -152.989026)
		(end 25.028398 -152.677876)
		(width 0.127)
		(layer "In5.Cu")
		(net "DEBUG_GPIO_BMC_1")
	)
	(segment
		(start 6.262878 -148.394166)
		(end 10.857738 -152.989026)
		(width 0.127)
		(layer "In5.Cu")
		(net "DEBUG_GPIO_BMC_1")
	)
	(segment
		(start 15.857728 -114.828574)
		(end 6.262878 -124.423424)
		(width 0.127)
		(layer "In5.Cu")
		(net "DEBUG_GPIO_BMC_1")
	)
	(segment
		(start 28.3464 -117.8179)
		(end 25.357074 -114.828574)
		(width 0.127)
		(layer "In5.Cu")
		(net "DEBUG_GPIO_BMC_1")
	)
	(segment
		(start 33.886648 -115.871752)
		(end 31.9405 -117.8179)
		(width 0.127)
		(layer "In5.Cu")
		(net "DEBUG_GPIO_BMC_1")
	)
	(segment
		(start 10.857738 -152.989026)
		(end 24.717248 -152.989026)
		(width 0.127)
		(layer "In5.Cu")
		(net "DEBUG_GPIO_BMC_1")
	)
	(segment
		(start 25.357074 -114.828574)
		(end 15.857728 -114.828574)
		(width 0.127)
		(layer "In5.Cu")
		(net "DEBUG_GPIO_BMC_1")
	)
	(segment
		(start 31.9405 -117.8179)
		(end 28.3464 -117.8179)
		(width 0.127)
		(layer "In5.Cu")
		(net "DEBUG_GPIO_BMC_1")
	)
	(segment
		(start 6.262878 -124.423424)
		(end 6.262878 -148.394166)
		(width 0.127)
		(layer "In5.Cu")
		(net "DEBUG_GPIO_BMC_1")
	)
	(segment
		(start 35.057842 -115.871752)
		(end 33.886648 -115.871752)
		(width 0.127)
		(layer "In5.Cu")
		(net "DEBUG_GPIO_BMC_1")
	)
	(segment
		(start 53.6448 -155.2702)
		(end 53.6448 -156.21)
		(width 0.127)
		(layer "F.Cu")
		(net "ADC_P2V5_STBY")
	)
	(segment
		(start 52.505864 -152.205944)
		(end 52.505864 -154.131264)
		(width 0.127)
		(layer "F.Cu")
		(net "ADC_P2V5_STBY")
	)
	(segment
		(start 52.505864 -154.131264)
		(end 53.6448 -155.2702)
		(width 0.127)
		(layer "F.Cu")
		(net "ADC_P2V5_STBY")
	)
	(segment
		(start 53.3654 -157.77972)
		(end 53.5432 -157.95752)
		(width 0.127)
		(layer "F.Cu")
		(net "ADC_P2V5_STBY")
	)
	(segment
		(start 53.5432 -158.115)
		(end 53.70068 -158.115)
		(width 0.127)
		(layer "F.Cu")
		(net "ADC_P2V5_STBY")
	)
	(segment
		(start 54.4703 -158.9659)
		(end 54.7116 -159.2072)
		(width 0.127)
		(layer "F.Cu")
		(net "ADC_P2V5_STBY")
	)
	(segment
		(start 53.3654 -156.4894)
		(end 53.3654 -157.77972)
		(width 0.127)
		(layer "F.Cu")
		(net "ADC_P2V5_STBY")
	)
	(segment
		(start 52.099972 -151.800052)
		(end 52.505864 -152.205944)
		(width 0.127)
		(layer "F.Cu")
		(net "ADC_P2V5_STBY")
	)
	(segment
		(start 53.70068 -158.115)
		(end 54.4703 -158.88462)
		(width 0.127)
		(layer "F.Cu")
		(net "ADC_P2V5_STBY")
	)
	(segment
		(start 54.552342 -166.521384)
		(end 54.539642 -166.508684)
		(width 0.127)
		(layer "F.Cu")
		(net "ADC_P2V5_STBY")
	)
	(segment
		(start 54.539642 -166.508684)
		(end 53.371242 -166.508684)
		(width 0.127)
		(layer "F.Cu")
		(net "ADC_P2V5_STBY")
	)
	(segment
		(start 53.5432 -157.95752)
		(end 53.5432 -158.115)
		(width 0.127)
		(layer "F.Cu")
		(net "ADC_P2V5_STBY")
	)
	(segment
		(start 53.371242 -166.508684)
		(end 52.869084 -166.508684)
		(width 0.127)
		(layer "F.Cu")
		(net "ADC_P2V5_STBY")
	)
	(segment
		(start 52.869084 -166.508684)
		(end 52.578 -166.2176)
		(width 0.127)
		(layer "F.Cu")
		(net "ADC_P2V5_STBY")
	)
	(segment
		(start 54.4703 -158.88462)
		(end 54.4703 -158.9659)
		(width 0.127)
		(layer "F.Cu")
		(net "ADC_P2V5_STBY")
	)
	(segment
		(start 55.530242 -166.521384)
		(end 54.552342 -166.521384)
		(width 0.127)
		(layer "F.Cu")
		(net "ADC_P2V5_STBY")
	)
	(segment
		(start 53.6448 -156.21)
		(end 53.3654 -156.4894)
		(width 0.127)
		(layer "F.Cu")
		(net "ADC_P2V5_STBY")
	)
	(via
		(at 53.5432 -158.115)
		(size 0.6604)
		(drill 0.3302)
		(layers "F.Cu" "B.Cu")
		(net "ADC_P2V5_STBY")
	)
	(via
		(at 52.578 -166.2176)
		(size 0.508)
		(drill 0.254)
		(layers "F.Cu" "B.Cu")
		(net "ADC_P2V5_STBY")
	)
	(via
		(at 54.7116 -159.2072)
		(size 0.508)
		(drill 0.254)
		(layers "F.Cu" "B.Cu")
		(net "ADC_P2V5_STBY")
	)
	(segment
		(start 52.4129 -164.6555)
		(end 52.7304 -164.973)
		(width 0.127)
		(layer "In2.Cu")
		(net "ADC_P2V5_STBY")
	)
	(segment
		(start 52.4129 -161.5059)
		(end 52.4129 -164.6555)
		(width 0.127)
		(layer "In2.Cu")
		(net "ADC_P2V5_STBY")
	)
	(segment
		(start 54.7116 -159.2072)
		(end 52.4129 -161.5059)
		(width 0.127)
		(layer "In2.Cu")
		(net "ADC_P2V5_STBY")
	)
	(segment
		(start 52.7304 -164.973)
		(end 52.7304 -166.0652)
		(width 0.127)
		(layer "In2.Cu")
		(net "ADC_P2V5_STBY")
	)
	(segment
		(start 52.7304 -166.0652)
		(end 52.578 -166.2176)
		(width 0.127)
		(layer "In2.Cu")
		(net "ADC_P2V5_STBY")
	)
	(segment
		(start 51.299872 -151.800052)
		(end 51.299618 -151.800052)
		(width 0.127)
		(layer "F.Cu")
		(net "ADC_P1V5")
	)
	(segment
		(start 51.299618 -151.800052)
		(end 50.899822 -152.199848)
		(width 0.127)
		(layer "F.Cu")
		(net "ADC_P1V5")
	)
	(via
		(at 50.899822 -152.199848)
		(size 0.4572)
		(drill 0.2032)
		(layers "F.Cu" "B.Cu")
		(net "ADC_P1V5")
	)
	(segment
		(start 50.105056 -151.599646)
		(end 50.29962 -151.599646)
		(width 0.127)
		(layer "B.Cu")
		(net "ADC_P1V5")
	)
	(segment
		(start 50.29962 -151.599646)
		(end 50.899822 -152.199848)
		(width 0.127)
		(layer "B.Cu")
		(net "ADC_P1V5")
	)
	(segment
		(start 52.899818 -151.800052)
		(end 53.299614 -152.199848)
		(width 0.127)
		(layer "F.Cu")
		(net "ADC_P1V2_STBY")
	)
	(via
		(at 53.299614 -152.199848)
		(size 0.4572)
		(drill 0.2032)
		(layers "F.Cu" "B.Cu")
		(net "ADC_P1V2_STBY")
	)
	(via
		(at 38.5572 -155.0162)
		(size 0.508)
		(drill 0.254)
		(layers "F.Cu" "B.Cu")
		(net "ADC_P1V2_STBY")
	)
	(via
		(at 35.4076 -156.21)
		(size 0.6096)
		(drill 0.3048)
		(layers "F.Cu" "B.Cu")
		(net "ADC_P1V2_STBY")
	)
	(segment
		(start 34.8869 -156.21)
		(end 34.6964 -156.0195)
		(width 0.127)
		(layer "B.Cu")
		(net "ADC_P1V2_STBY")
	)
	(segment
		(start 36.531042 -156.361384)
		(end 37.508942 -156.361384)
		(width 0.127)
		(layer "B.Cu")
		(net "ADC_P1V2_STBY")
	)
	(segment
		(start 35.4076 -156.21)
		(end 34.8869 -156.21)
		(width 0.127)
		(layer "B.Cu")
		(net "ADC_P1V2_STBY")
	)
	(segment
		(start 34.6964 -156.0195)
		(end 33.9344 -156.0195)
		(width 0.127)
		(layer "B.Cu")
		(net "ADC_P1V2_STBY")
	)
	(segment
		(start 37.631116 -156.374084)
		(end 37.521642 -156.374084)
		(width 0.127)
		(layer "B.Cu")
		(net "ADC_P1V2_STBY")
	)
	(segment
		(start 35.9156 -156.361384)
		(end 36.531042 -156.361384)
		(width 0.127)
		(layer "B.Cu")
		(net "ADC_P1V2_STBY")
	)
	(segment
		(start 37.508942 -156.361384)
		(end 37.521642 -156.374084)
		(width 0.127)
		(layer "B.Cu")
		(net "ADC_P1V2_STBY")
	)
	(segment
		(start 38.5572 -155.448)
		(end 37.631116 -156.374084)
		(width 0.127)
		(layer "B.Cu")
		(net "ADC_P1V2_STBY")
	)
	(segment
		(start 35.4076 -156.21)
		(end 35.764216 -156.21)
		(width 0.127)
		(layer "B.Cu")
		(net "ADC_P1V2_STBY")
	)
	(segment
		(start 35.764216 -156.21)
		(end 35.9156 -156.361384)
		(width 0.127)
		(layer "B.Cu")
		(net "ADC_P1V2_STBY")
	)
	(segment
		(start 38.5572 -155.0162)
		(end 38.5572 -155.448)
		(width 0.127)
		(layer "B.Cu")
		(net "ADC_P1V2_STBY")
	)
	(segment
		(start 53.299614 -153.557986)
		(end 53.299614 -152.199848)
		(width 0.127)
		(layer "In5.Cu")
		(net "ADC_P1V2_STBY")
	)
	(segment
		(start 52.585366 -154.272234)
		(end 53.299614 -153.557986)
		(width 0.127)
		(layer "In5.Cu")
		(net "ADC_P1V2_STBY")
	)
	(segment
		(start 39.301166 -154.272234)
		(end 52.585366 -154.272234)
		(width 0.127)
		(layer "In5.Cu")
		(net "ADC_P1V2_STBY")
	)
	(segment
		(start 38.5572 -155.0162)
		(end 39.301166 -154.272234)
		(width 0.127)
		(layer "In5.Cu")
		(net "ADC_P1V2_STBY")
	)
	(segment
		(start 66.757042 -159.549084)
		(end 65.753742 -159.549084)
		(width 0.127)
		(layer "F.Cu")
		(net "ADC_P1V15_STBY")
	)
	(segment
		(start 66.675 -162.433)
		(end 66.167 -161.925)
		(width 0.127)
		(layer "F.Cu")
		(net "ADC_P1V15_STBY")
	)
	(segment
		(start 65.753742 -159.549084)
		(end 65.741042 -159.536384)
		(width 0.127)
		(layer "F.Cu")
		(net "ADC_P1V15_STBY")
	)
	(segment
		(start 65.741042 -159.536384)
		(end 65.741042 -160.356042)
		(width 0.127)
		(layer "F.Cu")
		(net "ADC_P1V15_STBY")
	)
	(segment
		(start 65.741042 -160.356042)
		(end 65.753742 -160.368742)
		(width 0.127)
		(layer "F.Cu")
		(net "ADC_P1V15_STBY")
	)
	(segment
		(start 50.900076 -150.599648)
		(end 51.299872 -150.199852)
		(width 0.127)
		(layer "F.Cu")
		(net "ADC_P1V15_STBY")
	)
	(segment
		(start 67.5005 -162.433)
		(end 66.675 -162.433)
		(width 0.127)
		(layer "F.Cu")
		(net "ADC_P1V15_STBY")
	)
	(segment
		(start 66.167 -161.925)
		(end 65.753742 -161.511742)
		(width 0.127)
		(layer "F.Cu")
		(net "ADC_P1V15_STBY")
	)
	(segment
		(start 65.753742 -161.511742)
		(end 65.753742 -160.368742)
		(width 0.127)
		(layer "F.Cu")
		(net "ADC_P1V15_STBY")
	)
	(segment
		(start 50.899822 -150.599648)
		(end 50.900076 -150.599648)
		(width 0.127)
		(layer "F.Cu")
		(net "ADC_P1V15_STBY")
	)
	(via
		(at 50.899822 -150.599648)
		(size 0.4572)
		(drill 0.2032)
		(layers "F.Cu" "B.Cu")
		(net "ADC_P1V15_STBY")
	)
	(via
		(at 65.753742 -160.368742)
		(size 0.508)
		(drill 0.254)
		(layers "F.Cu" "B.Cu")
		(net "ADC_P1V15_STBY")
	)
	(via
		(at 66.167 -161.925)
		(size 0.6604)
		(drill 0.3302)
		(layers "F.Cu" "B.Cu")
		(net "ADC_P1V15_STBY")
	)
	(segment
		(start 65.289684 -160.8328)
		(end 65.753742 -160.368742)
		(width 0.127)
		(layer "In2.Cu")
		(net "ADC_P1V15_STBY")
	)
	(segment
		(start 51.305968 -151.691594)
		(end 53.131974 -153.5176)
		(width 0.127)
		(layer "In2.Cu")
		(net "ADC_P1V15_STBY")
	)
	(segment
		(start 50.899822 -150.599648)
		(end 51.305968 -151.005794)
		(width 0.127)
		(layer "In2.Cu")
		(net "ADC_P1V15_STBY")
	)
	(segment
		(start 61.468 -157.988)
		(end 64.3128 -160.8328)
		(width 0.127)
		(layer "In2.Cu")
		(net "ADC_P1V15_STBY")
	)
	(segment
		(start 57.912 -157.48)
		(end 58.42 -157.988)
		(width 0.127)
		(layer "In2.Cu")
		(net "ADC_P1V15_STBY")
	)
	(segment
		(start 57.912 -156.0576)
		(end 57.912 -157.48)
		(width 0.127)
		(layer "In2.Cu")
		(net "ADC_P1V15_STBY")
	)
	(segment
		(start 53.131974 -153.5176)
		(end 55.372 -153.5176)
		(width 0.127)
		(layer "In2.Cu")
		(net "ADC_P1V15_STBY")
	)
	(segment
		(start 51.305968 -151.005794)
		(end 51.305968 -151.691594)
		(width 0.127)
		(layer "In2.Cu")
		(net "ADC_P1V15_STBY")
	)
	(segment
		(start 58.42 -157.988)
		(end 61.468 -157.988)
		(width 0.127)
		(layer "In2.Cu")
		(net "ADC_P1V15_STBY")
	)
	(segment
		(start 64.3128 -160.8328)
		(end 65.289684 -160.8328)
		(width 0.127)
		(layer "In2.Cu")
		(net "ADC_P1V15_STBY")
	)
	(segment
		(start 55.372 -153.5176)
		(end 57.912 -156.0576)
		(width 0.127)
		(layer "In2.Cu")
		(net "ADC_P1V15_STBY")
	)
	(segment
		(start 52.6796 -156.94279)
		(end 52.485544 -157.136846)
		(width 0.127)
		(layer "F.Cu")
		(net "ADC_P0V975")
	)
	(segment
		(start 52.6796 -155.85059)
		(end 52.6796 -156.94279)
		(width 0.127)
		(layer "F.Cu")
		(net "ADC_P0V975")
	)
	(segment
		(start 51.260502 -152.599898)
		(end 50.9016 -152.9588)
		(width 0.127)
		(layer "F.Cu")
		(net "ADC_P0V975")
	)
	(segment
		(start 51.299872 -152.599898)
		(end 51.260502 -152.599898)
		(width 0.127)
		(layer "F.Cu")
		(net "ADC_P0V975")
	)
	(segment
		(start 50.9016 -154.07259)
		(end 52.6796 -155.85059)
		(width 0.127)
		(layer "F.Cu")
		(net "ADC_P0V975")
	)
	(segment
		(start 50.9016 -152.9588)
		(end 50.9016 -154.07259)
		(width 0.127)
		(layer "F.Cu")
		(net "ADC_P0V975")
	)
	(segment
		(start 46.459648 -150.999952)
		(end 46.101 -151.3586)
		(width 0.127)
		(layer "F.Cu")
		(net "PCIE_WAKE_N")
	)
	(segment
		(start 77.151738 -61.74994)
		(end 77.668374 -61.233304)
		(width 0.127)
		(layer "F.Cu")
		(net "PCIE_WAKE_N")
	)
	(segment
		(start 75.475084 -61.74994)
		(end 77.151738 -61.74994)
		(width 0.127)
		(layer "F.Cu")
		(net "PCIE_WAKE_N")
	)
	(segment
		(start 46.500034 -150.999952)
		(end 46.459648 -150.999952)
		(width 0.127)
		(layer "F.Cu")
		(net "PCIE_WAKE_N")
	)
	(via
		(at 70.302882 -149.582378)
		(size 0.508)
		(drill 0.254)
		(layers "F.Cu" "B.Cu")
		(net "PCIE_WAKE_N")
	)
	(via
		(at 46.101 -151.3586)
		(size 0.4572)
		(drill 0.2032)
		(layers "F.Cu" "B.Cu")
		(net "PCIE_WAKE_N")
	)
	(via
		(at 81.7118 -110.9091)
		(size 0.508)
		(drill 0.254)
		(layers "F.Cu" "B.Cu")
		(net "PCIE_WAKE_N")
	)
	(via
		(at 58.5724 -154.4574)
		(size 0.4572)
		(drill 0.2032)
		(layers "F.Cu" "B.Cu")
		(net "PCIE_WAKE_N")
	)
	(via
		(at 77.668374 -61.233304)
		(size 0.508)
		(drill 0.254)
		(layers "F.Cu" "B.Cu")
		(net "PCIE_WAKE_N")
	)
	(via
		(at 45.553376 -154.307286)
		(size 0.6096)
		(drill 0.3048)
		(layers "F.Cu" "B.Cu")
		(net "PCIE_WAKE_N")
	)
	(segment
		(start 85.020912 -101.86416)
		(end 85.020912 -110.0455)
		(width 0.127)
		(layer "B.Cu")
		(net "PCIE_WAKE_N")
	)
	(segment
		(start 75.44435 -95.73895)
		(end 76.8604 -97.155)
		(width 0.127)
		(layer "B.Cu")
		(net "PCIE_WAKE_N")
	)
	(segment
		(start 46.1772 -153.683462)
		(end 45.553376 -154.307286)
		(width 0.127)
		(layer "B.Cu")
		(net "PCIE_WAKE_N")
	)
	(segment
		(start 45.6946 -151.765)
		(end 45.6946 -152.440386)
		(width 0.127)
		(layer "B.Cu")
		(net "PCIE_WAKE_N")
	)
	(segment
		(start 82.382614 -111.262414)
		(end 82.0293 -110.9091)
		(width 0.127)
		(layer "B.Cu")
		(net "PCIE_WAKE_N")
	)
	(segment
		(start 46.1772 -152.922986)
		(end 46.1772 -153.683462)
		(width 0.127)
		(layer "B.Cu")
		(net "PCIE_WAKE_N")
	)
	(segment
		(start 85.020912 -110.0455)
		(end 83.803998 -111.262414)
		(width 0.127)
		(layer "B.Cu")
		(net "PCIE_WAKE_N")
	)
	(segment
		(start 77.668374 -61.233304)
		(end 75.44435 -63.457328)
		(width 0.127)
		(layer "B.Cu")
		(net "PCIE_WAKE_N")
	)
	(segment
		(start 45.6946 -152.440386)
		(end 46.1772 -152.922986)
		(width 0.127)
		(layer "B.Cu")
		(net "PCIE_WAKE_N")
	)
	(segment
		(start 83.803998 -111.262414)
		(end 82.382614 -111.262414)
		(width 0.127)
		(layer "B.Cu")
		(net "PCIE_WAKE_N")
	)
	(segment
		(start 79.610458 -97.155)
		(end 81.744058 -99.2886)
		(width 0.127)
		(layer "B.Cu")
		(net "PCIE_WAKE_N")
	)
	(segment
		(start 81.744058 -99.2886)
		(end 82.445352 -99.2886)
		(width 0.127)
		(layer "B.Cu")
		(net "PCIE_WAKE_N")
	)
	(segment
		(start 45.143928 -155.889198)
		(end 45.143928 -154.716734)
		(width 0.127)
		(layer "B.Cu")
		(net "PCIE_WAKE_N")
	)
	(segment
		(start 76.8604 -97.155)
		(end 79.610458 -97.155)
		(width 0.127)
		(layer "B.Cu")
		(net "PCIE_WAKE_N")
	)
	(segment
		(start 46.101 -151.3586)
		(end 45.6946 -151.765)
		(width 0.127)
		(layer "B.Cu")
		(net "PCIE_WAKE_N")
	)
	(segment
		(start 82.445352 -99.2886)
		(end 85.020912 -101.86416)
		(width 0.127)
		(layer "B.Cu")
		(net "PCIE_WAKE_N")
	)
	(segment
		(start 82.0293 -110.9091)
		(end 81.7118 -110.9091)
		(width 0.127)
		(layer "B.Cu")
		(net "PCIE_WAKE_N")
	)
	(segment
		(start 44.699936 -157.25648)
		(end 44.699936 -156.33319)
		(width 0.127)
		(layer "B.Cu")
		(net "PCIE_WAKE_N")
	)
	(segment
		(start 44.699936 -156.33319)
		(end 45.143928 -155.889198)
		(width 0.127)
		(layer "B.Cu")
		(net "PCIE_WAKE_N")
	)
	(segment
		(start 45.143928 -154.716734)
		(end 45.553376 -154.307286)
		(width 0.127)
		(layer "B.Cu")
		(net "PCIE_WAKE_N")
	)
	(segment
		(start 75.44435 -63.457328)
		(end 75.44435 -95.73895)
		(width 0.127)
		(layer "B.Cu")
		(net "PCIE_WAKE_N")
	)
	(segment
		(start 51.86299 -149.406356)
		(end 47.367444 -149.406356)
		(width 0.127)
		(layer "In2.Cu")
		(net "PCIE_WAKE_N")
	)
	(segment
		(start 46.387512 -151.3586)
		(end 46.101 -151.3586)
		(width 0.127)
		(layer "In2.Cu")
		(net "PCIE_WAKE_N")
	)
	(segment
		(start 69.102224 -142.150592)
		(end 69.102224 -146.474942)
		(width 0.127)
		(layer "In2.Cu")
		(net "PCIE_WAKE_N")
	)
	(segment
		(start 68.834 -124.346716)
		(end 68.834 -135.8646)
		(width 0.127)
		(layer "In2.Cu")
		(net "PCIE_WAKE_N")
	)
	(segment
		(start 78.937358 -110.5154)
		(end 72.517 -116.935758)
		(width 0.127)
		(layer "In2.Cu")
		(net "PCIE_WAKE_N")
	)
	(segment
		(start 46.8376 -150.908512)
		(end 46.387512 -151.3586)
		(width 0.127)
		(layer "In2.Cu")
		(net "PCIE_WAKE_N")
	)
	(segment
		(start 68.54571 -141.594078)
		(end 69.102224 -142.150592)
		(width 0.127)
		(layer "In2.Cu")
		(net "PCIE_WAKE_N")
	)
	(segment
		(start 81.7118 -110.9091)
		(end 81.0641 -110.9091)
		(width 0.127)
		(layer "In2.Cu")
		(net "PCIE_WAKE_N")
	)
	(segment
		(start 69.469 -122.885454)
		(end 69.469 -123.711716)
		(width 0.127)
		(layer "In2.Cu")
		(net "PCIE_WAKE_N")
	)
	(segment
		(start 69.905118 -149.184614)
		(end 70.302882 -149.582378)
		(width 0.127)
		(layer "In2.Cu")
		(net "PCIE_WAKE_N")
	)
	(segment
		(start 72.517 -119.837454)
		(end 69.469 -122.885454)
		(width 0.127)
		(layer "In2.Cu")
		(net "PCIE_WAKE_N")
	)
	(segment
		(start 72.517 -116.935758)
		(end 72.517 -119.837454)
		(width 0.127)
		(layer "In2.Cu")
		(net "PCIE_WAKE_N")
	)
	(segment
		(start 46.8376 -149.9362)
		(end 46.8376 -150.908512)
		(width 0.127)
		(layer "In2.Cu")
		(net "PCIE_WAKE_N")
	)
	(segment
		(start 68.5673 -137.641076)
		(end 69.102224 -138.176)
		(width 0.127)
		(layer "In2.Cu")
		(net "PCIE_WAKE_N")
	)
	(segment
		(start 69.102224 -146.474942)
		(end 69.905118 -147.277836)
		(width 0.127)
		(layer "In2.Cu")
		(net "PCIE_WAKE_N")
	)
	(segment
		(start 47.367444 -149.406356)
		(end 46.8376 -149.9362)
		(width 0.127)
		(layer "In2.Cu")
		(net "PCIE_WAKE_N")
	)
	(segment
		(start 58.5724 -154.4574)
		(end 55.908702 -151.793702)
		(width 0.127)
		(layer "In2.Cu")
		(net "PCIE_WAKE_N")
	)
	(segment
		(start 69.102224 -140.647928)
		(end 68.54571 -141.204442)
		(width 0.127)
		(layer "In2.Cu")
		(net "PCIE_WAKE_N")
	)
	(segment
		(start 68.54571 -141.204442)
		(end 68.54571 -141.594078)
		(width 0.127)
		(layer "In2.Cu")
		(net "PCIE_WAKE_N")
	)
	(segment
		(start 69.102224 -138.176)
		(end 69.102224 -140.647928)
		(width 0.127)
		(layer "In2.Cu")
		(net "PCIE_WAKE_N")
	)
	(segment
		(start 52.093368 -151.550624)
		(end 52.093368 -149.636734)
		(width 0.127)
		(layer "In2.Cu")
		(net "PCIE_WAKE_N")
	)
	(segment
		(start 80.6704 -110.5154)
		(end 78.937358 -110.5154)
		(width 0.127)
		(layer "In2.Cu")
		(net "PCIE_WAKE_N")
	)
	(segment
		(start 69.905118 -147.277836)
		(end 69.905118 -149.184614)
		(width 0.127)
		(layer "In2.Cu")
		(net "PCIE_WAKE_N")
	)
	(segment
		(start 69.469 -123.711716)
		(end 68.834 -124.346716)
		(width 0.127)
		(layer "In2.Cu")
		(net "PCIE_WAKE_N")
	)
	(segment
		(start 68.5673 -136.1313)
		(end 68.5673 -137.641076)
		(width 0.127)
		(layer "In2.Cu")
		(net "PCIE_WAKE_N")
	)
	(segment
		(start 68.834 -135.8646)
		(end 68.5673 -136.1313)
		(width 0.127)
		(layer "In2.Cu")
		(net "PCIE_WAKE_N")
	)
	(segment
		(start 81.0641 -110.9091)
		(end 80.6704 -110.5154)
		(width 0.127)
		(layer "In2.Cu")
		(net "PCIE_WAKE_N")
	)
	(segment
		(start 55.908702 -151.793702)
		(end 52.336446 -151.793702)
		(width 0.127)
		(layer "In2.Cu")
		(net "PCIE_WAKE_N")
	)
	(segment
		(start 52.093368 -149.636734)
		(end 51.86299 -149.406356)
		(width 0.127)
		(layer "In2.Cu")
		(net "PCIE_WAKE_N")
	)
	(segment
		(start 52.336446 -151.793702)
		(end 52.093368 -151.550624)
		(width 0.127)
		(layer "In2.Cu")
		(net "PCIE_WAKE_N")
	)
	(segment
		(start 59.453018 -151.9682)
		(end 62.132718 -149.2885)
		(width 0.127)
		(layer "In5.Cu")
		(net "PCIE_WAKE_N")
	)
	(segment
		(start 68.526406 -149.582378)
		(end 70.302882 -149.582378)
		(width 0.127)
		(layer "In5.Cu")
		(net "PCIE_WAKE_N")
	)
	(segment
		(start 58.7248 -151.9682)
		(end 59.453018 -151.9682)
		(width 0.127)
		(layer "In5.Cu")
		(net "PCIE_WAKE_N")
	)
	(segment
		(start 63.716662 -149.2885)
		(end 64.478662 -150.0505)
		(width 0.127)
		(layer "In5.Cu")
		(net "PCIE_WAKE_N")
	)
	(segment
		(start 58.5724 -154.4574)
		(end 58.3184 -154.2034)
		(width 0.127)
		(layer "In5.Cu")
		(net "PCIE_WAKE_N")
	)
	(segment
		(start 58.3184 -152.3746)
		(end 58.7248 -151.9682)
		(width 0.127)
		(layer "In5.Cu")
		(net "PCIE_WAKE_N")
	)
	(segment
		(start 64.478662 -150.0505)
		(end 68.058284 -150.0505)
		(width 0.127)
		(layer "In5.Cu")
		(net "PCIE_WAKE_N")
	)
	(segment
		(start 62.132718 -149.2885)
		(end 63.716662 -149.2885)
		(width 0.127)
		(layer "In5.Cu")
		(net "PCIE_WAKE_N")
	)
	(segment
		(start 58.3184 -154.2034)
		(end 58.3184 -152.3746)
		(width 0.127)
		(layer "In5.Cu")
		(net "PCIE_WAKE_N")
	)
	(segment
		(start 68.058284 -150.0505)
		(end 68.526406 -149.582378)
		(width 0.127)
		(layer "In5.Cu")
		(net "PCIE_WAKE_N")
	)
	(segment
		(start 52.07 -123.317)
		(end 52.07 -126.492)
		(width 0.127)
		(layer "F.Cu")
		(net "FLA1_WP_N")
	)
	(segment
		(start 52.07 -126.492)
		(end 52.3875 -126.8095)
		(width 0.127)
		(layer "F.Cu")
		(net "FLA1_WP_N")
	)
	(segment
		(start 52.3875 -126.8095)
		(end 53.848 -126.8095)
		(width 0.127)
		(layer "F.Cu")
		(net "FLA1_WP_N")
	)
	(segment
		(start 53.8861 -125.8062)
		(end 53.848 -126.8095)
		(width 0.127)
		(layer "F.Cu")
		(net "FLA1_WP_N")
	)
	(segment
		(start 53.8861 -125.8062)
		(end 56.012334 -125.8062)
		(width 0.127)
		(layer "F.Cu")
		(net "FLA1_WP_N")
	)
	(segment
		(start 50.546 -121.793)
		(end 52.07 -123.317)
		(width 0.127)
		(layer "F.Cu")
		(net "FLA1_WP_N")
	)
	(via
		(at 50.546 -121.793)
		(size 0.6604)
		(drill 0.3302)
		(layers "F.Cu" "B.Cu")
		(net "FLA1_WP_N")
	)
	(segment
		(start 68.0593 -120.49252)
		(end 68.0593 -119.4562)
		(width 0.127)
		(layer "F.Cu")
		(net "FLA1_SPI_RST")
	)
	(segment
		(start 68.0593 -119.4562)
		(end 65.806066 -119.4562)
		(width 0.127)
		(layer "F.Cu")
		(net "FLA1_SPI_RST")
	)
	(segment
		(start 27.559 -124.6505)
		(end 28.98013 -124.6505)
		(width 0.127)
		(layer "F.Cu")
		(net "FLA0_WP_N")
	)
	(segment
		(start 28.98013 -124.6505)
		(end 30.13583 -125.8062)
		(width 0.127)
		(layer "F.Cu")
		(net "FLA0_WP_N")
	)
	(segment
		(start 26.974546 -157.547056)
		(end 26.186892 -157.547056)
		(width 0.127)
		(layer "F.Cu")
		(net "FLA0_WP_N")
	)
	(segment
		(start 30.13583 -125.8062)
		(end 31.390844 -125.8062)
		(width 0.127)
		(layer "F.Cu")
		(net "FLA0_WP_N")
	)
	(segment
		(start 26.416 -124.6505)
		(end 27.559 -124.6505)
		(width 0.127)
		(layer "F.Cu")
		(net "FLA0_WP_N")
	)
	(segment
		(start 26.416 -124.6505)
		(end 25.5524 -124.6505)
		(width 0.127)
		(layer "F.Cu")
		(net "FLA0_WP_N")
	)
	(via
		(at 26.186892 -157.547056)
		(size 0.508)
		(drill 0.254)
		(layers "F.Cu" "B.Cu")
		(net "FLA0_WP_N")
	)
	(via
		(at 25.5524 -124.6505)
		(size 0.508)
		(drill 0.254)
		(layers "F.Cu" "B.Cu")
		(net "FLA0_WP_N")
	)
	(via
		(at 10.8077 -152.202896)
		(size 0.508)
		(drill 0.254)
		(layers "F.Cu" "B.Cu")
		(net "FLA0_WP_N")
	)
	(segment
		(start 16.15186 -157.547056)
		(end 26.186892 -157.547056)
		(width 0.127)
		(layer "In2.Cu")
		(net "FLA0_WP_N")
	)
	(segment
		(start 10.8077 -152.202896)
		(end 16.15186 -157.547056)
		(width 0.127)
		(layer "In2.Cu")
		(net "FLA0_WP_N")
	)
	(segment
		(start 6.770878 -131.238752)
		(end 6.770878 -148.166074)
		(width 0.127)
		(layer "In5.Cu")
		(net "FLA0_WP_N")
	)
	(segment
		(start 22.132036 -126.076964)
		(end 11.932666 -126.076964)
		(width 0.127)
		(layer "In5.Cu")
		(net "FLA0_WP_N")
	)
	(segment
		(start 25.5524 -124.6505)
		(end 23.5585 -124.6505)
		(width 0.127)
		(layer "In5.Cu")
		(net "FLA0_WP_N")
	)
	(segment
		(start 6.770878 -148.166074)
		(end 10.8077 -152.202896)
		(width 0.127)
		(layer "In5.Cu")
		(net "FLA0_WP_N")
	)
	(segment
		(start 23.5585 -124.6505)
		(end 22.132036 -126.076964)
		(width 0.127)
		(layer "In5.Cu")
		(net "FLA0_WP_N")
	)
	(segment
		(start 11.932666 -126.076964)
		(end 6.770878 -131.238752)
		(width 0.127)
		(layer "In5.Cu")
		(net "FLA0_WP_N")
	)
	(segment
		(start 45.469302 -119.34952)
		(end 45.469302 -120.397778)
		(width 0.127)
		(layer "F.Cu")
		(net "FLA0_SPI_RST")
	)
	(segment
		(start 43.052238 -119.4562)
		(end 43.158918 -119.34952)
		(width 0.127)
		(layer "F.Cu")
		(net "FLA0_SPI_RST")
	)
	(segment
		(start 43.158918 -119.34952)
		(end 45.469302 -119.34952)
		(width 0.127)
		(layer "F.Cu")
		(net "FLA0_SPI_RST")
	)
	(segment
		(start 45.469302 -120.397778)
		(end 45.463206 -120.403874)
		(width 0.127)
		(layer "F.Cu")
		(net "FLA0_SPI_RST")
	)
	(segment
		(start 41.184576 -119.4562)
		(end 43.052238 -119.4562)
		(width 0.127)
		(layer "F.Cu")
		(net "FLA0_SPI_RST")
	)
	(segment
		(start 41.184576 -116.9162)
		(end 45.337222 -116.9162)
		(width 0.127)
		(layer "F.Cu")
		(net "FLA0_SPI_HOLD_N")
	)
	(segment
		(start 45.337222 -116.9162)
		(end 45.469302 -116.78412)
		(width 0.127)
		(layer "F.Cu")
		(net "FLA0_SPI_HOLD_N")
	)
	(segment
		(start 26.416 -122.4915)
		(end 26.416 -123.7615)
		(width 0.127)
		(layer "F.Cu")
		(net "WP_ENABLE")
	)
	(segment
		(start 40.099996 -136.518396)
		(end 40.099996 -136.59993)
		(width 0.127)
		(layer "F.Cu")
		(net "TPM_PRSNT_N_R")
	)
	(segment
		(start 39.6748 -136.0932)
		(end 40.099996 -136.518396)
		(width 0.127)
		(layer "F.Cu")
		(net "TPM_PRSNT_N_R")
	)
	(via
		(at 39.6748 -136.0932)
		(size 0.508)
		(drill 0.254)
		(layers "F.Cu" "B.Cu")
		(net "TPM_PRSNT_N_R")
	)
	(via
		(at 39.2176 -133.1976)
		(size 0.6096)
		(drill 0.3048)
		(layers "F.Cu" "B.Cu")
		(net "TPM_PRSNT_N_R")
	)
	(segment
		(start 38.7604 -129.116582)
		(end 38.7604 -132.461)
		(width 0.127)
		(layer "B.Cu")
		(net "TPM_PRSNT_N_R")
	)
	(segment
		(start 38.986206 -128.890776)
		(end 38.7604 -129.116582)
		(width 0.127)
		(layer "B.Cu")
		(net "TPM_PRSNT_N_R")
	)
	(segment
		(start 38.7604 -132.461)
		(end 39.2176 -132.9182)
		(width 0.127)
		(layer "B.Cu")
		(net "TPM_PRSNT_N_R")
	)
	(segment
		(start 39.8018 -134.9756)
		(end 39.8018 -134.239)
		(width 0.127)
		(layer "B.Cu")
		(net "TPM_PRSNT_N_R")
	)
	(segment
		(start 38.986206 -127.149606)
		(end 38.986206 -128.890776)
		(width 0.127)
		(layer "B.Cu")
		(net "TPM_PRSNT_N_R")
	)
	(segment
		(start 39.2176 -132.9182)
		(end 39.2176 -133.1976)
		(width 0.127)
		(layer "B.Cu")
		(net "TPM_PRSNT_N_R")
	)
	(segment
		(start 39.6494 -136.0678)
		(end 39.6494 -135.128)
		(width 0.127)
		(layer "B.Cu")
		(net "TPM_PRSNT_N_R")
	)
	(segment
		(start 39.6748 -136.0932)
		(end 39.6494 -136.0678)
		(width 0.127)
		(layer "B.Cu")
		(net "TPM_PRSNT_N_R")
	)
	(segment
		(start 39.6494 -135.128)
		(end 39.8018 -134.9756)
		(width 0.127)
		(layer "B.Cu")
		(net "TPM_PRSNT_N_R")
	)
	(segment
		(start 38.757606 -124.742194)
		(end 38.481 -125.0188)
		(width 0.127)
		(layer "B.Cu")
		(net "TPM_PRSNT_N_R")
	)
	(segment
		(start 39.8018 -134.239)
		(end 39.2176 -133.6548)
		(width 0.127)
		(layer "B.Cu")
		(net "TPM_PRSNT_N_R")
	)
	(segment
		(start 39.2176 -133.6548)
		(end 39.2176 -133.1976)
		(width 0.127)
		(layer "B.Cu")
		(net "TPM_PRSNT_N_R")
	)
	(segment
		(start 38.481 -125.0188)
		(end 38.481 -126.6444)
		(width 0.127)
		(layer "B.Cu")
		(net "TPM_PRSNT_N_R")
	)
	(segment
		(start 38.757606 -124.340874)
		(end 38.757606 -124.742194)
		(width 0.127)
		(layer "B.Cu")
		(net "TPM_PRSNT_N_R")
	)
	(segment
		(start 38.481 -126.6444)
		(end 38.986206 -127.149606)
		(width 0.127)
		(layer "B.Cu")
		(net "TPM_PRSNT_N_R")
	)
	(segment
		(start 56.830722 -133.63956)
		(end 56.830722 -134.192264)
		(width 0.127)
		(layer "F.Cu")
		(net "RSTBTN_OUT_N_R")
	)
	(segment
		(start 56.4261 -135.612378)
		(end 55.668164 -136.370314)
		(width 0.127)
		(layer "F.Cu")
		(net "RSTBTN_OUT_N_R")
	)
	(segment
		(start 58.359548 -132.798566)
		(end 58.176414 -132.9817)
		(width 0.127)
		(layer "F.Cu")
		(net "RSTBTN_OUT_N_R")
	)
	(segment
		(start 56.4261 -134.596886)
		(end 56.4261 -135.612378)
		(width 0.127)
		(layer "F.Cu")
		(net "RSTBTN_OUT_N_R")
	)
	(segment
		(start 58.176414 -132.9817)
		(end 57.488582 -132.9817)
		(width 0.127)
		(layer "F.Cu")
		(net "RSTBTN_OUT_N_R")
	)
	(segment
		(start 58.252868 -131.67487)
		(end 58.359548 -131.78155)
		(width 0.127)
		(layer "F.Cu")
		(net "RSTBTN_OUT_N_R")
	)
	(segment
		(start 56.830722 -134.192264)
		(end 56.4261 -134.596886)
		(width 0.127)
		(layer "F.Cu")
		(net "RSTBTN_OUT_N_R")
	)
	(segment
		(start 55.452518 -136.96823)
		(end 54.131718 -136.96823)
		(width 0.127)
		(layer "F.Cu")
		(net "RSTBTN_OUT_N_R")
	)
	(segment
		(start 54.131718 -136.96823)
		(end 53.699918 -137.40003)
		(width 0.127)
		(layer "F.Cu")
		(net "RSTBTN_OUT_N_R")
	)
	(segment
		(start 55.668164 -136.370314)
		(end 55.668164 -136.752584)
		(width 0.127)
		(layer "F.Cu")
		(net "RSTBTN_OUT_N_R")
	)
	(segment
		(start 55.668164 -136.752584)
		(end 55.452518 -136.96823)
		(width 0.127)
		(layer "F.Cu")
		(net "RSTBTN_OUT_N_R")
	)
	(segment
		(start 57.488582 -132.9817)
		(end 56.830722 -133.63956)
		(width 0.127)
		(layer "F.Cu")
		(net "RSTBTN_OUT_N_R")
	)
	(segment
		(start 58.359548 -131.78155)
		(end 58.359548 -132.798566)
		(width 0.127)
		(layer "F.Cu")
		(net "RSTBTN_OUT_N_R")
	)
	(via
		(at 58.359548 -132.798566)
		(size 0.6604)
		(drill 0.3302)
		(layers "F.Cu" "B.Cu")
		(net "RSTBTN_OUT_N_R")
	)
	(segment
		(start 165.517576 -135.44931)
		(end 165.184582 -135.116316)
		(width 0.127)
		(layer "F.Cu")
		(net "M2_2_PRESENT_N_R")
	)
	(segment
		(start 164.289232 -133.555994)
		(end 163.717986 -134.12724)
		(width 0.127)
		(layer "F.Cu")
		(net "M2_2_PRESENT_N_R")
	)
	(segment
		(start 170.150028 -134.875016)
		(end 170.150028 -135.565896)
		(width 0.127)
		(layer "F.Cu")
		(net "M2_2_PRESENT_N_R")
	)
	(segment
		(start 165.184582 -133.555994)
		(end 164.289232 -133.555994)
		(width 0.127)
		(layer "F.Cu")
		(net "M2_2_PRESENT_N_R")
	)
	(segment
		(start 165.184582 -135.116316)
		(end 165.184582 -134.66953)
		(width 0.127)
		(layer "F.Cu")
		(net "M2_2_PRESENT_N_R")
	)
	(segment
		(start 167.000174 -135.44931)
		(end 165.517576 -135.44931)
		(width 0.127)
		(layer "F.Cu")
		(net "M2_2_PRESENT_N_R")
	)
	(segment
		(start 165.184582 -134.66953)
		(end 164.260276 -134.66953)
		(width 0.127)
		(layer "F.Cu")
		(net "M2_2_PRESENT_N_R")
	)
	(segment
		(start 167.252396 -135.701532)
		(end 167.000174 -135.44931)
		(width 0.127)
		(layer "F.Cu")
		(net "M2_2_PRESENT_N_R")
	)
	(segment
		(start 170.150028 -135.565896)
		(end 170.014392 -135.701532)
		(width 0.127)
		(layer "F.Cu")
		(net "M2_2_PRESENT_N_R")
	)
	(segment
		(start 164.260276 -134.66953)
		(end 163.717986 -134.12724)
		(width 0.127)
		(layer "F.Cu")
		(net "M2_2_PRESENT_N_R")
	)
	(segment
		(start 170.014392 -135.701532)
		(end 167.252396 -135.701532)
		(width 0.127)
		(layer "F.Cu")
		(net "M2_2_PRESENT_N_R")
	)
	(via
		(at 163.717986 -134.12724)
		(size 0.6604)
		(drill 0.3302)
		(layers "F.Cu" "B.Cu")
		(net "M2_2_PRESENT_N_R")
	)
	(segment
		(start 195.149978 -135.797798)
		(end 194.54749 -136.400286)
		(width 0.127)
		(layer "F.Cu")
		(net "M2_1_PRESENT_N_R")
	)
	(segment
		(start 195.149978 -134.875016)
		(end 195.149978 -135.797798)
		(width 0.127)
		(layer "F.Cu")
		(net "M2_1_PRESENT_N_R")
	)
	(via
		(at 194.120516 -138.37666)
		(size 0.6096)
		(drill 0.3048)
		(layers "F.Cu" "B.Cu")
		(net "M2_1_PRESENT_N_R")
	)
	(via
		(at 194.54749 -136.400286)
		(size 0.508)
		(drill 0.254)
		(layers "F.Cu" "B.Cu")
		(net "M2_1_PRESENT_N_R")
	)
	(segment
		(start 194.752976 -138.059922)
		(end 194.436238 -138.37666)
		(width 0.127)
		(layer "B.Cu")
		(net "M2_1_PRESENT_N_R")
	)
	(segment
		(start 194.752976 -137.218674)
		(end 194.752976 -138.059922)
		(width 0.127)
		(layer "B.Cu")
		(net "M2_1_PRESENT_N_R")
	)
	(segment
		(start 194.752976 -137.218674)
		(end 194.752976 -136.605772)
		(width 0.127)
		(layer "B.Cu")
		(net "M2_1_PRESENT_N_R")
	)
	(segment
		(start 194.436238 -138.37666)
		(end 194.120516 -138.37666)
		(width 0.127)
		(layer "B.Cu")
		(net "M2_1_PRESENT_N_R")
	)
	(segment
		(start 193.73977 -137.995914)
		(end 194.120516 -138.37666)
		(width 0.127)
		(layer "B.Cu")
		(net "M2_1_PRESENT_N_R")
	)
	(segment
		(start 194.752976 -136.605772)
		(end 194.54749 -136.400286)
		(width 0.127)
		(layer "B.Cu")
		(net "M2_1_PRESENT_N_R")
	)
	(segment
		(start 193.73977 -136.854438)
		(end 193.73977 -137.995914)
		(width 0.127)
		(layer "B.Cu")
		(net "M2_1_PRESENT_N_R")
	)
	(segment
		(start 82.360516 -63.05804)
		(end 82.068416 -63.35014)
		(width 0.127)
		(layer "F.Cu")
		(net "I2C_MEZZ_OOB_SDA")
	)
	(segment
		(start 84.664042 -62.665356)
		(end 84.271358 -63.05804)
		(width 0.127)
		(layer "F.Cu")
		(net "I2C_MEZZ_OOB_SDA")
	)
	(segment
		(start 85.954362 -109.885988)
		(end 84.38515 -111.4552)
		(width 0.127)
		(layer "F.Cu")
		(net "I2C_MEZZ_OOB_SDA")
	)
	(segment
		(start 84.38515 -111.4552)
		(end 76.454 -111.4552)
		(width 0.127)
		(layer "F.Cu")
		(net "I2C_MEZZ_OOB_SDA")
	)
	(segment
		(start 62.0522 -118.36019)
		(end 62.0522 -120.4341)
		(width 0.127)
		(layer "F.Cu")
		(net "I2C_MEZZ_OOB_SDA")
	)
	(segment
		(start 87.510112 -64.942212)
		(end 85.233256 -62.665356)
		(width 0.127)
		(layer "F.Cu")
		(net "I2C_MEZZ_OOB_SDA")
	)
	(segment
		(start 91.0336 -92.673932)
		(end 93.682566 -95.322898)
		(width 0.127)
		(layer "F.Cu")
		(net "I2C_MEZZ_OOB_SDA")
	)
	(segment
		(start 65.65519 -114.7572)
		(end 62.0522 -118.36019)
		(width 0.127)
		(layer "F.Cu")
		(net "I2C_MEZZ_OOB_SDA")
	)
	(segment
		(start 85.233256 -62.665356)
		(end 84.664042 -62.665356)
		(width 0.127)
		(layer "F.Cu")
		(net "I2C_MEZZ_OOB_SDA")
	)
	(segment
		(start 82.068416 -63.35014)
		(end 79.925164 -63.35014)
		(width 0.127)
		(layer "F.Cu")
		(net "I2C_MEZZ_OOB_SDA")
	)
	(segment
		(start 93.682566 -95.322898)
		(end 93.682566 -109.03331)
		(width 0.127)
		(layer "F.Cu")
		(net "I2C_MEZZ_OOB_SDA")
	)
	(segment
		(start 84.271358 -63.05804)
		(end 82.360516 -63.05804)
		(width 0.127)
		(layer "F.Cu")
		(net "I2C_MEZZ_OOB_SDA")
	)
	(segment
		(start 90.892884 -66.109342)
		(end 91.0336 -66.250058)
		(width 0.127)
		(layer "F.Cu")
		(net "I2C_MEZZ_OOB_SDA")
	)
	(segment
		(start 91.0336 -66.250058)
		(end 91.0336 -92.673932)
		(width 0.127)
		(layer "F.Cu")
		(net "I2C_MEZZ_OOB_SDA")
	)
	(segment
		(start 76.454 -111.4552)
		(end 73.152 -114.7572)
		(width 0.127)
		(layer "F.Cu")
		(net "I2C_MEZZ_OOB_SDA")
	)
	(segment
		(start 90.892884 -66.109342)
		(end 89.725754 -64.942212)
		(width 0.127)
		(layer "F.Cu")
		(net "I2C_MEZZ_OOB_SDA")
	)
	(segment
		(start 89.725754 -64.942212)
		(end 87.510112 -64.942212)
		(width 0.127)
		(layer "F.Cu")
		(net "I2C_MEZZ_OOB_SDA")
	)
	(segment
		(start 92.829888 -109.885988)
		(end 85.954362 -109.885988)
		(width 0.127)
		(layer "F.Cu")
		(net "I2C_MEZZ_OOB_SDA")
	)
	(segment
		(start 93.682566 -109.03331)
		(end 92.829888 -109.885988)
		(width 0.127)
		(layer "F.Cu")
		(net "I2C_MEZZ_OOB_SDA")
	)
	(segment
		(start 73.152 -114.7572)
		(end 65.65519 -114.7572)
		(width 0.127)
		(layer "F.Cu")
		(net "I2C_MEZZ_OOB_SDA")
	)
	(via
		(at 90.892884 -66.109342)
		(size 0.6604)
		(drill 0.3302)
		(layers "F.Cu" "B.Cu")
		(net "I2C_MEZZ_OOB_SDA")
	)
	(via
		(at 62.0522 -120.4341)
		(size 0.508)
		(drill 0.254)
		(layers "F.Cu" "B.Cu")
		(net "I2C_MEZZ_OOB_SDA")
	)
	(via
		(at 67.2592 -160.6042)
		(size 0.508)
		(drill 0.254)
		(layers "F.Cu" "B.Cu")
		(net "I2C_MEZZ_OOB_SDA")
	)
	(segment
		(start 65.749678 -161.889948)
		(end 66.45529 -161.889948)
		(width 0.127)
		(layer "B.Cu")
		(net "I2C_MEZZ_OOB_SDA")
	)
	(segment
		(start 67.2592 -161.086038)
		(end 67.2592 -160.6042)
		(width 0.127)
		(layer "B.Cu")
		(net "I2C_MEZZ_OOB_SDA")
	)
	(segment
		(start 47.69993 -163.240974)
		(end 47.69993 -163.484814)
		(width 0.127)
		(layer "B.Cu")
		(net "I2C_MEZZ_OOB_SDA")
	)
	(segment
		(start 66.45529 -161.889948)
		(end 67.2592 -161.086038)
		(width 0.127)
		(layer "B.Cu")
		(net "I2C_MEZZ_OOB_SDA")
	)
	(segment
		(start 47.410116 -161.59226)
		(end 47.410116 -162.065716)
		(width 0.127)
		(layer "B.Cu")
		(net "I2C_MEZZ_OOB_SDA")
	)
	(segment
		(start 61.211968 -165.0873)
		(end 61.580268 -164.719)
		(width 0.127)
		(layer "B.Cu")
		(net "I2C_MEZZ_OOB_SDA")
	)
	(segment
		(start 49.581816 -165.3667)
		(end 51.565048 -165.3667)
		(width 0.127)
		(layer "B.Cu")
		(net "I2C_MEZZ_OOB_SDA")
	)
	(segment
		(start 47.69993 -162.715448)
		(end 47.69993 -163.240974)
		(width 0.127)
		(layer "B.Cu")
		(net "I2C_MEZZ_OOB_SDA")
	)
	(segment
		(start 51.565048 -165.3667)
		(end 51.692048 -165.2397)
		(width 0.127)
		(layer "B.Cu")
		(net "I2C_MEZZ_OOB_SDA")
	)
	(segment
		(start 61.580268 -164.719)
		(end 62.920626 -164.719)
		(width 0.127)
		(layer "B.Cu")
		(net "I2C_MEZZ_OOB_SDA")
	)
	(segment
		(start 62.920626 -164.719)
		(end 65.749678 -161.889948)
		(width 0.127)
		(layer "B.Cu")
		(net "I2C_MEZZ_OOB_SDA")
	)
	(segment
		(start 47.6631 -162.678618)
		(end 47.69993 -162.715448)
		(width 0.127)
		(layer "B.Cu")
		(net "I2C_MEZZ_OOB_SDA")
	)
	(segment
		(start 52.195984 -165.2397)
		(end 52.348384 -165.0873)
		(width 0.127)
		(layer "B.Cu")
		(net "I2C_MEZZ_OOB_SDA")
	)
	(segment
		(start 47.69993 -163.484814)
		(end 49.581816 -165.3667)
		(width 0.127)
		(layer "B.Cu")
		(net "I2C_MEZZ_OOB_SDA")
	)
	(segment
		(start 52.348384 -165.0873)
		(end 61.211968 -165.0873)
		(width 0.127)
		(layer "B.Cu")
		(net "I2C_MEZZ_OOB_SDA")
	)
	(segment
		(start 51.692048 -165.2397)
		(end 52.195984 -165.2397)
		(width 0.127)
		(layer "B.Cu")
		(net "I2C_MEZZ_OOB_SDA")
	)
	(segment
		(start 47.6631 -162.3187)
		(end 47.6631 -162.678618)
		(width 0.127)
		(layer "B.Cu")
		(net "I2C_MEZZ_OOB_SDA")
	)
	(segment
		(start 47.410116 -162.065716)
		(end 47.6631 -162.3187)
		(width 0.127)
		(layer "B.Cu")
		(net "I2C_MEZZ_OOB_SDA")
	)
	(segment
		(start 59.767216 -134.264908)
		(end 63.1444 -130.887724)
		(width 0.127)
		(layer "In2.Cu")
		(net "I2C_MEZZ_OOB_SDA")
	)
	(segment
		(start 61.3156 -149.051518)
		(end 61.3156 -139.986766)
		(width 0.127)
		(layer "In2.Cu")
		(net "I2C_MEZZ_OOB_SDA")
	)
	(segment
		(start 63.1444 -128.6256)
		(end 62.5856 -128.0668)
		(width 0.127)
		(layer "In2.Cu")
		(net "I2C_MEZZ_OOB_SDA")
	)
	(segment
		(start 67.2592 -160.419034)
		(end 65.702434 -158.862268)
		(width 0.127)
		(layer "In2.Cu")
		(net "I2C_MEZZ_OOB_SDA")
	)
	(segment
		(start 67.2592 -160.6042)
		(end 67.2592 -160.419034)
		(width 0.127)
		(layer "In2.Cu")
		(net "I2C_MEZZ_OOB_SDA")
	)
	(segment
		(start 60.070492 -137.080244)
		(end 59.767216 -136.776968)
		(width 0.127)
		(layer "In2.Cu")
		(net "I2C_MEZZ_OOB_SDA")
	)
	(segment
		(start 62.530482 -151.439118)
		(end 62.530482 -150.2664)
		(width 0.127)
		(layer "In2.Cu")
		(net "I2C_MEZZ_OOB_SDA")
	)
	(segment
		(start 62.5856 -128.0668)
		(end 62.5856 -120.9675)
		(width 0.127)
		(layer "In2.Cu")
		(net "I2C_MEZZ_OOB_SDA")
	)
	(segment
		(start 60.070492 -138.741658)
		(end 60.070492 -137.080244)
		(width 0.127)
		(layer "In2.Cu")
		(net "I2C_MEZZ_OOB_SDA")
	)
	(segment
		(start 62.1157 -151.8539)
		(end 62.530482 -151.439118)
		(width 0.127)
		(layer "In2.Cu")
		(net "I2C_MEZZ_OOB_SDA")
	)
	(segment
		(start 61.3156 -139.986766)
		(end 60.070492 -138.741658)
		(width 0.127)
		(layer "In2.Cu")
		(net "I2C_MEZZ_OOB_SDA")
	)
	(segment
		(start 62.1157 -155.265882)
		(end 62.1157 -151.8539)
		(width 0.127)
		(layer "In2.Cu")
		(net "I2C_MEZZ_OOB_SDA")
	)
	(segment
		(start 65.702434 -158.862268)
		(end 65.702434 -158.852616)
		(width 0.127)
		(layer "In2.Cu")
		(net "I2C_MEZZ_OOB_SDA")
	)
	(segment
		(start 62.530482 -150.2664)
		(end 61.3156 -149.051518)
		(width 0.127)
		(layer "In2.Cu")
		(net "I2C_MEZZ_OOB_SDA")
	)
	(segment
		(start 62.5856 -120.9675)
		(end 62.0522 -120.4341)
		(width 0.127)
		(layer "In2.Cu")
		(net "I2C_MEZZ_OOB_SDA")
	)
	(segment
		(start 59.767216 -136.776968)
		(end 59.767216 -134.264908)
		(width 0.127)
		(layer "In2.Cu")
		(net "I2C_MEZZ_OOB_SDA")
	)
	(segment
		(start 65.702434 -158.852616)
		(end 62.1157 -155.265882)
		(width 0.127)
		(layer "In2.Cu")
		(net "I2C_MEZZ_OOB_SDA")
	)
	(segment
		(start 63.1444 -130.887724)
		(end 63.1444 -128.6256)
		(width 0.127)
		(layer "In2.Cu")
		(net "I2C_MEZZ_OOB_SDA")
	)
	(segment
		(start 91.632786 -66.07683)
		(end 91.632786 -92.554552)
		(width 0.127)
		(layer "F.Cu")
		(net "I2C_MEZZ_OOB_SCL")
	)
	(segment
		(start 93.040454 -110.393988)
		(end 86.164928 -110.393988)
		(width 0.127)
		(layer "F.Cu")
		(net "I2C_MEZZ_OOB_SCL")
	)
	(segment
		(start 62.611 -118.519956)
		(end 62.611 -121.031)
		(width 0.127)
		(layer "F.Cu")
		(net "I2C_MEZZ_OOB_SCL")
	)
	(segment
		(start 87.720678 -64.434212)
		(end 89.990168 -64.434212)
		(width 0.127)
		(layer "F.Cu")
		(net "I2C_MEZZ_OOB_SCL")
	)
	(segment
		(start 91.632786 -92.554552)
		(end 94.190566 -95.112332)
		(width 0.127)
		(layer "F.Cu")
		(net "I2C_MEZZ_OOB_SCL")
	)
	(segment
		(start 62.611 -121.031)
		(end 62.0776 -121.5644)
		(width 0.127)
		(layer "F.Cu")
		(net "I2C_MEZZ_OOB_SCL")
	)
	(segment
		(start 84.452968 -62.157356)
		(end 85.443822 -62.157356)
		(width 0.127)
		(layer "F.Cu")
		(net "I2C_MEZZ_OOB_SCL")
	)
	(segment
		(start 89.990168 -64.434212)
		(end 91.632786 -66.07683)
		(width 0.127)
		(layer "F.Cu")
		(net "I2C_MEZZ_OOB_SCL")
	)
	(segment
		(start 94.190566 -95.112332)
		(end 94.190566 -109.243876)
		(width 0.127)
		(layer "F.Cu")
		(net "I2C_MEZZ_OOB_SCL")
	)
	(segment
		(start 79.925164 -62.55004)
		(end 84.060284 -62.55004)
		(width 0.127)
		(layer "F.Cu")
		(net "I2C_MEZZ_OOB_SCL")
	)
	(segment
		(start 85.443822 -62.157356)
		(end 87.720678 -64.434212)
		(width 0.127)
		(layer "F.Cu")
		(net "I2C_MEZZ_OOB_SCL")
	)
	(segment
		(start 76.664566 -111.9632)
		(end 73.362566 -115.2652)
		(width 0.127)
		(layer "F.Cu")
		(net "I2C_MEZZ_OOB_SCL")
	)
	(segment
		(start 86.164928 -110.393988)
		(end 84.595716 -111.9632)
		(width 0.127)
		(layer "F.Cu")
		(net "I2C_MEZZ_OOB_SCL")
	)
	(segment
		(start 94.190566 -109.243876)
		(end 93.040454 -110.393988)
		(width 0.127)
		(layer "F.Cu")
		(net "I2C_MEZZ_OOB_SCL")
	)
	(segment
		(start 65.865756 -115.2652)
		(end 62.611 -118.519956)
		(width 0.127)
		(layer "F.Cu")
		(net "I2C_MEZZ_OOB_SCL")
	)
	(segment
		(start 73.362566 -115.2652)
		(end 65.865756 -115.2652)
		(width 0.127)
		(layer "F.Cu")
		(net "I2C_MEZZ_OOB_SCL")
	)
	(segment
		(start 84.060284 -62.55004)
		(end 84.452968 -62.157356)
		(width 0.127)
		(layer "F.Cu")
		(net "I2C_MEZZ_OOB_SCL")
	)
	(segment
		(start 84.595716 -111.9632)
		(end 76.664566 -111.9632)
		(width 0.127)
		(layer "F.Cu")
		(net "I2C_MEZZ_OOB_SCL")
	)
	(via
		(at 62.0776 -121.5644)
		(size 0.508)
		(drill 0.254)
		(layers "F.Cu" "B.Cu")
		(net "I2C_MEZZ_OOB_SCL")
	)
	(via
		(at 66.49974 -161.03092)
		(size 0.508)
		(drill 0.254)
		(layers "F.Cu" "B.Cu")
		(net "I2C_MEZZ_OOB_SCL")
	)
	(via
		(at 63.7286 -163.0934)
		(size 0.6096)
		(drill 0.3048)
		(layers "F.Cu" "B.Cu")
		(net "I2C_MEZZ_OOB_SCL")
	)
	(segment
		(start 49.6951 -163.2712)
		(end 49.6951 -163.3347)
		(width 0.127)
		(layer "B.Cu")
		(net "I2C_MEZZ_OOB_SCL")
	)
	(segment
		(start 61.369702 -164.211)
		(end 62.611 -164.211)
		(width 0.127)
		(layer "B.Cu")
		(net "I2C_MEZZ_OOB_SCL")
	)
	(segment
		(start 49.6951 -163.3347)
		(end 49.2125 -163.8173)
		(width 0.127)
		(layer "B.Cu")
		(net "I2C_MEZZ_OOB_SCL")
	)
	(segment
		(start 49.6951 -162.01136)
		(end 49.6951 -163.2712)
		(width 0.127)
		(layer "B.Cu")
		(net "I2C_MEZZ_OOB_SCL")
	)
	(segment
		(start 66.49974 -161.03092)
		(end 66.148712 -161.381948)
		(width 0.127)
		(layer "B.Cu")
		(net "I2C_MEZZ_OOB_SCL")
	)
	(segment
		(start 51.481482 -164.7317)
		(end 51.985418 -164.7317)
		(width 0.127)
		(layer "B.Cu")
		(net "I2C_MEZZ_OOB_SCL")
	)
	(segment
		(start 51.354482 -164.8587)
		(end 51.481482 -164.7317)
		(width 0.127)
		(layer "B.Cu")
		(net "I2C_MEZZ_OOB_SCL")
	)
	(segment
		(start 66.148712 -161.381948)
		(end 65.440052 -161.381948)
		(width 0.127)
		(layer "B.Cu")
		(net "I2C_MEZZ_OOB_SCL")
	)
	(segment
		(start 65.440052 -161.381948)
		(end 63.7286 -163.0934)
		(width 0.127)
		(layer "B.Cu")
		(net "I2C_MEZZ_OOB_SCL")
	)
	(segment
		(start 51.985418 -164.7317)
		(end 52.137818 -164.5793)
		(width 0.127)
		(layer "B.Cu")
		(net "I2C_MEZZ_OOB_SCL")
	)
	(segment
		(start 49.2125 -164.278818)
		(end 49.792382 -164.8587)
		(width 0.127)
		(layer "B.Cu")
		(net "I2C_MEZZ_OOB_SCL")
	)
	(segment
		(start 49.2125 -163.8173)
		(end 49.2125 -164.278818)
		(width 0.127)
		(layer "B.Cu")
		(net "I2C_MEZZ_OOB_SCL")
	)
	(segment
		(start 52.137818 -164.5793)
		(end 61.001402 -164.5793)
		(width 0.127)
		(layer "B.Cu")
		(net "I2C_MEZZ_OOB_SCL")
	)
	(segment
		(start 49.792382 -164.8587)
		(end 51.354482 -164.8587)
		(width 0.127)
		(layer "B.Cu")
		(net "I2C_MEZZ_OOB_SCL")
	)
	(segment
		(start 49.30648 -161.59734)
		(end 49.6951 -162.01136)
		(width 0.127)
		(layer "B.Cu")
		(net "I2C_MEZZ_OOB_SCL")
	)
	(segment
		(start 62.611 -164.211)
		(end 63.7286 -163.0934)
		(width 0.127)
		(layer "B.Cu")
		(net "I2C_MEZZ_OOB_SCL")
	)
	(segment
		(start 61.001402 -164.5793)
		(end 61.369702 -164.211)
		(width 0.127)
		(layer "B.Cu")
		(net "I2C_MEZZ_OOB_SCL")
	)
	(segment
		(start 62.022482 -151.228552)
		(end 61.6077 -151.643334)
		(width 0.127)
		(layer "In2.Cu")
		(net "I2C_MEZZ_OOB_SCL")
	)
	(segment
		(start 62.6364 -130.677158)
		(end 59.152536 -134.161022)
		(width 0.127)
		(layer "In2.Cu")
		(net "I2C_MEZZ_OOB_SCL")
	)
	(segment
		(start 65.194434 -159.072834)
		(end 66.49974 -160.37814)
		(width 0.127)
		(layer "In2.Cu")
		(net "I2C_MEZZ_OOB_SCL")
	)
	(segment
		(start 62.022482 -150.476966)
		(end 62.022482 -151.228552)
		(width 0.127)
		(layer "In2.Cu")
		(net "I2C_MEZZ_OOB_SCL")
	)
	(segment
		(start 62.0776 -128.277366)
		(end 62.6364 -128.836166)
		(width 0.127)
		(layer "In2.Cu")
		(net "I2C_MEZZ_OOB_SCL")
	)
	(segment
		(start 61.6077 -155.476448)
		(end 65.194434 -159.063182)
		(width 0.127)
		(layer "In2.Cu")
		(net "I2C_MEZZ_OOB_SCL")
	)
	(segment
		(start 61.6077 -151.643334)
		(end 61.6077 -155.476448)
		(width 0.127)
		(layer "In2.Cu")
		(net "I2C_MEZZ_OOB_SCL")
	)
	(segment
		(start 65.194434 -159.063182)
		(end 65.194434 -159.072834)
		(width 0.127)
		(layer "In2.Cu")
		(net "I2C_MEZZ_OOB_SCL")
	)
	(segment
		(start 60.8076 -140.197332)
		(end 60.8076 -149.262084)
		(width 0.127)
		(layer "In2.Cu")
		(net "I2C_MEZZ_OOB_SCL")
	)
	(segment
		(start 60.8076 -149.262084)
		(end 62.022482 -150.476966)
		(width 0.127)
		(layer "In2.Cu")
		(net "I2C_MEZZ_OOB_SCL")
	)
	(segment
		(start 62.6364 -128.836166)
		(end 62.6364 -130.677158)
		(width 0.127)
		(layer "In2.Cu")
		(net "I2C_MEZZ_OOB_SCL")
	)
	(segment
		(start 66.49974 -160.37814)
		(end 66.49974 -161.03092)
		(width 0.127)
		(layer "In2.Cu")
		(net "I2C_MEZZ_OOB_SCL")
	)
	(segment
		(start 62.0776 -121.5644)
		(end 62.0776 -128.277366)
		(width 0.127)
		(layer "In2.Cu")
		(net "I2C_MEZZ_OOB_SCL")
	)
	(segment
		(start 59.152536 -138.542268)
		(end 60.8076 -140.197332)
		(width 0.127)
		(layer "In2.Cu")
		(net "I2C_MEZZ_OOB_SCL")
	)
	(segment
		(start 59.152536 -134.161022)
		(end 59.152536 -138.542268)
		(width 0.127)
		(layer "In2.Cu")
		(net "I2C_MEZZ_OOB_SCL")
	)
	(segment
		(start 77.110336 -60.950094)
		(end 77.666088 -60.394342)
		(width 0.127)
		(layer "F.Cu")
		(net "I2C_MEZZ_FRU_SENSOR_SDA")
	)
	(segment
		(start 75.475084 -60.950094)
		(end 77.110336 -60.950094)
		(width 0.127)
		(layer "F.Cu")
		(net "I2C_MEZZ_FRU_SENSOR_SDA")
	)
	(segment
		(start 77.666088 -60.394342)
		(end 77.666088 -60.368942)
		(width 0.127)
		(layer "F.Cu")
		(net "I2C_MEZZ_FRU_SENSOR_SDA")
	)
	(via
		(at 66.064384 -145.972022)
		(size 0.6096)
		(drill 0.3048)
		(layers "F.Cu" "B.Cu")
		(net "I2C_MEZZ_FRU_SENSOR_SDA")
	)
	(via
		(at 67.1068 -145.8214)
		(size 0.508)
		(drill 0.254)
		(layers "F.Cu" "B.Cu")
		(net "I2C_MEZZ_FRU_SENSOR_SDA")
	)
	(via
		(at 77.666088 -60.368942)
		(size 0.508)
		(drill 0.254)
		(layers "F.Cu" "B.Cu")
		(net "I2C_MEZZ_FRU_SENSOR_SDA")
	)
	(via
		(at 71.0692 -144.572228)
		(size 0.508)
		(drill 0.254)
		(layers "F.Cu" "B.Cu")
		(net "I2C_MEZZ_FRU_SENSOR_SDA")
	)
	(via
		(at 82.528664 -110.58144)
		(size 0.508)
		(drill 0.254)
		(layers "F.Cu" "B.Cu")
		(net "I2C_MEZZ_FRU_SENSOR_SDA")
	)
	(segment
		(start 64.609726 -145.478754)
		(end 64.58458 -145.5039)
		(width 0.127)
		(layer "B.Cu")
		(net "I2C_MEZZ_FRU_SENSOR_SDA")
	)
	(segment
		(start 63.3603 -145.0594)
		(end 63.343028 -145.042128)
		(width 0.127)
		(layer "B.Cu")
		(net "I2C_MEZZ_FRU_SENSOR_SDA")
	)
	(segment
		(start 66.064384 -145.972022)
		(end 65.838832 -145.972022)
		(width 0.127)
		(layer "B.Cu")
		(net "I2C_MEZZ_FRU_SENSOR_SDA")
	)
	(segment
		(start 63.7159 -145.5039)
		(end 63.3603 -145.1483)
		(width 0.127)
		(layer "B.Cu")
		(net "I2C_MEZZ_FRU_SENSOR_SDA")
	)
	(segment
		(start 65.345564 -145.478754)
		(end 64.609726 -145.478754)
		(width 0.127)
		(layer "B.Cu")
		(net "I2C_MEZZ_FRU_SENSOR_SDA")
	)
	(segment
		(start 63.343028 -145.042128)
		(end 62.27572 -145.042128)
		(width 0.127)
		(layer "B.Cu")
		(net "I2C_MEZZ_FRU_SENSOR_SDA")
	)
	(segment
		(start 64.58458 -145.5039)
		(end 63.7159 -145.5039)
		(width 0.127)
		(layer "B.Cu")
		(net "I2C_MEZZ_FRU_SENSOR_SDA")
	)
	(segment
		(start 63.3603 -145.1483)
		(end 63.3603 -145.0594)
		(width 0.127)
		(layer "B.Cu")
		(net "I2C_MEZZ_FRU_SENSOR_SDA")
	)
	(segment
		(start 65.838832 -145.972022)
		(end 65.345564 -145.478754)
		(width 0.127)
		(layer "B.Cu")
		(net "I2C_MEZZ_FRU_SENSOR_SDA")
	)
	(segment
		(start 66.956178 -145.972022)
		(end 66.064384 -145.972022)
		(width 0.127)
		(layer "B.Cu")
		(net "I2C_MEZZ_FRU_SENSOR_SDA")
	)
	(segment
		(start 67.1068 -145.8214)
		(end 66.956178 -145.972022)
		(width 0.127)
		(layer "B.Cu")
		(net "I2C_MEZZ_FRU_SENSOR_SDA")
	)
	(segment
		(start 73.050654 -117.12067)
		(end 77.208126 -112.963198)
		(width 0.127)
		(layer "In2.Cu")
		(net "I2C_MEZZ_FRU_SENSOR_SDA")
	)
	(segment
		(start 82.528664 -110.841028)
		(end 82.528664 -110.58144)
		(width 0.127)
		(layer "In2.Cu")
		(net "I2C_MEZZ_FRU_SENSOR_SDA")
	)
	(segment
		(start 71.4883 -135.636)
		(end 71.4883 -123.855988)
		(width 0.127)
		(layer "In2.Cu")
		(net "I2C_MEZZ_FRU_SENSOR_SDA")
	)
	(segment
		(start 71.007224 -136.117076)
		(end 71.4883 -135.636)
		(width 0.127)
		(layer "In2.Cu")
		(net "I2C_MEZZ_FRU_SENSOR_SDA")
	)
	(segment
		(start 71.0692 -144.572228)
		(end 71.007224 -144.510252)
		(width 0.127)
		(layer "In2.Cu")
		(net "I2C_MEZZ_FRU_SENSOR_SDA")
	)
	(segment
		(start 80.406494 -112.963198)
		(end 82.528664 -110.841028)
		(width 0.127)
		(layer "In2.Cu")
		(net "I2C_MEZZ_FRU_SENSOR_SDA")
	)
	(segment
		(start 71.4883 -123.855988)
		(end 73.050654 -122.293634)
		(width 0.127)
		(layer "In2.Cu")
		(net "I2C_MEZZ_FRU_SENSOR_SDA")
	)
	(segment
		(start 71.007224 -144.510252)
		(end 71.007224 -136.117076)
		(width 0.127)
		(layer "In2.Cu")
		(net "I2C_MEZZ_FRU_SENSOR_SDA")
	)
	(segment
		(start 73.050654 -122.293634)
		(end 73.050654 -117.12067)
		(width 0.127)
		(layer "In2.Cu")
		(net "I2C_MEZZ_FRU_SENSOR_SDA")
	)
	(segment
		(start 77.208126 -112.963198)
		(end 80.406494 -112.963198)
		(width 0.127)
		(layer "In2.Cu")
		(net "I2C_MEZZ_FRU_SENSOR_SDA")
	)
	(segment
		(start 69.831966 -144.7546)
		(end 68.727066 -145.8595)
		(width 0.127)
		(layer "In5.Cu")
		(net "I2C_MEZZ_FRU_SENSOR_SDA")
	)
	(segment
		(start 71.0692 -144.572228)
		(end 70.886828 -144.7546)
		(width 0.127)
		(layer "In5.Cu")
		(net "I2C_MEZZ_FRU_SENSOR_SDA")
	)
	(segment
		(start 76.7207 -98.80219)
		(end 76.7207 -61.31433)
		(width 0.127)
		(layer "In5.Cu")
		(net "I2C_MEZZ_FRU_SENSOR_SDA")
	)
	(segment
		(start 67.1449 -145.8595)
		(end 67.1068 -145.8214)
		(width 0.127)
		(layer "In5.Cu")
		(net "I2C_MEZZ_FRU_SENSOR_SDA")
	)
	(segment
		(start 70.886828 -144.7546)
		(end 69.831966 -144.7546)
		(width 0.127)
		(layer "In5.Cu")
		(net "I2C_MEZZ_FRU_SENSOR_SDA")
	)
	(segment
		(start 78.93431 -101.0158)
		(end 76.7207 -98.80219)
		(width 0.127)
		(layer "In5.Cu")
		(net "I2C_MEZZ_FRU_SENSOR_SDA")
	)
	(segment
		(start 84.173314 -108.73232)
		(end 84.173314 -103.68407)
		(width 0.127)
		(layer "In5.Cu")
		(net "I2C_MEZZ_FRU_SENSOR_SDA")
	)
	(segment
		(start 68.727066 -145.8595)
		(end 67.1449 -145.8595)
		(width 0.127)
		(layer "In5.Cu")
		(net "I2C_MEZZ_FRU_SENSOR_SDA")
	)
	(segment
		(start 82.528664 -110.58144)
		(end 82.528664 -110.37697)
		(width 0.127)
		(layer "In5.Cu")
		(net "I2C_MEZZ_FRU_SENSOR_SDA")
	)
	(segment
		(start 84.173314 -103.68407)
		(end 81.505044 -101.0158)
		(width 0.127)
		(layer "In5.Cu")
		(net "I2C_MEZZ_FRU_SENSOR_SDA")
	)
	(segment
		(start 76.7207 -61.31433)
		(end 77.666088 -60.368942)
		(width 0.127)
		(layer "In5.Cu")
		(net "I2C_MEZZ_FRU_SENSOR_SDA")
	)
	(segment
		(start 82.528664 -110.37697)
		(end 84.173314 -108.73232)
		(width 0.127)
		(layer "In5.Cu")
		(net "I2C_MEZZ_FRU_SENSOR_SDA")
	)
	(segment
		(start 81.505044 -101.0158)
		(end 78.93431 -101.0158)
		(width 0.127)
		(layer "In5.Cu")
		(net "I2C_MEZZ_FRU_SENSOR_SDA")
	)
	(segment
		(start 75.475084 -60.149994)
		(end 77.04963 -60.149994)
		(width 0.127)
		(layer "F.Cu")
		(net "I2C_MEZZ_FRU_SENSOR_SCL")
	)
	(segment
		(start 77.04963 -60.149994)
		(end 77.694028 -59.505596)
		(width 0.127)
		(layer "F.Cu")
		(net "I2C_MEZZ_FRU_SENSOR_SCL")
	)
	(via
		(at 65.025778 -146.0627)
		(size 0.508)
		(drill 0.254)
		(layers "F.Cu" "B.Cu")
		(net "I2C_MEZZ_FRU_SENSOR_SCL")
	)
	(via
		(at 71.62165 -145.532602)
		(size 0.508)
		(drill 0.254)
		(layers "F.Cu" "B.Cu")
		(net "I2C_MEZZ_FRU_SENSOR_SCL")
	)
	(via
		(at 62.8396 -146.4056)
		(size 0.6096)
		(drill 0.3048)
		(layers "F.Cu" "B.Cu")
		(net "I2C_MEZZ_FRU_SENSOR_SCL")
	)
	(via
		(at 83.391502 -110.620302)
		(size 0.508)
		(drill 0.254)
		(layers "F.Cu" "B.Cu")
		(net "I2C_MEZZ_FRU_SENSOR_SCL")
	)
	(via
		(at 77.694028 -59.505596)
		(size 0.508)
		(drill 0.254)
		(layers "F.Cu" "B.Cu")
		(net "I2C_MEZZ_FRU_SENSOR_SCL")
	)
	(segment
		(start 64.643 -146.0627)
		(end 64.0842 -146.6215)
		(width 0.127)
		(layer "B.Cu")
		(net "I2C_MEZZ_FRU_SENSOR_SCL")
	)
	(segment
		(start 65.025778 -146.0627)
		(end 64.643 -146.0627)
		(width 0.127)
		(layer "B.Cu")
		(net "I2C_MEZZ_FRU_SENSOR_SCL")
	)
	(segment
		(start 61.6204 -146.0627)
		(end 62.4967 -146.0627)
		(width 0.127)
		(layer "B.Cu")
		(net "I2C_MEZZ_FRU_SENSOR_SCL")
	)
	(segment
		(start 63.0555 -146.6215)
		(end 64.0842 -146.6215)
		(width 0.127)
		(layer "B.Cu")
		(net "I2C_MEZZ_FRU_SENSOR_SCL")
	)
	(segment
		(start 62.8396 -146.4056)
		(end 63.0555 -146.6215)
		(width 0.127)
		(layer "B.Cu")
		(net "I2C_MEZZ_FRU_SENSOR_SCL")
	)
	(segment
		(start 62.4967 -146.0627)
		(end 62.8396 -146.4056)
		(width 0.127)
		(layer "B.Cu")
		(net "I2C_MEZZ_FRU_SENSOR_SCL")
	)
	(segment
		(start 73.558654 -122.5042)
		(end 71.9963 -124.066554)
		(width 0.127)
		(layer "In2.Cu")
		(net "I2C_MEZZ_FRU_SENSOR_SCL")
	)
	(segment
		(start 83.391502 -110.620302)
		(end 83.391502 -110.696756)
		(width 0.127)
		(layer "In2.Cu")
		(net "I2C_MEZZ_FRU_SENSOR_SCL")
	)
	(segment
		(start 80.61706 -113.471198)
		(end 77.418692 -113.471198)
		(width 0.127)
		(layer "In2.Cu")
		(net "I2C_MEZZ_FRU_SENSOR_SCL")
	)
	(segment
		(start 71.9963 -124.066554)
		(end 71.9963 -135.846566)
		(width 0.127)
		(layer "In2.Cu")
		(net "I2C_MEZZ_FRU_SENSOR_SCL")
	)
	(segment
		(start 71.9963 -135.846566)
		(end 71.515224 -136.327642)
		(width 0.127)
		(layer "In2.Cu")
		(net "I2C_MEZZ_FRU_SENSOR_SCL")
	)
	(segment
		(start 73.558654 -117.331236)
		(end 73.558654 -122.5042)
		(width 0.127)
		(layer "In2.Cu")
		(net "I2C_MEZZ_FRU_SENSOR_SCL")
	)
	(segment
		(start 71.62165 -142.400782)
		(end 71.62165 -145.532602)
		(width 0.127)
		(layer "In2.Cu")
		(net "I2C_MEZZ_FRU_SENSOR_SCL")
	)
	(segment
		(start 71.515224 -136.327642)
		(end 71.515224 -142.294356)
		(width 0.127)
		(layer "In2.Cu")
		(net "I2C_MEZZ_FRU_SENSOR_SCL")
	)
	(segment
		(start 83.391502 -110.696756)
		(end 80.61706 -113.471198)
		(width 0.127)
		(layer "In2.Cu")
		(net "I2C_MEZZ_FRU_SENSOR_SCL")
	)
	(segment
		(start 77.418692 -113.471198)
		(end 73.558654 -117.331236)
		(width 0.127)
		(layer "In2.Cu")
		(net "I2C_MEZZ_FRU_SENSOR_SCL")
	)
	(segment
		(start 71.515224 -142.294356)
		(end 71.62165 -142.400782)
		(width 0.127)
		(layer "In2.Cu")
		(net "I2C_MEZZ_FRU_SENSOR_SCL")
	)
	(segment
		(start 66.690748 -146.167348)
		(end 65.130426 -146.167348)
		(width 0.127)
		(layer "In5.Cu")
		(net "I2C_MEZZ_FRU_SENSOR_SCL")
	)
	(segment
		(start 68.937632 -146.3675)
		(end 66.8909 -146.3675)
		(width 0.127)
		(layer "In5.Cu")
		(net "I2C_MEZZ_FRU_SENSOR_SCL")
	)
	(segment
		(start 78.84922 -99.80422)
		(end 78.84922 -97.96018)
		(width 0.127)
		(layer "In5.Cu")
		(net "I2C_MEZZ_FRU_SENSOR_SCL")
	)
	(segment
		(start 81.67624 -100.457)
		(end 79.502 -100.457)
		(width 0.127)
		(layer "In5.Cu")
		(net "I2C_MEZZ_FRU_SENSOR_SCL")
	)
	(segment
		(start 69.945504 -145.359628)
		(end 68.937632 -146.3675)
		(width 0.127)
		(layer "In5.Cu")
		(net "I2C_MEZZ_FRU_SENSOR_SCL")
	)
	(segment
		(start 66.8909 -146.3675)
		(end 66.690748 -146.167348)
		(width 0.127)
		(layer "In5.Cu")
		(net "I2C_MEZZ_FRU_SENSOR_SCL")
	)
	(segment
		(start 84.681314 -103.462074)
		(end 81.67624 -100.457)
		(width 0.127)
		(layer "In5.Cu")
		(net "I2C_MEZZ_FRU_SENSOR_SCL")
	)
	(segment
		(start 71.62165 -145.532602)
		(end 70.909434 -145.532602)
		(width 0.127)
		(layer "In5.Cu")
		(net "I2C_MEZZ_FRU_SENSOR_SCL")
	)
	(segment
		(start 70.909434 -145.532602)
		(end 70.73646 -145.359628)
		(width 0.127)
		(layer "In5.Cu")
		(net "I2C_MEZZ_FRU_SENSOR_SCL")
	)
	(segment
		(start 78.4098 -97.52076)
		(end 78.4098 -92.220542)
		(width 0.127)
		(layer "In5.Cu")
		(net "I2C_MEZZ_FRU_SENSOR_SCL")
	)
	(segment
		(start 79.502 -100.457)
		(end 78.84922 -99.80422)
		(width 0.127)
		(layer "In5.Cu")
		(net "I2C_MEZZ_FRU_SENSOR_SCL")
	)
	(segment
		(start 83.391502 -110.232698)
		(end 84.681314 -108.942886)
		(width 0.127)
		(layer "In5.Cu")
		(net "I2C_MEZZ_FRU_SENSOR_SCL")
	)
	(segment
		(start 84.681314 -108.942886)
		(end 84.681314 -103.462074)
		(width 0.127)
		(layer "In5.Cu")
		(net "I2C_MEZZ_FRU_SENSOR_SCL")
	)
	(segment
		(start 78.566518 -92.063824)
		(end 78.566518 -60.378086)
		(width 0.127)
		(layer "In5.Cu")
		(net "I2C_MEZZ_FRU_SENSOR_SCL")
	)
	(segment
		(start 65.130426 -146.167348)
		(end 65.025778 -146.0627)
		(width 0.127)
		(layer "In5.Cu")
		(net "I2C_MEZZ_FRU_SENSOR_SCL")
	)
	(segment
		(start 83.391502 -110.620302)
		(end 83.391502 -110.232698)
		(width 0.127)
		(layer "In5.Cu")
		(net "I2C_MEZZ_FRU_SENSOR_SCL")
	)
	(segment
		(start 78.4098 -92.220542)
		(end 78.566518 -92.063824)
		(width 0.127)
		(layer "In5.Cu")
		(net "I2C_MEZZ_FRU_SENSOR_SCL")
	)
	(segment
		(start 78.566518 -60.378086)
		(end 77.694028 -59.505596)
		(width 0.127)
		(layer "In5.Cu")
		(net "I2C_MEZZ_FRU_SENSOR_SCL")
	)
	(segment
		(start 78.84922 -97.96018)
		(end 78.4098 -97.52076)
		(width 0.127)
		(layer "In5.Cu")
		(net "I2C_MEZZ_FRU_SENSOR_SCL")
	)
	(segment
		(start 70.73646 -145.359628)
		(end 69.945504 -145.359628)
		(width 0.127)
		(layer "In5.Cu")
		(net "I2C_MEZZ_FRU_SENSOR_SCL")
	)
	(segment
		(start 64.0715 -164.75075)
		(end 64.0715 -163.5379)
		(width 0.127)
		(layer "F.Cu")
		(net "FM_TPM_PRSNT_RST_N_R")
	)
	(segment
		(start 64.490854 -163.118546)
		(end 64.1858 -163.4236)
		(width 0.127)
		(layer "F.Cu")
		(net "FM_TPM_PRSNT_RST_N_R")
	)
	(segment
		(start 65.235328 -163.118546)
		(end 64.490854 -163.118546)
		(width 0.127)
		(layer "F.Cu")
		(net "FM_TPM_PRSNT_RST_N_R")
	)
	(segment
		(start 64.0715 -163.5379)
		(end 64.1858 -163.4236)
		(width 0.127)
		(layer "F.Cu")
		(net "FM_TPM_PRSNT_RST_N_R")
	)
	(via
		(at 64.1858 -163.4236)
		(size 0.6604)
		(drill 0.3302)
		(layers "F.Cu" "B.Cu")
		(net "FM_TPM_PRSNT_RST_N_R")
	)
	(segment
		(start 60.919868 -173.1264)
		(end 60.919868 -173.645068)
		(width 0.127)
		(layer "F.Cu")
		(net "FM_TPM_PRSNT_RST_N_C")
	)
	(segment
		(start 63.7032 -172.5549)
		(end 62.6618 -172.5549)
		(width 0.127)
		(layer "F.Cu")
		(net "FM_TPM_PRSNT_RST_N_C")
	)
	(segment
		(start 60.919868 -173.645068)
		(end 61.588396 -174.313596)
		(width 0.127)
		(layer "F.Cu")
		(net "FM_TPM_PRSNT_RST_N_C")
	)
	(segment
		(start 62.6618 -172.5549)
		(end 61.491368 -172.5549)
		(width 0.127)
		(layer "F.Cu")
		(net "FM_TPM_PRSNT_RST_N_C")
	)
	(segment
		(start 61.588396 -174.313596)
		(end 62.476634 -174.313596)
		(width 0.127)
		(layer "F.Cu")
		(net "FM_TPM_PRSNT_RST_N_C")
	)
	(segment
		(start 61.491368 -172.5549)
		(end 60.919868 -173.1264)
		(width 0.127)
		(layer "F.Cu")
		(net "FM_TPM_PRSNT_RST_N_C")
	)
	(via
		(at 60.919868 -173.1264)
		(size 0.6604)
		(drill 0.3302)
		(layers "F.Cu" "B.Cu")
		(net "FM_TPM_PRSNT_RST_N_C")
	)
	(segment
		(start 54.1909 -177.1777)
		(end 60.1599 -177.1777)
		(width 0.127)
		(layer "F.Cu")
		(net "FM_TPM_PRSNT_RST_N")
	)
	(segment
		(start 63.473838 -180.9369)
		(end 64.390016 -181.853078)
		(width 0.127)
		(layer "F.Cu")
		(net "FM_TPM_PRSNT_RST_N")
	)
	(segment
		(start 66.926714 -175.913796)
		(end 66.926714 -177.072544)
		(width 0.127)
		(layer "F.Cu")
		(net "FM_TPM_PRSNT_RST_N")
	)
	(segment
		(start 60.656978 -167.289734)
		(end 60.32246 -167.289734)
		(width 0.127)
		(layer "F.Cu")
		(net "FM_TPM_PRSNT_RST_N")
	)
	(segment
		(start 62.1665 -170.76928)
		(end 62.1665 -169.291)
		(width 0.127)
		(layer "F.Cu")
		(net "FM_TPM_PRSNT_RST_N")
	)
	(segment
		(start 60.8584 -177.8762)
		(end 60.8584 -180.213)
		(width 0.127)
		(layer "F.Cu")
		(net "FM_TPM_PRSNT_RST_N")
	)
	(segment
		(start 60.32246 -167.289734)
		(end 59.700668 -166.667942)
		(width 0.127)
		(layer "F.Cu")
		(net "FM_TPM_PRSNT_RST_N")
	)
	(segment
		(start 67.57797 -177.7238)
		(end 67.8434 -177.7238)
		(width 0.127)
		(layer "F.Cu")
		(net "FM_TPM_PRSNT_RST_N")
	)
	(segment
		(start 60.656978 -167.82669)
		(end 60.656978 -167.289734)
		(width 0.127)
		(layer "F.Cu")
		(net "FM_TPM_PRSNT_RST_N")
	)
	(segment
		(start 66.37147 -181.853078)
		(end 67.183 -181.853078)
		(width 0.127)
		(layer "F.Cu")
		(net "FM_TPM_PRSNT_RST_N")
	)
	(segment
		(start 60.8584 -180.213)
		(end 61.5823 -180.9369)
		(width 0.127)
		(layer "F.Cu")
		(net "FM_TPM_PRSNT_RST_N")
	)
	(segment
		(start 60.1599 -177.1777)
		(end 60.8584 -177.8762)
		(width 0.127)
		(layer "F.Cu")
		(net "FM_TPM_PRSNT_RST_N")
	)
	(segment
		(start 67.33413 -178.23307)
		(end 67.8434 -177.7238)
		(width 0.127)
		(layer "F.Cu")
		(net "FM_TPM_PRSNT_RST_N")
	)
	(segment
		(start 53.280056 -174.994824)
		(end 53.280056 -176.266856)
		(width 0.127)
		(layer "F.Cu")
		(net "FM_TPM_PRSNT_RST_N")
	)
	(segment
		(start 67.183 -181.853078)
		(end 67.33413 -181.701948)
		(width 0.127)
		(layer "F.Cu")
		(net "FM_TPM_PRSNT_RST_N")
	)
	(segment
		(start 60.690506 -168.774618)
		(end 61.206888 -169.291)
		(width 0.127)
		(layer "F.Cu")
		(net "FM_TPM_PRSNT_RST_N")
	)
	(segment
		(start 66.671698 -163.118546)
		(end 66.929 -163.375848)
		(width 0.127)
		(layer "F.Cu")
		(net "FM_TPM_PRSNT_RST_N")
	)
	(segment
		(start 66.124328 -163.118546)
		(end 66.671698 -163.118546)
		(width 0.127)
		(layer "F.Cu")
		(net "FM_TPM_PRSNT_RST_N")
	)
	(segment
		(start 53.280056 -176.266856)
		(end 54.1909 -177.1777)
		(width 0.127)
		(layer "F.Cu")
		(net "FM_TPM_PRSNT_RST_N")
	)
	(segment
		(start 60.690506 -168.317418)
		(end 60.690506 -167.860218)
		(width 0.127)
		(layer "F.Cu")
		(net "FM_TPM_PRSNT_RST_N")
	)
	(segment
		(start 67.33413 -181.701948)
		(end 67.33413 -178.23307)
		(width 0.127)
		(layer "F.Cu")
		(net "FM_TPM_PRSNT_RST_N")
	)
	(segment
		(start 61.5823 -180.9369)
		(end 63.473838 -180.9369)
		(width 0.127)
		(layer "F.Cu")
		(net "FM_TPM_PRSNT_RST_N")
	)
	(segment
		(start 61.7474 -172.085)
		(end 62.1665 -171.6659)
		(width 0.127)
		(layer "F.Cu")
		(net "FM_TPM_PRSNT_RST_N")
	)
	(segment
		(start 64.390016 -181.853078)
		(end 66.37147 -181.853078)
		(width 0.127)
		(layer "F.Cu")
		(net "FM_TPM_PRSNT_RST_N")
	)
	(segment
		(start 62.1665 -171.6659)
		(end 62.6618 -171.6659)
		(width 0.127)
		(layer "F.Cu")
		(net "FM_TPM_PRSNT_RST_N")
	)
	(segment
		(start 62.6618 -171.26458)
		(end 62.1665 -170.76928)
		(width 0.127)
		(layer "F.Cu")
		(net "FM_TPM_PRSNT_RST_N")
	)
	(segment
		(start 62.6618 -171.6659)
		(end 62.6618 -171.26458)
		(width 0.127)
		(layer "F.Cu")
		(net "FM_TPM_PRSNT_RST_N")
	)
	(segment
		(start 60.690506 -168.317418)
		(end 60.690506 -168.774618)
		(width 0.127)
		(layer "F.Cu")
		(net "FM_TPM_PRSNT_RST_N")
	)
	(segment
		(start 61.206888 -169.291)
		(end 62.1665 -169.291)
		(width 0.127)
		(layer "F.Cu")
		(net "FM_TPM_PRSNT_RST_N")
	)
	(segment
		(start 66.926714 -177.072544)
		(end 67.57797 -177.7238)
		(width 0.127)
		(layer "F.Cu")
		(net "FM_TPM_PRSNT_RST_N")
	)
	(segment
		(start 60.690506 -167.860218)
		(end 60.656978 -167.82669)
		(width 0.127)
		(layer "F.Cu")
		(net "FM_TPM_PRSNT_RST_N")
	)
	(via
		(at 61.7474 -172.085)
		(size 0.508)
		(drill 0.254)
		(layers "F.Cu" "B.Cu")
		(net "FM_TPM_PRSNT_RST_N")
	)
	(via
		(at 59.700668 -166.667942)
		(size 0.508)
		(drill 0.254)
		(layers "F.Cu" "B.Cu")
		(net "FM_TPM_PRSNT_RST_N")
	)
	(via
		(at 67.8434 -177.7238)
		(size 0.508)
		(drill 0.254)
		(layers "F.Cu" "B.Cu")
		(net "FM_TPM_PRSNT_RST_N")
	)
	(via
		(at 66.37147 -181.853078)
		(size 0.6604)
		(drill 0.3302)
		(layers "F.Cu" "B.Cu")
		(net "FM_TPM_PRSNT_RST_N")
	)
	(via
		(at 66.929 -163.375848)
		(size 0.508)
		(drill 0.254)
		(layers "F.Cu" "B.Cu")
		(net "FM_TPM_PRSNT_RST_N")
	)
	(segment
		(start 62.109858 -166.667942)
		(end 62.5348 -166.243)
		(width 0.127)
		(layer "B.Cu")
		(net "FM_TPM_PRSNT_RST_N")
	)
	(segment
		(start 64.061848 -166.243)
		(end 66.929 -163.375848)
		(width 0.127)
		(layer "B.Cu")
		(net "FM_TPM_PRSNT_RST_N")
	)
	(segment
		(start 63.177928 -173.515528)
		(end 65.399412 -173.515528)
		(width 0.127)
		(layer "B.Cu")
		(net "FM_TPM_PRSNT_RST_N")
	)
	(segment
		(start 68.29933 -176.415446)
		(end 68.29933 -176.948592)
		(width 0.127)
		(layer "B.Cu")
		(net "FM_TPM_PRSNT_RST_N")
	)
	(segment
		(start 62.5348 -166.243)
		(end 64.061848 -166.243)
		(width 0.127)
		(layer "B.Cu")
		(net "FM_TPM_PRSNT_RST_N")
	)
	(segment
		(start 61.7474 -172.085)
		(end 63.177928 -173.515528)
		(width 0.127)
		(layer "B.Cu")
		(net "FM_TPM_PRSNT_RST_N")
	)
	(segment
		(start 68.29933 -176.948592)
		(end 67.8434 -177.404522)
		(width 0.127)
		(layer "B.Cu")
		(net "FM_TPM_PRSNT_RST_N")
	)
	(segment
		(start 59.700668 -166.667942)
		(end 62.109858 -166.667942)
		(width 0.127)
		(layer "B.Cu")
		(net "FM_TPM_PRSNT_RST_N")
	)
	(segment
		(start 67.8434 -177.404522)
		(end 67.8434 -177.7238)
		(width 0.127)
		(layer "B.Cu")
		(net "FM_TPM_PRSNT_RST_N")
	)
	(segment
		(start 65.399412 -173.515528)
		(end 68.29933 -176.415446)
		(width 0.127)
		(layer "B.Cu")
		(net "FM_TPM_PRSNT_RST_N")
	)
	(segment
		(start 64.265556 -165.735)
		(end 64.9732 -165.027356)
		(width 0.127)
		(layer "F.Cu")
		(net "FM_TPM_PRSNT_RST")
	)
	(segment
		(start 65.532 -166.0525)
		(end 66.63309 -166.0525)
		(width 0.127)
		(layer "F.Cu")
		(net "FM_TPM_PRSNT_RST")
	)
	(segment
		(start 67.207892 -166.0525)
		(end 68.187824 -167.032432)
		(width 0.127)
		(layer "F.Cu")
		(net "FM_TPM_PRSNT_RST")
	)
	(segment
		(start 66.63309 -166.0525)
		(end 67.207892 -166.0525)
		(width 0.127)
		(layer "F.Cu")
		(net "FM_TPM_PRSNT_RST")
	)
	(segment
		(start 65.532 -166.0525)
		(end 65.532 -165.027356)
		(width 0.127)
		(layer "F.Cu")
		(net "FM_TPM_PRSNT_RST")
	)
	(segment
		(start 64.9732 -165.027356)
		(end 65.532 -165.027356)
		(width 0.127)
		(layer "F.Cu")
		(net "FM_TPM_PRSNT_RST")
	)
	(segment
		(start 62.1665 -165.735)
		(end 64.265556 -165.735)
		(width 0.127)
		(layer "F.Cu")
		(net "FM_TPM_PRSNT_RST")
	)
	(via
		(at 66.63309 -166.0525)
		(size 0.6604)
		(drill 0.3302)
		(layers "F.Cu" "B.Cu")
		(net "FM_TPM_PRSNT_RST")
	)
	(segment
		(start 65.626234 -173.123098)
		(end 65.659 -173.090332)
		(width 0.127)
		(layer "F.Cu")
		(net "FM_TPM_PRSNT_N")
	)
	(segment
		(start 65.659 -173.090332)
		(end 65.659 -172.5295)
		(width 0.127)
		(layer "F.Cu")
		(net "FM_TPM_PRSNT_N")
	)
	(segment
		(start 65.659 -172.5295)
		(end 64.9351 -172.5295)
		(width 0.127)
		(layer "F.Cu")
		(net "FM_TPM_PRSNT_N")
	)
	(segment
		(start 65.626234 -174.262796)
		(end 65.626234 -173.123098)
		(width 0.127)
		(layer "F.Cu")
		(net "FM_TPM_PRSNT_N")
	)
	(segment
		(start 64.9351 -172.5295)
		(end 64.77 -172.6946)
		(width 0.127)
		(layer "F.Cu")
		(net "FM_TPM_PRSNT_N")
	)
	(via
		(at 64.167004 -119.1641)
		(size 0.508)
		(drill 0.254)
		(layers "F.Cu" "B.Cu")
		(net "FM_TPM_PRSNT_N")
	)
	(via
		(at 64.77 -172.6946)
		(size 0.508)
		(drill 0.254)
		(layers "F.Cu" "B.Cu")
		(net "FM_TPM_PRSNT_N")
	)
	(via
		(at 38.986206 -122.315986)
		(size 0.508)
		(drill 0.254)
		(layers "F.Cu" "B.Cu")
		(net "FM_TPM_PRSNT_N")
	)
	(via
		(at 63.532512 -172.238924)
		(size 0.6096)
		(drill 0.3048)
		(layers "F.Cu" "B.Cu")
		(net "FM_TPM_PRSNT_N")
	)
	(segment
		(start 38.757606 -123.451874)
		(end 38.757606 -122.544586)
		(width 0.127)
		(layer "B.Cu")
		(net "FM_TPM_PRSNT_N")
	)
	(segment
		(start 63.988188 -172.6946)
		(end 64.77 -172.6946)
		(width 0.127)
		(layer "B.Cu")
		(net "FM_TPM_PRSNT_N")
	)
	(segment
		(start 38.757606 -122.544586)
		(end 38.986206 -122.315986)
		(width 0.127)
		(layer "B.Cu")
		(net "FM_TPM_PRSNT_N")
	)
	(segment
		(start 63.532512 -172.238924)
		(end 63.988188 -172.6946)
		(width 0.127)
		(layer "B.Cu")
		(net "FM_TPM_PRSNT_N")
	)
	(segment
		(start 63.7032 -149.83714)
		(end 63.7032 -147.414742)
		(width 0.127)
		(layer "In2.Cu")
		(net "FM_TPM_PRSNT_N")
	)
	(segment
		(start 65.87109 -163.415472)
		(end 67.8688 -161.417762)
		(width 0.127)
		(layer "In2.Cu")
		(net "FM_TPM_PRSNT_N")
	)
	(segment
		(start 66.174366 -150.688294)
		(end 64.554354 -150.688294)
		(width 0.127)
		(layer "In2.Cu")
		(net "FM_TPM_PRSNT_N")
	)
	(segment
		(start 62.409324 -137.8585)
		(end 62.187582 -137.8585)
		(width 0.127)
		(layer "In2.Cu")
		(net "FM_TPM_PRSNT_N")
	)
	(segment
		(start 61.84392 -134.997952)
		(end 64.6684 -132.173472)
		(width 0.127)
		(layer "In2.Cu")
		(net "FM_TPM_PRSNT_N")
	)
	(segment
		(start 64.6684 -127.993902)
		(end 64.167004 -127.492506)
		(width 0.127)
		(layer "In2.Cu")
		(net "FM_TPM_PRSNT_N")
	)
	(segment
		(start 62.990984 -146.702526)
		(end 62.990984 -140.388594)
		(width 0.127)
		(layer "In2.Cu")
		(net "FM_TPM_PRSNT_N")
	)
	(segment
		(start 62.187582 -137.8585)
		(end 61.71311 -137.384028)
		(width 0.127)
		(layer "In2.Cu")
		(net "FM_TPM_PRSNT_N")
	)
	(segment
		(start 63.1317 -140.247878)
		(end 63.1317 -138.580876)
		(width 0.127)
		(layer "In2.Cu")
		(net "FM_TPM_PRSNT_N")
	)
	(segment
		(start 63.7032 -147.414742)
		(end 62.990984 -146.702526)
		(width 0.127)
		(layer "In2.Cu")
		(net "FM_TPM_PRSNT_N")
	)
	(segment
		(start 66.25844 -154.153108)
		(end 66.79184 -153.619708)
		(width 0.127)
		(layer "In2.Cu")
		(net "FM_TPM_PRSNT_N")
	)
	(segment
		(start 63.1317 -138.580876)
		(end 62.409324 -137.8585)
		(width 0.127)
		(layer "In2.Cu")
		(net "FM_TPM_PRSNT_N")
	)
	(segment
		(start 64.554354 -150.688294)
		(end 63.7032 -149.83714)
		(width 0.127)
		(layer "In2.Cu")
		(net "FM_TPM_PRSNT_N")
	)
	(segment
		(start 67.8688 -160.310068)
		(end 66.25844 -158.699708)
		(width 0.127)
		(layer "In2.Cu")
		(net "FM_TPM_PRSNT_N")
	)
	(segment
		(start 67.8688 -161.417762)
		(end 67.8688 -160.310068)
		(width 0.127)
		(layer "In2.Cu")
		(net "FM_TPM_PRSNT_N")
	)
	(segment
		(start 61.71311 -136.524238)
		(end 61.84392 -136.393428)
		(width 0.127)
		(layer "In2.Cu")
		(net "FM_TPM_PRSNT_N")
	)
	(segment
		(start 64.167004 -127.492506)
		(end 64.167004 -119.1641)
		(width 0.127)
		(layer "In2.Cu")
		(net "FM_TPM_PRSNT_N")
	)
	(segment
		(start 64.77 -172.6946)
		(end 65.87109 -171.59351)
		(width 0.127)
		(layer "In2.Cu")
		(net "FM_TPM_PRSNT_N")
	)
	(segment
		(start 65.87109 -171.59351)
		(end 65.87109 -163.415472)
		(width 0.127)
		(layer "In2.Cu")
		(net "FM_TPM_PRSNT_N")
	)
	(segment
		(start 66.79184 -153.619708)
		(end 66.79184 -151.305768)
		(width 0.127)
		(layer "In2.Cu")
		(net "FM_TPM_PRSNT_N")
	)
	(segment
		(start 64.6684 -132.173472)
		(end 64.6684 -127.993902)
		(width 0.127)
		(layer "In2.Cu")
		(net "FM_TPM_PRSNT_N")
	)
	(segment
		(start 61.84392 -136.393428)
		(end 61.84392 -134.997952)
		(width 0.127)
		(layer "In2.Cu")
		(net "FM_TPM_PRSNT_N")
	)
	(segment
		(start 61.71311 -137.384028)
		(end 61.71311 -136.524238)
		(width 0.127)
		(layer "In2.Cu")
		(net "FM_TPM_PRSNT_N")
	)
	(segment
		(start 66.25844 -158.699708)
		(end 66.25844 -154.153108)
		(width 0.127)
		(layer "In2.Cu")
		(net "FM_TPM_PRSNT_N")
	)
	(segment
		(start 62.990984 -140.388594)
		(end 63.1317 -140.247878)
		(width 0.127)
		(layer "In2.Cu")
		(net "FM_TPM_PRSNT_N")
	)
	(segment
		(start 66.79184 -151.305768)
		(end 66.174366 -150.688294)
		(width 0.127)
		(layer "In2.Cu")
		(net "FM_TPM_PRSNT_N")
	)
	(segment
		(start 63.697104 -118.6942)
		(end 52.358036 -118.6942)
		(width 0.127)
		(layer "In5.Cu")
		(net "FM_TPM_PRSNT_N")
	)
	(segment
		(start 52.358036 -118.6942)
		(end 50.110136 -120.9421)
		(width 0.127)
		(layer "In5.Cu")
		(net "FM_TPM_PRSNT_N")
	)
	(segment
		(start 50.110136 -120.9421)
		(end 49.018444 -120.9421)
		(width 0.127)
		(layer "In5.Cu")
		(net "FM_TPM_PRSNT_N")
	)
	(segment
		(start 42.14368 -123.469654)
		(end 40.990012 -122.315986)
		(width 0.127)
		(layer "In5.Cu")
		(net "FM_TPM_PRSNT_N")
	)
	(segment
		(start 64.167004 -119.1641)
		(end 63.697104 -118.6942)
		(width 0.127)
		(layer "In5.Cu")
		(net "FM_TPM_PRSNT_N")
	)
	(segment
		(start 46.49089 -123.469654)
		(end 42.14368 -123.469654)
		(width 0.127)
		(layer "In5.Cu")
		(net "FM_TPM_PRSNT_N")
	)
	(segment
		(start 40.990012 -122.315986)
		(end 38.986206 -122.315986)
		(width 0.127)
		(layer "In5.Cu")
		(net "FM_TPM_PRSNT_N")
	)
	(segment
		(start 49.018444 -120.9421)
		(end 46.49089 -123.469654)
		(width 0.127)
		(layer "In5.Cu")
		(net "FM_TPM_PRSNT_N")
	)
	(segment
		(start 59.033664 -144.8435)
		(end 59.478164 -145.288)
		(width 0.127)
		(layer "F.Cu")
		(net "DB_PRSNT_BMC_N")
	)
	(segment
		(start 58.131964 -145.2118)
		(end 58.500264 -144.8435)
		(width 0.127)
		(layer "F.Cu")
		(net "DB_PRSNT_BMC_N")
	)
	(segment
		(start 59.478164 -145.288)
		(end 59.6392 -145.288)
		(width 0.127)
		(layer "F.Cu")
		(net "DB_PRSNT_BMC_N")
	)
	(segment
		(start 55.75681 -145.742914)
		(end 56.745886 -145.742914)
		(width 0.127)
		(layer "F.Cu")
		(net "DB_PRSNT_BMC_N")
	)
	(segment
		(start 58.500264 -144.8435)
		(end 59.033664 -144.8435)
		(width 0.127)
		(layer "F.Cu")
		(net "DB_PRSNT_BMC_N")
	)
	(segment
		(start 55.299864 -146.19986)
		(end 55.75681 -145.742914)
		(width 0.127)
		(layer "F.Cu")
		(net "DB_PRSNT_BMC_N")
	)
	(segment
		(start 57.277 -145.2118)
		(end 58.131964 -145.2118)
		(width 0.127)
		(layer "F.Cu")
		(net "DB_PRSNT_BMC_N")
	)
	(segment
		(start 56.745886 -145.742914)
		(end 57.277 -145.2118)
		(width 0.127)
		(layer "F.Cu")
		(net "DB_PRSNT_BMC_N")
	)
	(via
		(at 93.08846 -143.34744)
		(size 0.508)
		(drill 0.254)
		(layers "F.Cu" "B.Cu")
		(net "DB_PRSNT_BMC_N")
	)
	(via
		(at 59.6392 -145.288)
		(size 0.508)
		(drill 0.254)
		(layers "F.Cu" "B.Cu")
		(net "DB_PRSNT_BMC_N")
	)
	(via
		(at 90.7796 -142.113)
		(size 0.6096)
		(drill 0.3048)
		(layers "F.Cu" "B.Cu")
		(net "DB_PRSNT_BMC_N")
	)
	(segment
		(start 92.39504 -143.34744)
		(end 91.1606 -142.113)
		(width 0.127)
		(layer "B.Cu")
		(net "DB_PRSNT_BMC_N")
	)
	(segment
		(start 90.6018 -142.9131)
		(end 90.6018 -142.2908)
		(width 0.127)
		(layer "B.Cu")
		(net "DB_PRSNT_BMC_N")
	)
	(segment
		(start 93.08846 -143.34744)
		(end 92.39504 -143.34744)
		(width 0.127)
		(layer "B.Cu")
		(net "DB_PRSNT_BMC_N")
	)
	(segment
		(start 94.2213 -143.129)
		(end 93.3069 -143.129)
		(width 0.127)
		(layer "B.Cu")
		(net "DB_PRSNT_BMC_N")
	)
	(segment
		(start 93.3069 -143.129)
		(end 93.08846 -143.34744)
		(width 0.127)
		(layer "B.Cu")
		(net "DB_PRSNT_BMC_N")
	)
	(segment
		(start 90.6018 -142.2908)
		(end 90.7796 -142.113)
		(width 0.127)
		(layer "B.Cu")
		(net "DB_PRSNT_BMC_N")
	)
	(segment
		(start 90.805 -143.1163)
		(end 90.6018 -142.9131)
		(width 0.127)
		(layer "B.Cu")
		(net "DB_PRSNT_BMC_N")
	)
	(segment
		(start 91.1606 -142.113)
		(end 90.7796 -142.113)
		(width 0.127)
		(layer "B.Cu")
		(net "DB_PRSNT_BMC_N")
	)
	(segment
		(start 93.08846 -143.34744)
		(end 89.939368 -143.34744)
		(width 0.127)
		(layer "In5.Cu")
		(net "DB_PRSNT_BMC_N")
	)
	(segment
		(start 69.44614 -142.261336)
		(end 67.945 -143.762476)
		(width 0.127)
		(layer "In5.Cu")
		(net "DB_PRSNT_BMC_N")
	)
	(segment
		(start 82.54746 -142.7226)
		(end 81.60766 -141.7828)
		(width 0.127)
		(layer "In5.Cu")
		(net "DB_PRSNT_BMC_N")
	)
	(segment
		(start 65.275714 -145.0213)
		(end 59.9059 -145.0213)
		(width 0.127)
		(layer "In5.Cu")
		(net "DB_PRSNT_BMC_N")
	)
	(segment
		(start 89.314528 -142.7226)
		(end 82.54746 -142.7226)
		(width 0.127)
		(layer "In5.Cu")
		(net "DB_PRSNT_BMC_N")
	)
	(segment
		(start 72.648064 -142.261336)
		(end 69.44614 -142.261336)
		(width 0.127)
		(layer "In5.Cu")
		(net "DB_PRSNT_BMC_N")
	)
	(segment
		(start 73.1266 -141.7828)
		(end 72.648064 -142.261336)
		(width 0.127)
		(layer "In5.Cu")
		(net "DB_PRSNT_BMC_N")
	)
	(segment
		(start 66.534538 -143.762476)
		(end 65.275714 -145.0213)
		(width 0.127)
		(layer "In5.Cu")
		(net "DB_PRSNT_BMC_N")
	)
	(segment
		(start 89.939368 -143.34744)
		(end 89.314528 -142.7226)
		(width 0.127)
		(layer "In5.Cu")
		(net "DB_PRSNT_BMC_N")
	)
	(segment
		(start 81.60766 -141.7828)
		(end 73.1266 -141.7828)
		(width 0.127)
		(layer "In5.Cu")
		(net "DB_PRSNT_BMC_N")
	)
	(segment
		(start 67.945 -143.762476)
		(end 66.534538 -143.762476)
		(width 0.127)
		(layer "In5.Cu")
		(net "DB_PRSNT_BMC_N")
	)
	(segment
		(start 59.9059 -145.0213)
		(end 59.6392 -145.288)
		(width 0.127)
		(layer "In5.Cu")
		(net "DB_PRSNT_BMC_N")
	)
	(segment
		(start 68.89496 -173.47184)
		(end 68.89496 -174.3329)
		(width 0.127)
		(layer "F.Cu")
		(net "COMP_TO_BMC_RESET_N_OUT")
	)
	(segment
		(start 68.8848 -172.69206)
		(end 68.88988 -172.69714)
		(width 0.127)
		(layer "F.Cu")
		(net "COMP_TO_BMC_RESET_N_OUT")
	)
	(segment
		(start 68.8848 -171.7421)
		(end 68.8848 -172.69206)
		(width 0.127)
		(layer "F.Cu")
		(net "COMP_TO_BMC_RESET_N_OUT")
	)
	(segment
		(start 81.870804 -149.410674)
		(end 82.743294 -150.283164)
		(width 0.127)
		(layer "F.Cu")
		(net "COMP_TO_BMC_RESET_N_OUT")
	)
	(segment
		(start 68.88988 -172.69714)
		(end 68.88988 -173.46676)
		(width 0.127)
		(layer "F.Cu")
		(net "COMP_TO_BMC_RESET_N_OUT")
	)
	(segment
		(start 82.743294 -150.283164)
		(end 82.743294 -150.611586)
		(width 0.127)
		(layer "F.Cu")
		(net "COMP_TO_BMC_RESET_N_OUT")
	)
	(segment
		(start 80.965548 -149.410674)
		(end 81.870804 -149.410674)
		(width 0.127)
		(layer "F.Cu")
		(net "COMP_TO_BMC_RESET_N_OUT")
	)
	(segment
		(start 68.88988 -173.46676)
		(end 68.89496 -173.47184)
		(width 0.127)
		(layer "F.Cu")
		(net "COMP_TO_BMC_RESET_N_OUT")
	)
	(via
		(at 82.634328 -174.140368)
		(size 0.6096)
		(drill 0.3048)
		(layers "F.Cu" "B.Cu")
		(net "COMP_TO_BMC_RESET_N_OUT")
	)
	(via
		(at 68.88988 -172.69714)
		(size 0.508)
		(drill 0.254)
		(layers "F.Cu" "B.Cu")
		(net "COMP_TO_BMC_RESET_N_OUT")
	)
	(via
		(at 82.743294 -150.611586)
		(size 0.508)
		(drill 0.254)
		(layers "F.Cu" "B.Cu")
		(net "COMP_TO_BMC_RESET_N_OUT")
	)
	(via
		(at 85.88629 -170.309794)
		(size 0.508)
		(drill 0.254)
		(layers "F.Cu" "B.Cu")
		(net "COMP_TO_BMC_RESET_N_OUT")
	)
	(segment
		(start 69.596 -173.40326)
		(end 69.596 -173.739302)
		(width 0.127)
		(layer "B.Cu")
		(net "COMP_TO_BMC_RESET_N_OUT")
	)
	(segment
		(start 83.167474 -173.607222)
		(end 82.634328 -174.140368)
		(width 0.127)
		(layer "B.Cu")
		(net "COMP_TO_BMC_RESET_N_OUT")
	)
	(segment
		(start 69.596 -173.739302)
		(end 70.740778 -174.88408)
		(width 0.127)
		(layer "B.Cu")
		(net "COMP_TO_BMC_RESET_N_OUT")
	)
	(segment
		(start 82.238088 -174.536608)
		(end 82.634328 -174.140368)
		(width 0.127)
		(layer "B.Cu")
		(net "COMP_TO_BMC_RESET_N_OUT")
	)
	(segment
		(start 68.88988 -172.69714)
		(end 69.596 -173.40326)
		(width 0.127)
		(layer "B.Cu")
		(net "COMP_TO_BMC_RESET_N_OUT")
	)
	(segment
		(start 81.89087 -174.88408)
		(end 82.238088 -174.536862)
		(width 0.127)
		(layer "B.Cu")
		(net "COMP_TO_BMC_RESET_N_OUT")
	)
	(segment
		(start 82.238088 -174.536862)
		(end 82.238088 -174.536608)
		(width 0.127)
		(layer "B.Cu")
		(net "COMP_TO_BMC_RESET_N_OUT")
	)
	(segment
		(start 85.384132 -170.811952)
		(end 85.384132 -171.390818)
		(width 0.127)
		(layer "B.Cu")
		(net "COMP_TO_BMC_RESET_N_OUT")
	)
	(segment
		(start 85.88629 -170.309794)
		(end 85.384132 -170.811952)
		(width 0.127)
		(layer "B.Cu")
		(net "COMP_TO_BMC_RESET_N_OUT")
	)
	(segment
		(start 70.740778 -174.88408)
		(end 81.89087 -174.88408)
		(width 0.127)
		(layer "B.Cu")
		(net "COMP_TO_BMC_RESET_N_OUT")
	)
	(segment
		(start 85.384132 -171.390818)
		(end 83.167728 -173.607222)
		(width 0.127)
		(layer "B.Cu")
		(net "COMP_TO_BMC_RESET_N_OUT")
	)
	(segment
		(start 83.167728 -173.607222)
		(end 83.167474 -173.607222)
		(width 0.127)
		(layer "B.Cu")
		(net "COMP_TO_BMC_RESET_N_OUT")
	)
	(segment
		(start 86.4489 -161.482532)
		(end 83.51012 -158.543752)
		(width 0.127)
		(layer "In2.Cu")
		(net "COMP_TO_BMC_RESET_N_OUT")
	)
	(segment
		(start 86.4489 -166.2557)
		(end 86.4489 -161.482532)
		(width 0.127)
		(layer "In2.Cu")
		(net "COMP_TO_BMC_RESET_N_OUT")
	)
	(segment
		(start 83.51012 -151.378412)
		(end 82.743294 -150.611586)
		(width 0.127)
		(layer "In2.Cu")
		(net "COMP_TO_BMC_RESET_N_OUT")
	)
	(segment
		(start 85.888322 -170.309794)
		(end 85.8901 -170.308016)
		(width 0.127)
		(layer "In2.Cu")
		(net "COMP_TO_BMC_RESET_N_OUT")
	)
	(segment
		(start 85.8901 -166.8145)
		(end 86.4489 -166.2557)
		(width 0.127)
		(layer "In2.Cu")
		(net "COMP_TO_BMC_RESET_N_OUT")
	)
	(segment
		(start 83.51012 -158.543752)
		(end 83.51012 -151.378412)
		(width 0.127)
		(layer "In2.Cu")
		(net "COMP_TO_BMC_RESET_N_OUT")
	)
	(segment
		(start 85.8901 -170.308016)
		(end 85.8901 -166.8145)
		(width 0.127)
		(layer "In2.Cu")
		(net "COMP_TO_BMC_RESET_N_OUT")
	)
	(segment
		(start 85.88629 -170.309794)
		(end 85.888322 -170.309794)
		(width 0.127)
		(layer "In2.Cu")
		(net "COMP_TO_BMC_RESET_N_OUT")
	)
	(segment
		(start 74.4347 -140.0302)
		(end 75.38593 -140.0302)
		(width 0.127)
		(layer "F.Cu")
		(net "SYS_RST_BTN_IN_N")
	)
	(segment
		(start 75.874626 -137.804652)
		(end 75.8698 -137.809478)
		(width 0.127)
		(layer "F.Cu")
		(net "SYS_RST_BTN_IN_N")
	)
	(segment
		(start 9.779 -12.6365)
		(end 10.6045 -12.6365)
		(width 0.127)
		(layer "F.Cu")
		(net "SYS_RST_BTN_IN_N")
	)
	(segment
		(start 75.8698 -137.809478)
		(end 75.8698 -139.54633)
		(width 0.127)
		(layer "F.Cu")
		(net "SYS_RST_BTN_IN_N")
	)
	(segment
		(start 8.636 -12.319)
		(end 8.636 -11.176)
		(width 0.127)
		(layer "F.Cu")
		(net "SYS_RST_BTN_IN_N")
	)
	(segment
		(start 8.636 -11.176)
		(end 9.750044 -10.061956)
		(width 0.127)
		(layer "F.Cu")
		(net "SYS_RST_BTN_IN_N")
	)
	(segment
		(start 75.38593 -140.0302)
		(end 75.691746 -139.724384)
		(width 0.127)
		(layer "F.Cu")
		(net "SYS_RST_BTN_IN_N")
	)
	(segment
		(start 9.750044 -10.061956)
		(end 9.750044 -6.249924)
		(width 0.127)
		(layer "F.Cu")
		(net "SYS_RST_BTN_IN_N")
	)
	(segment
		(start 10.6045 -12.6365)
		(end 10.922 -12.319)
		(width 0.127)
		(layer "F.Cu")
		(net "SYS_RST_BTN_IN_N")
	)
	(segment
		(start 11.811 -12.319)
		(end 10.922 -12.319)
		(width 0.127)
		(layer "F.Cu")
		(net "SYS_RST_BTN_IN_N")
	)
	(segment
		(start 8.636 -12.319)
		(end 9.4615 -12.319)
		(width 0.127)
		(layer "F.Cu")
		(net "SYS_RST_BTN_IN_N")
	)
	(segment
		(start 75.8698 -139.54633)
		(end 75.691746 -139.724384)
		(width 0.127)
		(layer "F.Cu")
		(net "SYS_RST_BTN_IN_N")
	)
	(segment
		(start 9.4615 -12.319)
		(end 9.779 -12.6365)
		(width 0.127)
		(layer "F.Cu")
		(net "SYS_RST_BTN_IN_N")
	)
	(via
		(at 75.691746 -139.724384)
		(size 0.6604)
		(drill 0.3302)
		(layers "F.Cu" "B.Cu")
		(net "SYS_RST_BTN_IN_N")
	)
	(via
		(at 29.98851 -113.92789)
		(size 0.508)
		(drill 0.254)
		(layers "F.Cu" "B.Cu")
		(net "SYS_RST_BTN_IN_N")
	)
	(via
		(at 75.874626 -137.804652)
		(size 0.508)
		(drill 0.254)
		(layers "F.Cu" "B.Cu")
		(net "SYS_RST_BTN_IN_N")
	)
	(via
		(at 11.811 -12.319)
		(size 0.508)
		(drill 0.254)
		(layers "F.Cu" "B.Cu")
		(net "SYS_RST_BTN_IN_N")
	)
	(segment
		(start 69.053456 -127.080264)
		(end 65.662048 -127.080264)
		(width 0.127)
		(layer "B.Cu")
		(net "SYS_RST_BTN_IN_N")
	)
	(segment
		(start 40.422322 -116.459)
		(end 34.804096 -116.459)
		(width 0.127)
		(layer "B.Cu")
		(net "SYS_RST_BTN_IN_N")
	)
	(segment
		(start 75.874626 -137.804652)
		(end 75.8698 -137.799826)
		(width 0.127)
		(layer "B.Cu")
		(net "SYS_RST_BTN_IN_N")
	)
	(segment
		(start 71.5899 -131.79552)
		(end 71.5899 -129.616708)
		(width 0.127)
		(layer "B.Cu")
		(net "SYS_RST_BTN_IN_N")
	)
	(segment
		(start 53.834284 -115.2525)
		(end 41.628822 -115.2525)
		(width 0.127)
		(layer "B.Cu")
		(net "SYS_RST_BTN_IN_N")
	)
	(segment
		(start 32.272986 -113.92789)
		(end 29.98851 -113.92789)
		(width 0.127)
		(layer "B.Cu")
		(net "SYS_RST_BTN_IN_N")
	)
	(segment
		(start 65.662048 -127.080264)
		(end 53.834284 -115.2525)
		(width 0.127)
		(layer "B.Cu")
		(net "SYS_RST_BTN_IN_N")
	)
	(segment
		(start 41.628822 -115.2525)
		(end 40.422322 -116.459)
		(width 0.127)
		(layer "B.Cu")
		(net "SYS_RST_BTN_IN_N")
	)
	(segment
		(start 75.8698 -137.799826)
		(end 75.8698 -136.07542)
		(width 0.127)
		(layer "B.Cu")
		(net "SYS_RST_BTN_IN_N")
	)
	(segment
		(start 71.5899 -129.616708)
		(end 69.053456 -127.080264)
		(width 0.127)
		(layer "B.Cu")
		(net "SYS_RST_BTN_IN_N")
	)
	(segment
		(start 34.804096 -116.459)
		(end 32.272986 -113.92789)
		(width 0.127)
		(layer "B.Cu")
		(net "SYS_RST_BTN_IN_N")
	)
	(segment
		(start 75.8698 -136.07542)
		(end 71.5899 -131.79552)
		(width 0.127)
		(layer "B.Cu")
		(net "SYS_RST_BTN_IN_N")
	)
	(segment
		(start 19.875754 -15.494)
		(end 16.700754 -12.319)
		(width 0.127)
		(layer "In2.Cu")
		(net "SYS_RST_BTN_IN_N")
	)
	(segment
		(start 29.98851 -113.92789)
		(end 26.2636 -110.20298)
		(width 0.127)
		(layer "In2.Cu")
		(net "SYS_RST_BTN_IN_N")
	)
	(segment
		(start 26.4922 -18.486628)
		(end 23.499572 -15.494)
		(width 0.127)
		(layer "In2.Cu")
		(net "SYS_RST_BTN_IN_N")
	)
	(segment
		(start 23.499572 -15.494)
		(end 19.875754 -15.494)
		(width 0.127)
		(layer "In2.Cu")
		(net "SYS_RST_BTN_IN_N")
	)
	(segment
		(start 26.4922 -47.4726)
		(end 26.4922 -18.486628)
		(width 0.127)
		(layer "In2.Cu")
		(net "SYS_RST_BTN_IN_N")
	)
	(segment
		(start 16.438372 -57.526428)
		(end 26.4922 -47.4726)
		(width 0.127)
		(layer "In2.Cu")
		(net "SYS_RST_BTN_IN_N")
	)
	(segment
		(start 26.2636 -72.672956)
		(end 16.438372 -62.847728)
		(width 0.127)
		(layer "In2.Cu")
		(net "SYS_RST_BTN_IN_N")
	)
	(segment
		(start 26.2636 -110.20298)
		(end 26.2636 -72.672956)
		(width 0.127)
		(layer "In2.Cu")
		(net "SYS_RST_BTN_IN_N")
	)
	(segment
		(start 16.438372 -62.847728)
		(end 16.438372 -57.526428)
		(width 0.127)
		(layer "In2.Cu")
		(net "SYS_RST_BTN_IN_N")
	)
	(segment
		(start 16.700754 -12.319)
		(end 11.811 -12.319)
		(width 0.127)
		(layer "In2.Cu")
		(net "SYS_RST_BTN_IN_N")
	)
	(segment
		(start 52.499768 -138.600434)
		(end 52.899818 -138.200384)
		(width 0.127)
		(layer "F.Cu")
		(net "SYS_RESET_N_OUT_R")
	)
	(segment
		(start 52.899818 -138.200384)
		(end 52.899818 -138.199876)
		(width 0.127)
		(layer "F.Cu")
		(net "SYS_RESET_N_OUT_R")
	)
	(via
		(at 52.499768 -138.600434)
		(size 0.4572)
		(drill 0.2032)
		(layers "F.Cu" "B.Cu")
		(net "SYS_RESET_N_OUT_R")
	)
	(via
		(at 51.79822 -137.231882)
		(size 0.6096)
		(drill 0.3048)
		(layers "F.Cu" "B.Cu")
		(net "SYS_RESET_N_OUT_R")
	)
	(segment
		(start 51.79822 -137.231882)
		(end 51.79822 -137.898886)
		(width 0.127)
		(layer "B.Cu")
		(net "SYS_RESET_N_OUT_R")
	)
	(segment
		(start 51.79822 -137.898886)
		(end 52.499768 -138.600434)
		(width 0.127)
		(layer "B.Cu")
		(net "SYS_RESET_N_OUT_R")
	)
	(segment
		(start 51.79822 -137.196322)
		(end 50.807874 -136.205976)
		(width 0.127)
		(layer "B.Cu")
		(net "SYS_RESET_N_OUT_R")
	)
	(segment
		(start 51.79822 -137.231882)
		(end 51.79822 -137.196322)
		(width 0.127)
		(layer "B.Cu")
		(net "SYS_RESET_N_OUT_R")
	)
	(via
		(at 51.738784 -135.382)
		(size 0.508)
		(drill 0.254)
		(layers "F.Cu" "B.Cu")
		(net "SYS_RESET_N_OUT")
	)
	(via
		(at 31.8516 -126.6444)
		(size 0.508)
		(drill 0.254)
		(layers "F.Cu" "B.Cu")
		(net "SYS_RESET_N_OUT")
	)
	(via
		(at 49.1236 -117.6782)
		(size 0.508)
		(drill 0.254)
		(layers "F.Cu" "B.Cu")
		(net "SYS_RESET_N_OUT")
	)
	(segment
		(start 31.8516 -126.6444)
		(end 32.4866 -127.2794)
		(width 0.127)
		(layer "B.Cu")
		(net "SYS_RESET_N_OUT")
	)
	(segment
		(start 30.548326 -126.31547)
		(end 30.549342 -126.316486)
		(width 0.127)
		(layer "B.Cu")
		(net "SYS_RESET_N_OUT")
	)
	(segment
		(start 51.67376 -135.316976)
		(end 51.738784 -135.382)
		(width 0.127)
		(layer "B.Cu")
		(net "SYS_RESET_N_OUT")
	)
	(segment
		(start 32.4866 -127.2794)
		(end 35.6997 -127.2794)
		(width 0.127)
		(layer "B.Cu")
		(net "SYS_RESET_N_OUT")
	)
	(segment
		(start 30.549342 -126.316486)
		(end 31.523686 -126.316486)
		(width 0.127)
		(layer "B.Cu")
		(net "SYS_RESET_N_OUT")
	)
	(segment
		(start 29.520388 -126.31547)
		(end 30.548326 -126.31547)
		(width 0.127)
		(layer "B.Cu")
		(net "SYS_RESET_N_OUT")
	)
	(segment
		(start 31.523686 -126.316486)
		(end 31.8516 -126.6444)
		(width 0.127)
		(layer "B.Cu")
		(net "SYS_RESET_N_OUT")
	)
	(segment
		(start 50.807874 -135.316976)
		(end 51.67376 -135.316976)
		(width 0.127)
		(layer "B.Cu")
		(net "SYS_RESET_N_OUT")
	)
	(segment
		(start 51.738784 -135.332216)
		(end 51.738784 -135.382)
		(width 0.127)
		(layer "In2.Cu")
		(net "SYS_RESET_N_OUT")
	)
	(segment
		(start 52.161694 -125.677422)
		(end 52.161694 -129.102866)
		(width 0.127)
		(layer "In2.Cu")
		(net "SYS_RESET_N_OUT")
	)
	(segment
		(start 52.161694 -129.102866)
		(end 52.5399 -129.481072)
		(width 0.127)
		(layer "In2.Cu")
		(net "SYS_RESET_N_OUT")
	)
	(segment
		(start 52.18176 -134.88924)
		(end 51.738784 -135.332216)
		(width 0.127)
		(layer "In2.Cu")
		(net "SYS_RESET_N_OUT")
	)
	(segment
		(start 51.915568 -120.470168)
		(end 51.915568 -125.431296)
		(width 0.127)
		(layer "In2.Cu")
		(net "SYS_RESET_N_OUT")
	)
	(segment
		(start 52.18176 -133.49224)
		(end 52.18176 -134.88924)
		(width 0.127)
		(layer "In2.Cu")
		(net "SYS_RESET_N_OUT")
	)
	(segment
		(start 52.5399 -133.1341)
		(end 52.18176 -133.49224)
		(width 0.127)
		(layer "In2.Cu")
		(net "SYS_RESET_N_OUT")
	)
	(segment
		(start 51.915568 -125.431296)
		(end 52.161694 -125.677422)
		(width 0.127)
		(layer "In2.Cu")
		(net "SYS_RESET_N_OUT")
	)
	(segment
		(start 49.1236 -117.6782)
		(end 51.915568 -120.470168)
		(width 0.127)
		(layer "In2.Cu")
		(net "SYS_RESET_N_OUT")
	)
	(segment
		(start 52.5399 -129.481072)
		(end 52.5399 -133.1341)
		(width 0.127)
		(layer "In2.Cu")
		(net "SYS_RESET_N_OUT")
	)
	(segment
		(start 39.2176 -120.9294)
		(end 37.6174 -122.5296)
		(width 0.127)
		(layer "In5.Cu")
		(net "SYS_RESET_N_OUT")
	)
	(segment
		(start 37.6174 -122.5296)
		(end 35.9664 -122.5296)
		(width 0.127)
		(layer "In5.Cu")
		(net "SYS_RESET_N_OUT")
	)
	(segment
		(start 35.9664 -122.5296)
		(end 31.8516 -126.6444)
		(width 0.127)
		(layer "In5.Cu")
		(net "SYS_RESET_N_OUT")
	)
	(segment
		(start 49.1236 -117.6782)
		(end 49.1236 -118.681246)
		(width 0.127)
		(layer "In5.Cu")
		(net "SYS_RESET_N_OUT")
	)
	(segment
		(start 46.875446 -120.9294)
		(end 39.2176 -120.9294)
		(width 0.127)
		(layer "In5.Cu")
		(net "SYS_RESET_N_OUT")
	)
	(segment
		(start 49.1236 -118.681246)
		(end 46.875446 -120.9294)
		(width 0.127)
		(layer "In5.Cu")
		(net "SYS_RESET_N_OUT")
	)
	(segment
		(start 121.3485 -7.741666)
		(end 122.752866 -7.741666)
		(width 0.127)
		(layer "F.Cu")
		(net "P12V_IOM_PGOOD")
	)
	(segment
		(start 124.3584 -8.636)
		(end 123.6218 -7.8994)
		(width 0.127)
		(layer "F.Cu")
		(net "P12V_IOM_PGOOD")
	)
	(segment
		(start 122.9106 -7.8994)
		(end 123.6218 -7.8994)
		(width 0.127)
		(layer "F.Cu")
		(net "P12V_IOM_PGOOD")
	)
	(segment
		(start 122.752866 -7.741666)
		(end 122.9106 -7.8994)
		(width 0.127)
		(layer "F.Cu")
		(net "P12V_IOM_PGOOD")
	)
	(segment
		(start 214.903558 -38.652196)
		(end 213.873588 -38.652196)
		(width 0.127)
		(layer "F.Cu")
		(net "P12V_IOM_PGOOD")
	)
	(segment
		(start 124.4981 -8.636)
		(end 124.3584 -8.636)
		(width 0.127)
		(layer "F.Cu")
		(net "P12V_IOM_PGOOD")
	)
	(via
		(at 213.873588 -38.652196)
		(size 0.508)
		(drill 0.254)
		(layers "F.Cu" "B.Cu")
		(net "P12V_IOM_PGOOD")
	)
	(via
		(at 123.6218 -7.8994)
		(size 0.508)
		(drill 0.254)
		(layers "F.Cu" "B.Cu")
		(net "P12V_IOM_PGOOD")
	)
	(via
		(at 122.705114 -8.6106)
		(size 0.6096)
		(drill 0.3048)
		(layers "F.Cu" "B.Cu")
		(net "P12V_IOM_PGOOD")
	)
	(segment
		(start 122.9106 -8.6106)
		(end 122.705114 -8.6106)
		(width 0.127)
		(layer "B.Cu")
		(net "P12V_IOM_PGOOD")
	)
	(segment
		(start 124.302774 -8.580374)
		(end 123.6218 -7.8994)
		(width 0.127)
		(layer "B.Cu")
		(net "P12V_IOM_PGOOD")
	)
	(segment
		(start 122.705114 -8.6106)
		(end 122.223022 -8.6106)
		(width 0.127)
		(layer "B.Cu")
		(net "P12V_IOM_PGOOD")
	)
	(segment
		(start 122.151648 -8.539226)
		(end 121.245122 -8.539226)
		(width 0.127)
		(layer "B.Cu")
		(net "P12V_IOM_PGOOD")
	)
	(segment
		(start 122.223022 -8.6106)
		(end 122.151648 -8.539226)
		(width 0.127)
		(layer "B.Cu")
		(net "P12V_IOM_PGOOD")
	)
	(segment
		(start 123.6218 -7.8994)
		(end 122.9106 -8.6106)
		(width 0.127)
		(layer "B.Cu")
		(net "P12V_IOM_PGOOD")
	)
	(segment
		(start 124.5108 -8.580374)
		(end 124.302774 -8.580374)
		(width 0.127)
		(layer "B.Cu")
		(net "P12V_IOM_PGOOD")
	)
	(segment
		(start 123.6218 -5.226812)
		(end 124.733812 -4.1148)
		(width 0.127)
		(layer "In2.Cu")
		(net "P12V_IOM_PGOOD")
	)
	(segment
		(start 213.467188 -38.245796)
		(end 213.873588 -38.652196)
		(width 0.127)
		(layer "In2.Cu")
		(net "P12V_IOM_PGOOD")
	)
	(segment
		(start 147.73656 -8.73506)
		(end 148.76399 -8.73506)
		(width 0.127)
		(layer "In2.Cu")
		(net "P12V_IOM_PGOOD")
	)
	(segment
		(start 124.733812 -4.1148)
		(end 144.216882 -4.1148)
		(width 0.127)
		(layer "In2.Cu")
		(net "P12V_IOM_PGOOD")
	)
	(segment
		(start 153.66365 -3.8354)
		(end 173.6852 -3.8354)
		(width 0.127)
		(layer "In2.Cu")
		(net "P12V_IOM_PGOOD")
	)
	(segment
		(start 123.6218 -7.8994)
		(end 123.6218 -5.226812)
		(width 0.127)
		(layer "In2.Cu")
		(net "P12V_IOM_PGOOD")
	)
	(segment
		(start 197.520814 -7.1882)
		(end 200.065132 -9.732518)
		(width 0.127)
		(layer "In2.Cu")
		(net "P12V_IOM_PGOOD")
	)
	(segment
		(start 144.216882 -4.1148)
		(end 147.235672 -7.13359)
		(width 0.127)
		(layer "In2.Cu")
		(net "P12V_IOM_PGOOD")
	)
	(segment
		(start 209.392266 -9.732518)
		(end 213.467188 -13.80744)
		(width 0.127)
		(layer "In2.Cu")
		(net "P12V_IOM_PGOOD")
	)
	(segment
		(start 173.6852 -3.8354)
		(end 177.038 -7.1882)
		(width 0.127)
		(layer "In2.Cu")
		(net "P12V_IOM_PGOOD")
	)
	(segment
		(start 200.065132 -9.732518)
		(end 209.392266 -9.732518)
		(width 0.127)
		(layer "In2.Cu")
		(net "P12V_IOM_PGOOD")
	)
	(segment
		(start 148.76399 -8.73506)
		(end 153.66365 -3.8354)
		(width 0.127)
		(layer "In2.Cu")
		(net "P12V_IOM_PGOOD")
	)
	(segment
		(start 213.467188 -13.80744)
		(end 213.467188 -38.245796)
		(width 0.127)
		(layer "In2.Cu")
		(net "P12V_IOM_PGOOD")
	)
	(segment
		(start 147.235672 -8.234172)
		(end 147.73656 -8.73506)
		(width 0.127)
		(layer "In2.Cu")
		(net "P12V_IOM_PGOOD")
	)
	(segment
		(start 147.235672 -7.13359)
		(end 147.235672 -8.234172)
		(width 0.127)
		(layer "In2.Cu")
		(net "P12V_IOM_PGOOD")
	)
	(segment
		(start 177.038 -7.1882)
		(end 197.520814 -7.1882)
		(width 0.127)
		(layer "In2.Cu")
		(net "P12V_IOM_PGOOD")
	)
	(segment
		(start 94.680786 -83.504786)
		(end 94.680786 -62.672214)
		(width 0.127)
		(layer "F.Cu")
		(net "IOM_STBY_PGOOD")
	)
	(segment
		(start 88.0999 -168.275)
		(end 88.0999 -170.3832)
		(width 0.127)
		(layer "F.Cu")
		(net "IOM_STBY_PGOOD")
	)
	(segment
		(start 94.14383 -52.663852)
		(end 94.032324 -52.552346)
		(width 0.127)
		(layer "F.Cu")
		(net "IOM_STBY_PGOOD")
	)
	(segment
		(start 94.680786 -62.672214)
		(end 95.123 -62.23)
		(width 0.127)
		(layer "F.Cu")
		(net "IOM_STBY_PGOOD")
	)
	(segment
		(start 100.6856 -167.5892)
		(end 97.383854 -167.5892)
		(width 0.127)
		(layer "F.Cu")
		(net "IOM_STBY_PGOOD")
	)
	(segment
		(start 62.865 -179.2605)
		(end 64.1096 -179.2605)
		(width 0.127)
		(layer "F.Cu")
		(net "IOM_STBY_PGOOD")
	)
	(segment
		(start 93.467936 -52.552346)
		(end 93.467682 -52.5526)
		(width 0.127)
		(layer "F.Cu")
		(net "IOM_STBY_PGOOD")
	)
	(segment
		(start 93.467682 -52.5526)
		(end 93.3196 -52.5526)
		(width 0.127)
		(layer "F.Cu")
		(net "IOM_STBY_PGOOD")
	)
	(segment
		(start 93.3196 -52.5526)
		(end 93.09989 -52.77231)
		(width 0.127)
		(layer "F.Cu")
		(net "IOM_STBY_PGOOD")
	)
	(segment
		(start 94.9198 -83.7438)
		(end 94.680786 -83.504786)
		(width 0.127)
		(layer "F.Cu")
		(net "IOM_STBY_PGOOD")
	)
	(segment
		(start 64.1985 -179.2605)
		(end 64.6938 -179.7558)
		(width 0.127)
		(layer "F.Cu")
		(net "IOM_STBY_PGOOD")
	)
	(segment
		(start 95.123 -62.23)
		(end 95.123 -53.6448)
		(width 0.127)
		(layer "F.Cu")
		(net "IOM_STBY_PGOOD")
	)
	(segment
		(start 96.698054 -168.275)
		(end 88.0999 -168.275)
		(width 0.127)
		(layer "F.Cu")
		(net "IOM_STBY_PGOOD")
	)
	(segment
		(start 64.6938 -179.7558)
		(end 64.6938 -180.0606)
		(width 0.127)
		(layer "F.Cu")
		(net "IOM_STBY_PGOOD")
	)
	(segment
		(start 93.09989 -52.77231)
		(end 93.09989 -53.352446)
		(width 0.127)
		(layer "F.Cu")
		(net "IOM_STBY_PGOOD")
	)
	(segment
		(start 94.032324 -52.552346)
		(end 93.467936 -52.552346)
		(width 0.127)
		(layer "F.Cu")
		(net "IOM_STBY_PGOOD")
	)
	(segment
		(start 94.14383 -52.66563)
		(end 94.14383 -52.663852)
		(width 0.127)
		(layer "F.Cu")
		(net "IOM_STBY_PGOOD")
	)
	(segment
		(start 97.383854 -167.5892)
		(end 96.698054 -168.275)
		(width 0.127)
		(layer "F.Cu")
		(net "IOM_STBY_PGOOD")
	)
	(segment
		(start 95.123 -53.6448)
		(end 94.14383 -52.66563)
		(width 0.127)
		(layer "F.Cu")
		(net "IOM_STBY_PGOOD")
	)
	(segment
		(start 88.0999 -170.3832)
		(end 87.7951 -170.688)
		(width 0.127)
		(layer "F.Cu")
		(net "IOM_STBY_PGOOD")
	)
	(segment
		(start 64.1096 -179.2605)
		(end 64.1985 -179.2605)
		(width 0.127)
		(layer "F.Cu")
		(net "IOM_STBY_PGOOD")
	)
	(via
		(at 64.1096 -179.2605)
		(size 0.6604)
		(drill 0.3302)
		(layers "F.Cu" "B.Cu")
		(net "IOM_STBY_PGOOD")
	)
	(via
		(at 99.588066 -178.672236)
		(size 0.508)
		(drill 0.254)
		(layers "F.Cu" "B.Cu")
		(net "IOM_STBY_PGOOD")
	)
	(via
		(at 94.9198 -83.7438)
		(size 0.508)
		(drill 0.254)
		(layers "F.Cu" "B.Cu")
		(net "IOM_STBY_PGOOD")
	)
	(via
		(at 64.6938 -180.0606)
		(size 0.508)
		(drill 0.254)
		(layers "F.Cu" "B.Cu")
		(net "IOM_STBY_PGOOD")
	)
	(via
		(at 100.6856 -167.5892)
		(size 0.508)
		(drill 0.254)
		(layers "F.Cu" "B.Cu")
		(net "IOM_STBY_PGOOD")
	)
	(segment
		(start 102.0318 -132.151628)
		(end 102.1969 -132.316728)
		(width 0.127)
		(layer "B.Cu")
		(net "IOM_STBY_PGOOD")
	)
	(segment
		(start 99.9236 -175.3108)
		(end 99.9236 -178.336702)
		(width 0.127)
		(layer "B.Cu")
		(net "IOM_STBY_PGOOD")
	)
	(segment
		(start 102.1969 -165.39464)
		(end 100.6856 -166.90594)
		(width 0.127)
		(layer "B.Cu")
		(net "IOM_STBY_PGOOD")
	)
	(segment
		(start 95.504 -84.8868)
		(end 102.0318 -91.4146)
		(width 0.127)
		(layer "B.Cu")
		(net "IOM_STBY_PGOOD")
	)
	(segment
		(start 99.9236 -178.336702)
		(end 99.588066 -178.672236)
		(width 0.127)
		(layer "B.Cu")
		(net "IOM_STBY_PGOOD")
	)
	(segment
		(start 102.1969 -132.316728)
		(end 102.1969 -165.39464)
		(width 0.127)
		(layer "B.Cu")
		(net "IOM_STBY_PGOOD")
	)
	(segment
		(start 102.0318 -91.4146)
		(end 102.0318 -132.151628)
		(width 0.127)
		(layer "B.Cu")
		(net "IOM_STBY_PGOOD")
	)
	(segment
		(start 95.504 -84.328)
		(end 95.504 -84.8868)
		(width 0.127)
		(layer "B.Cu")
		(net "IOM_STBY_PGOOD")
	)
	(segment
		(start 100.6856 -174.5488)
		(end 99.9236 -175.3108)
		(width 0.127)
		(layer "B.Cu")
		(net "IOM_STBY_PGOOD")
	)
	(segment
		(start 94.9198 -83.7438)
		(end 95.504 -84.328)
		(width 0.127)
		(layer "B.Cu")
		(net "IOM_STBY_PGOOD")
	)
	(segment
		(start 100.6856 -167.5892)
		(end 100.6856 -174.5488)
		(width 0.127)
		(layer "B.Cu")
		(net "IOM_STBY_PGOOD")
	)
	(segment
		(start 100.6856 -166.90594)
		(end 100.6856 -167.5892)
		(width 0.127)
		(layer "B.Cu")
		(net "IOM_STBY_PGOOD")
	)
	(segment
		(start 69.4309 -180.0606)
		(end 64.6938 -180.0606)
		(width 0.127)
		(layer "In5.Cu")
		(net "IOM_STBY_PGOOD")
	)
	(segment
		(start 74.290428 -177.9143)
		(end 71.5772 -177.9143)
		(width 0.127)
		(layer "In5.Cu")
		(net "IOM_STBY_PGOOD")
	)
	(segment
		(start 75.443588 -177.940716)
		(end 74.316844 -177.940716)
		(width 0.127)
		(layer "In5.Cu")
		(net "IOM_STBY_PGOOD")
	)
	(segment
		(start 99.588066 -178.672236)
		(end 98.288602 -179.9717)
		(width 0.127)
		(layer "In5.Cu")
		(net "IOM_STBY_PGOOD")
	)
	(segment
		(start 98.288602 -179.9717)
		(end 82.830162 -179.9717)
		(width 0.127)
		(layer "In5.Cu")
		(net "IOM_STBY_PGOOD")
	)
	(segment
		(start 81.307178 -178.448716)
		(end 76.650596 -178.448716)
		(width 0.127)
		(layer "In5.Cu")
		(net "IOM_STBY_PGOOD")
	)
	(segment
		(start 82.830162 -179.9717)
		(end 81.307178 -178.448716)
		(width 0.127)
		(layer "In5.Cu")
		(net "IOM_STBY_PGOOD")
	)
	(segment
		(start 76.11618 -177.9143)
		(end 75.470004 -177.9143)
		(width 0.127)
		(layer "In5.Cu")
		(net "IOM_STBY_PGOOD")
	)
	(segment
		(start 75.470004 -177.9143)
		(end 75.443588 -177.940716)
		(width 0.127)
		(layer "In5.Cu")
		(net "IOM_STBY_PGOOD")
	)
	(segment
		(start 76.650596 -178.448716)
		(end 76.11618 -177.9143)
		(width 0.127)
		(layer "In5.Cu")
		(net "IOM_STBY_PGOOD")
	)
	(segment
		(start 74.316844 -177.940716)
		(end 74.290428 -177.9143)
		(width 0.127)
		(layer "In5.Cu")
		(net "IOM_STBY_PGOOD")
	)
	(segment
		(start 71.5772 -177.9143)
		(end 69.4309 -180.0606)
		(width 0.127)
		(layer "In5.Cu")
		(net "IOM_STBY_PGOOD")
	)
	(segment
		(start 136.199626 -4.2672)
		(end 169.116502 -4.2672)
		(width 0.127)
		(layer "F.Cu")
		(net "IOM_FULL_PGOOD")
	)
	(segment
		(start 214.999824 -90.806778)
		(end 216.080086 -90.806778)
		(width 0.127)
		(layer "F.Cu")
		(net "IOM_FULL_PGOOD")
	)
	(segment
		(start 106.295698 -18.147538)
		(end 108.753148 -15.690088)
		(width 0.127)
		(layer "F.Cu")
		(net "IOM_FULL_PGOOD")
	)
	(segment
		(start 171.679362 -6.83006)
		(end 171.679362 -7.503414)
		(width 0.127)
		(layer "F.Cu")
		(net "IOM_FULL_PGOOD")
	)
	(segment
		(start 41.7322 -133.201918)
		(end 43.175174 -134.644892)
		(width 0.127)
		(layer "F.Cu")
		(net "IOM_FULL_PGOOD")
	)
	(segment
		(start 218.492832 -94.007432)
		(end 216.08542 -91.60002)
		(width 0.127)
		(layer "F.Cu")
		(net "IOM_FULL_PGOOD")
	)
	(segment
		(start 97.027746 -62.489842)
		(end 96.012 -63.505588)
		(width 0.127)
		(layer "F.Cu")
		(net "IOM_FULL_PGOOD")
	)
	(segment
		(start 104.981248 -19.461988)
		(end 103.326438 -19.461988)
		(width 0.127)
		(layer "F.Cu")
		(net "IOM_FULL_PGOOD")
	)
	(segment
		(start 96.012 -63.505588)
		(end 96.012 -82.096356)
		(width 0.127)
		(layer "F.Cu")
		(net "IOM_FULL_PGOOD")
	)
	(segment
		(start 216.67724 -103.567992)
		(end 215.75268 -103.567992)
		(width 0.127)
		(layer "F.Cu")
		(net "IOM_FULL_PGOOD")
	)
	(segment
		(start 43.715432 -136.497568)
		(end 43.715432 -136.975342)
		(width 0.127)
		(layer "F.Cu")
		(net "IOM_FULL_PGOOD")
	)
	(segment
		(start 103.326438 -19.461988)
		(end 97.027746 -25.76068)
		(width 0.127)
		(layer "F.Cu")
		(net "IOM_FULL_PGOOD")
	)
	(segment
		(start 43.715432 -136.975342)
		(end 44.099988 -137.359898)
		(width 0.127)
		(layer "F.Cu")
		(net "IOM_FULL_PGOOD")
	)
	(segment
		(start 96.012 -82.096356)
		(end 96.6724 -82.756756)
		(width 0.127)
		(layer "F.Cu")
		(net "IOM_FULL_PGOOD")
	)
	(segment
		(start 169.116502 -4.2672)
		(end 171.679362 -6.83006)
		(width 0.127)
		(layer "F.Cu")
		(net "IOM_FULL_PGOOD")
	)
	(segment
		(start 96.6724 -82.756756)
		(end 96.6724 -85.2678)
		(width 0.127)
		(layer "F.Cu")
		(net "IOM_FULL_PGOOD")
	)
	(segment
		(start 216.080086 -90.806778)
		(end 216.08542 -90.812112)
		(width 0.127)
		(layer "F.Cu")
		(net "IOM_FULL_PGOOD")
	)
	(segment
		(start 41.7322 -130.8608)
		(end 41.7322 -133.201918)
		(width 0.127)
		(layer "F.Cu")
		(net "IOM_FULL_PGOOD")
	)
	(segment
		(start 214.999824 -90.806778)
		(end 214.175086 -90.806778)
		(width 0.127)
		(layer "F.Cu")
		(net "IOM_FULL_PGOOD")
	)
	(segment
		(start 39.624 -126.0094)
		(end 39.624 -126.9746)
		(width 0.127)
		(layer "F.Cu")
		(net "IOM_FULL_PGOOD")
	)
	(segment
		(start 106.295698 -18.147538)
		(end 104.981248 -19.461988)
		(width 0.127)
		(layer "F.Cu")
		(net "IOM_FULL_PGOOD")
	)
	(segment
		(start 108.753148 -15.690088)
		(end 108.753148 -5.13969)
		(width 0.127)
		(layer "F.Cu")
		(net "IOM_FULL_PGOOD")
	)
	(segment
		(start 44.099988 -137.359898)
		(end 44.099988 -137.40003)
		(width 0.127)
		(layer "F.Cu")
		(net "IOM_FULL_PGOOD")
	)
	(segment
		(start 39.624 -126.9746)
		(end 42.037 -129.3876)
		(width 0.127)
		(layer "F.Cu")
		(net "IOM_FULL_PGOOD")
	)
	(segment
		(start 43.175174 -135.95731)
		(end 43.715432 -136.497568)
		(width 0.127)
		(layer "F.Cu")
		(net "IOM_FULL_PGOOD")
	)
	(segment
		(start 216.08542 -91.60002)
		(end 216.08542 -90.812112)
		(width 0.127)
		(layer "F.Cu")
		(net "IOM_FULL_PGOOD")
	)
	(segment
		(start 42.037 -130.556)
		(end 41.7322 -130.8608)
		(width 0.127)
		(layer "F.Cu")
		(net "IOM_FULL_PGOOD")
	)
	(segment
		(start 42.037 -129.3876)
		(end 42.037 -130.556)
		(width 0.127)
		(layer "F.Cu")
		(net "IOM_FULL_PGOOD")
	)
	(segment
		(start 218.492832 -94.934024)
		(end 218.492832 -94.007432)
		(width 0.127)
		(layer "F.Cu")
		(net "IOM_FULL_PGOOD")
	)
	(segment
		(start 97.027746 -25.76068)
		(end 97.027746 -62.489842)
		(width 0.127)
		(layer "F.Cu")
		(net "IOM_FULL_PGOOD")
	)
	(segment
		(start 110.23727 -3.655568)
		(end 135.587994 -3.655568)
		(width 0.127)
		(layer "F.Cu")
		(net "IOM_FULL_PGOOD")
	)
	(segment
		(start 43.175174 -134.644892)
		(end 43.175174 -135.95731)
		(width 0.127)
		(layer "F.Cu")
		(net "IOM_FULL_PGOOD")
	)
	(segment
		(start 135.587994 -3.655568)
		(end 136.199626 -4.2672)
		(width 0.127)
		(layer "F.Cu")
		(net "IOM_FULL_PGOOD")
	)
	(segment
		(start 108.753148 -5.13969)
		(end 110.23727 -3.655568)
		(width 0.127)
		(layer "F.Cu")
		(net "IOM_FULL_PGOOD")
	)
	(segment
		(start 214.175086 -90.806778)
		(end 214.100664 -90.732356)
		(width 0.127)
		(layer "F.Cu")
		(net "IOM_FULL_PGOOD")
	)
	(via
		(at 169.806874 -18.161)
		(size 0.508)
		(drill 0.254)
		(layers "F.Cu" "B.Cu")
		(net "IOM_FULL_PGOOD")
	)
	(via
		(at 106.295698 -18.147538)
		(size 0.6604)
		(drill 0.3302)
		(layers "F.Cu" "B.Cu")
		(net "IOM_FULL_PGOOD")
	)
	(via
		(at 171.679362 -7.503414)
		(size 0.508)
		(drill 0.254)
		(layers "F.Cu" "B.Cu")
		(net "IOM_FULL_PGOOD")
	)
	(via
		(at 41.409874 -112.1918)
		(size 0.508)
		(drill 0.254)
		(layers "F.Cu" "B.Cu")
		(net "IOM_FULL_PGOOD")
	)
	(via
		(at 96.22536 -113.96726)
		(size 0.508)
		(drill 0.254)
		(layers "F.Cu" "B.Cu")
		(net "IOM_FULL_PGOOD")
	)
	(via
		(at 208.8642 -99.06)
		(size 0.508)
		(drill 0.254)
		(layers "F.Cu" "B.Cu")
		(net "IOM_FULL_PGOOD")
	)
	(via
		(at 96.6724 -85.2678)
		(size 0.508)
		(drill 0.254)
		(layers "F.Cu" "B.Cu")
		(net "IOM_FULL_PGOOD")
	)
	(via
		(at 39.624 -126.0094)
		(size 0.508)
		(drill 0.254)
		(layers "F.Cu" "B.Cu")
		(net "IOM_FULL_PGOOD")
	)
	(via
		(at 215.75268 -103.567992)
		(size 0.508)
		(drill 0.254)
		(layers "F.Cu" "B.Cu")
		(net "IOM_FULL_PGOOD")
	)
	(via
		(at 212.29828 -96.690688)
		(size 0.6096)
		(drill 0.3048)
		(layers "F.Cu" "B.Cu")
		(net "IOM_FULL_PGOOD")
	)
	(via
		(at 214.100664 -90.732356)
		(size 0.508)
		(drill 0.254)
		(layers "F.Cu" "B.Cu")
		(net "IOM_FULL_PGOOD")
	)
	(via
		(at 179.1843 -112.0013)
		(size 0.508)
		(drill 0.254)
		(layers "F.Cu" "B.Cu")
		(net "IOM_FULL_PGOOD")
	)
	(segment
		(start 95.48622 -113.7666)
		(end 95.19285 -113.47323)
		(width 0.127)
		(layer "B.Cu")
		(net "IOM_FULL_PGOOD")
	)
	(segment
		(start 61.403992 -117.509798)
		(end 57.686194 -113.792)
		(width 0.127)
		(layer "B.Cu")
		(net "IOM_FULL_PGOOD")
	)
	(segment
		(start 63.533782 -117.509798)
		(end 61.403992 -117.509798)
		(width 0.127)
		(layer "B.Cu")
		(net "IOM_FULL_PGOOD")
	)
	(segment
		(start 96.22536 -113.96726)
		(end 96.0247 -113.7666)
		(width 0.127)
		(layer "B.Cu")
		(net "IOM_FULL_PGOOD")
	)
	(segment
		(start 212.29828 -95.369888)
		(end 214.100664 -93.567504)
		(width 0.127)
		(layer "B.Cu")
		(net "IOM_FULL_PGOOD")
	)
	(segment
		(start 171.814744 -16.15313)
		(end 169.806874 -18.161)
		(width 0.127)
		(layer "B.Cu")
		(net "IOM_FULL_PGOOD")
	)
	(segment
		(start 214.100664 -93.567504)
		(end 214.100664 -90.732356)
		(width 0.127)
		(layer "B.Cu")
		(net "IOM_FULL_PGOOD")
	)
	(segment
		(start 171.679362 -7.503414)
		(end 171.679362 -7.973314)
		(width 0.127)
		(layer "B.Cu")
		(net "IOM_FULL_PGOOD")
	)
	(segment
		(start 63.600584 -117.5766)
		(end 63.533782 -117.509798)
		(width 0.127)
		(layer "B.Cu")
		(net "IOM_FULL_PGOOD")
	)
	(segment
		(start 89.59977 -113.47323)
		(end 88.381586 -114.691414)
		(width 0.127)
		(layer "B.Cu")
		(net "IOM_FULL_PGOOD")
	)
	(segment
		(start 212.29828 -96.690688)
		(end 212.29828 -95.369888)
		(width 0.127)
		(layer "B.Cu")
		(net "IOM_FULL_PGOOD")
	)
	(segment
		(start 178.2445 -112.2934)
		(end 178.8922 -112.2934)
		(width 0.127)
		(layer "B.Cu")
		(net "IOM_FULL_PGOOD")
	)
	(segment
		(start 212.29828 -100.113592)
		(end 215.75268 -103.567992)
		(width 0.127)
		(layer "B.Cu")
		(net "IOM_FULL_PGOOD")
	)
	(segment
		(start 95.19285 -113.47323)
		(end 89.59977 -113.47323)
		(width 0.127)
		(layer "B.Cu")
		(net "IOM_FULL_PGOOD")
	)
	(segment
		(start 56.401208 -113.792)
		(end 54.635908 -112.0267)
		(width 0.127)
		(layer "B.Cu")
		(net "IOM_FULL_PGOOD")
	)
	(segment
		(start 171.814744 -8.108696)
		(end 171.814744 -16.15313)
		(width 0.127)
		(layer "B.Cu")
		(net "IOM_FULL_PGOOD")
	)
	(segment
		(start 212.29828 -96.690688)
		(end 212.29828 -100.113592)
		(width 0.127)
		(layer "B.Cu")
		(net "IOM_FULL_PGOOD")
	)
	(segment
		(start 57.686194 -113.792)
		(end 56.401208 -113.792)
		(width 0.127)
		(layer "B.Cu")
		(net "IOM_FULL_PGOOD")
	)
	(segment
		(start 208.8261 -99.0981)
		(end 208.8642 -99.06)
		(width 0.127)
		(layer "B.Cu")
		(net "IOM_FULL_PGOOD")
	)
	(segment
		(start 54.635908 -112.0267)
		(end 41.574974 -112.0267)
		(width 0.127)
		(layer "B.Cu")
		(net "IOM_FULL_PGOOD")
	)
	(segment
		(start 76.767182 -114.691414)
		(end 73.881996 -117.5766)
		(width 0.127)
		(layer "B.Cu")
		(net "IOM_FULL_PGOOD")
	)
	(segment
		(start 73.881996 -117.5766)
		(end 63.600584 -117.5766)
		(width 0.127)
		(layer "B.Cu")
		(net "IOM_FULL_PGOOD")
	)
	(segment
		(start 171.679362 -7.973314)
		(end 171.814744 -8.108696)
		(width 0.127)
		(layer "B.Cu")
		(net "IOM_FULL_PGOOD")
	)
	(segment
		(start 41.574974 -112.0267)
		(end 41.409874 -112.1918)
		(width 0.127)
		(layer "B.Cu")
		(net "IOM_FULL_PGOOD")
	)
	(segment
		(start 88.381586 -114.691414)
		(end 76.767182 -114.691414)
		(width 0.127)
		(layer "B.Cu")
		(net "IOM_FULL_PGOOD")
	)
	(segment
		(start 96.0247 -113.7666)
		(end 95.48622 -113.7666)
		(width 0.127)
		(layer "B.Cu")
		(net "IOM_FULL_PGOOD")
	)
	(segment
		(start 178.8922 -112.2934)
		(end 179.1843 -112.0013)
		(width 0.127)
		(layer "B.Cu")
		(net "IOM_FULL_PGOOD")
	)
	(segment
		(start 208.0514 -99.0981)
		(end 208.8261 -99.0981)
		(width 0.127)
		(layer "B.Cu")
		(net "IOM_FULL_PGOOD")
	)
	(segment
		(start 40.814498 -124.818902)
		(end 39.624 -126.0094)
		(width 0.127)
		(layer "In2.Cu")
		(net "IOM_FULL_PGOOD")
	)
	(segment
		(start 40.814498 -115.186714)
		(end 40.814498 -124.818902)
		(width 0.127)
		(layer "In2.Cu")
		(net "IOM_FULL_PGOOD")
	)
	(segment
		(start 41.409874 -114.591338)
		(end 40.814498 -115.186714)
		(width 0.127)
		(layer "In2.Cu")
		(net "IOM_FULL_PGOOD")
	)
	(segment
		(start 41.409874 -112.1918)
		(end 41.409874 -114.591338)
		(width 0.127)
		(layer "In2.Cu")
		(net "IOM_FULL_PGOOD")
	)
	(segment
		(start 213.372192 -103.567992)
		(end 208.8642 -99.06)
		(width 0.127)
		(layer "In2.Cu")
		(net "IOM_FULL_PGOOD")
	)
	(segment
		(start 215.75268 -103.567992)
		(end 213.372192 -103.567992)
		(width 0.127)
		(layer "In2.Cu")
		(net "IOM_FULL_PGOOD")
	)
	(segment
		(start 98.20148 -86.79688)
		(end 96.6724 -85.2678)
		(width 0.127)
		(layer "In5.Cu")
		(net "IOM_FULL_PGOOD")
	)
	(segment
		(start 179.1843 -112.0013)
		(end 178.9176 -112.9792)
		(width 0.127)
		(layer "In5.Cu")
		(net "IOM_FULL_PGOOD")
	)
	(segment
		(start 176.8856 -109.22)
		(end 179.1843 -111.5187)
		(width 0.127)
		(layer "In5.Cu")
		(net "IOM_FULL_PGOOD")
	)
	(segment
		(start 208.8642 -99.06)
		(end 206.5274 -101.3968)
		(width 0.127)
		(layer "In5.Cu")
		(net "IOM_FULL_PGOOD")
	)
	(segment
		(start 97.5106 -110.5408)
		(end 98.20148 -109.84992)
		(width 0.127)
		(layer "In5.Cu")
		(net "IOM_FULL_PGOOD")
	)
	(segment
		(start 182.9308 -101.3968)
		(end 176.8856 -107.442)
		(width 0.127)
		(layer "In5.Cu")
		(net "IOM_FULL_PGOOD")
	)
	(segment
		(start 96.2152 -113.96726)
		(end 96.2152 -113.9952)
		(width 0.127)
		(layer "In5.Cu")
		(net "IOM_FULL_PGOOD")
	)
	(segment
		(start 176.0728 -111.9886)
		(end 176.0728 -93.963998)
		(width 0.127)
		(layer "In5.Cu")
		(net "IOM_FULL_PGOOD")
	)
	(segment
		(start 206.5274 -101.3968)
		(end 182.9308 -101.3968)
		(width 0.127)
		(layer "In5.Cu")
		(net "IOM_FULL_PGOOD")
	)
	(segment
		(start 97.5106 -112.6998)
		(end 97.5106 -110.5408)
		(width 0.127)
		(layer "In5.Cu")
		(net "IOM_FULL_PGOOD")
	)
	(segment
		(start 175.811688 -38.727888)
		(end 169.806874 -32.723074)
		(width 0.127)
		(layer "In5.Cu")
		(net "IOM_FULL_PGOOD")
	)
	(segment
		(start 169.806874 -32.723074)
		(end 169.806874 -18.161)
		(width 0.127)
		(layer "In5.Cu")
		(net "IOM_FULL_PGOOD")
	)
	(segment
		(start 96.22536 -113.96726)
		(end 96.2152 -113.96726)
		(width 0.127)
		(layer "In5.Cu")
		(net "IOM_FULL_PGOOD")
	)
	(segment
		(start 178.9176 -112.9792)
		(end 177.0634 -112.9792)
		(width 0.127)
		(layer "In5.Cu")
		(net "IOM_FULL_PGOOD")
	)
	(segment
		(start 96.2152 -113.9952)
		(end 97.5106 -112.6998)
		(width 0.127)
		(layer "In5.Cu")
		(net "IOM_FULL_PGOOD")
	)
	(segment
		(start 176.8856 -107.442)
		(end 176.8856 -109.22)
		(width 0.127)
		(layer "In5.Cu")
		(net "IOM_FULL_PGOOD")
	)
	(segment
		(start 98.20148 -109.84992)
		(end 98.20148 -86.79688)
		(width 0.127)
		(layer "In5.Cu")
		(net "IOM_FULL_PGOOD")
	)
	(segment
		(start 175.811688 -93.702886)
		(end 175.811688 -38.727888)
		(width 0.127)
		(layer "In5.Cu")
		(net "IOM_FULL_PGOOD")
	)
	(segment
		(start 177.0634 -112.9792)
		(end 176.0728 -111.9886)
		(width 0.127)
		(layer "In5.Cu")
		(net "IOM_FULL_PGOOD")
	)
	(segment
		(start 179.1843 -111.5187)
		(end 179.1843 -112.0013)
		(width 0.127)
		(layer "In5.Cu")
		(net "IOM_FULL_PGOOD")
	)
	(segment
		(start 176.0728 -93.963998)
		(end 175.811688 -93.702886)
		(width 0.127)
		(layer "In5.Cu")
		(net "IOM_FULL_PGOOD")
	)
	(segment
		(start 100.5332 -133.288532)
		(end 100.5332 -130.525012)
		(width 0.127)
		(layer "F.Cu")
		(net "DPB_MISC_ALERT_OUT")
	)
	(segment
		(start 102.467664 -169.18432)
		(end 102.467664 -135.222996)
		(width 0.127)
		(layer "F.Cu")
		(net "DPB_MISC_ALERT_OUT")
	)
	(segment
		(start 99.4918 -129.483612)
		(end 99.4918 -128.8542)
		(width 0.127)
		(layer "F.Cu")
		(net "DPB_MISC_ALERT_OUT")
	)
	(segment
		(start 99.4918 -128.8542)
		(end 99.4918 -128.060958)
		(width 0.127)
		(layer "F.Cu")
		(net "DPB_MISC_ALERT_OUT")
	)
	(segment
		(start 98.7425 -171.6024)
		(end 100.049584 -171.6024)
		(width 0.127)
		(layer "F.Cu")
		(net "DPB_MISC_ALERT_OUT")
	)
	(segment
		(start 99.4918 -128.060958)
		(end 98.583242 -127.1524)
		(width 0.127)
		(layer "F.Cu")
		(net "DPB_MISC_ALERT_OUT")
	)
	(segment
		(start 100.049584 -171.6024)
		(end 102.467664 -169.18432)
		(width 0.127)
		(layer "F.Cu")
		(net "DPB_MISC_ALERT_OUT")
	)
	(segment
		(start 98.583242 -127.1524)
		(end 98.583242 -125.077728)
		(width 0.127)
		(layer "F.Cu")
		(net "DPB_MISC_ALERT_OUT")
	)
	(segment
		(start 102.467664 -135.222996)
		(end 100.5332 -133.288532)
		(width 0.127)
		(layer "F.Cu")
		(net "DPB_MISC_ALERT_OUT")
	)
	(segment
		(start 100.5332 -130.525012)
		(end 99.4918 -129.483612)
		(width 0.127)
		(layer "F.Cu")
		(net "DPB_MISC_ALERT_OUT")
	)
	(via
		(at 99.4918 -128.8542)
		(size 0.6604)
		(drill 0.3302)
		(layers "F.Cu" "B.Cu")
		(net "DPB_MISC_ALERT_OUT")
	)
	(via
		(at 50.8508 -134.4168)
		(size 0.508)
		(drill 0.254)
		(layers "F.Cu" "B.Cu")
		(net "DPB_MISC_ALERT_OUT")
	)
	(via
		(at 98.583242 -125.077728)
		(size 0.508)
		(drill 0.254)
		(layers "F.Cu" "B.Cu")
		(net "DPB_MISC_ALERT_OUT")
	)
	(segment
		(start 49.787302 -135.31215)
		(end 49.787302 -134.527798)
		(width 0.127)
		(layer "B.Cu")
		(net "DPB_MISC_ALERT_OUT")
	)
	(segment
		(start 50.673 -134.239)
		(end 50.0761 -134.239)
		(width 0.127)
		(layer "B.Cu")
		(net "DPB_MISC_ALERT_OUT")
	)
	(segment
		(start 50.8508 -134.4168)
		(end 50.673 -134.239)
		(width 0.127)
		(layer "B.Cu")
		(net "DPB_MISC_ALERT_OUT")
	)
	(segment
		(start 49.787302 -134.527798)
		(end 50.0761 -134.239)
		(width 0.127)
		(layer "B.Cu")
		(net "DPB_MISC_ALERT_OUT")
	)
	(segment
		(start 98.583242 -125.104652)
		(end 98.583242 -125.077728)
		(width 0.127)
		(layer "In5.Cu")
		(net "DPB_MISC_ALERT_OUT")
	)
	(segment
		(start 83.542124 -129.8956)
		(end 83.846924 -129.5908)
		(width 0.127)
		(layer "In5.Cu")
		(net "DPB_MISC_ALERT_OUT")
	)
	(segment
		(start 83.846924 -129.5908)
		(end 85.617812 -129.5908)
		(width 0.127)
		(layer "In5.Cu")
		(net "DPB_MISC_ALERT_OUT")
	)
	(segment
		(start 80.1624 -129.4384)
		(end 80.6196 -129.8956)
		(width 0.127)
		(layer "In5.Cu")
		(net "DPB_MISC_ALERT_OUT")
	)
	(segment
		(start 56.4134 -133.4008)
		(end 58.5216 -131.2926)
		(width 0.127)
		(layer "In5.Cu")
		(net "DPB_MISC_ALERT_OUT")
	)
	(segment
		(start 51.8668 -133.4008)
		(end 56.4134 -133.4008)
		(width 0.127)
		(layer "In5.Cu")
		(net "DPB_MISC_ALERT_OUT")
	)
	(segment
		(start 50.8508 -134.4168)
		(end 51.8668 -133.4008)
		(width 0.127)
		(layer "In5.Cu")
		(net "DPB_MISC_ALERT_OUT")
	)
	(segment
		(start 85.617812 -129.5908)
		(end 87.243412 -127.9652)
		(width 0.127)
		(layer "In5.Cu")
		(net "DPB_MISC_ALERT_OUT")
	)
	(segment
		(start 70.781164 -131.2926)
		(end 71.365364 -130.7084)
		(width 0.127)
		(layer "In5.Cu")
		(net "DPB_MISC_ALERT_OUT")
	)
	(segment
		(start 80.6196 -129.8956)
		(end 83.542124 -129.8956)
		(width 0.127)
		(layer "In5.Cu")
		(net "DPB_MISC_ALERT_OUT")
	)
	(segment
		(start 71.365364 -130.7084)
		(end 76.817982 -130.7084)
		(width 0.127)
		(layer "In5.Cu")
		(net "DPB_MISC_ALERT_OUT")
	)
	(segment
		(start 78.087982 -129.4384)
		(end 80.1624 -129.4384)
		(width 0.127)
		(layer "In5.Cu")
		(net "DPB_MISC_ALERT_OUT")
	)
	(segment
		(start 96.618298 -127.069596)
		(end 98.583242 -125.104652)
		(width 0.127)
		(layer "In5.Cu")
		(net "DPB_MISC_ALERT_OUT")
	)
	(segment
		(start 58.5216 -131.2926)
		(end 70.781164 -131.2926)
		(width 0.127)
		(layer "In5.Cu")
		(net "DPB_MISC_ALERT_OUT")
	)
	(segment
		(start 93.545406 -126.134368)
		(end 94.480634 -127.069596)
		(width 0.127)
		(layer "In5.Cu")
		(net "DPB_MISC_ALERT_OUT")
	)
	(segment
		(start 89.658444 -126.134368)
		(end 93.545406 -126.134368)
		(width 0.127)
		(layer "In5.Cu")
		(net "DPB_MISC_ALERT_OUT")
	)
	(segment
		(start 76.817982 -130.7084)
		(end 78.087982 -129.4384)
		(width 0.127)
		(layer "In5.Cu")
		(net "DPB_MISC_ALERT_OUT")
	)
	(segment
		(start 87.827612 -127.9652)
		(end 89.658444 -126.134368)
		(width 0.127)
		(layer "In5.Cu")
		(net "DPB_MISC_ALERT_OUT")
	)
	(segment
		(start 87.243412 -127.9652)
		(end 87.827612 -127.9652)
		(width 0.127)
		(layer "In5.Cu")
		(net "DPB_MISC_ALERT_OUT")
	)
	(segment
		(start 94.480634 -127.069596)
		(end 96.618298 -127.069596)
		(width 0.127)
		(layer "In5.Cu")
		(net "DPB_MISC_ALERT_OUT")
	)
	(segment
		(start 50.899822 -138.599926)
		(end 50.500026 -138.999722)
		(width 0.127)
		(layer "F.Cu")
		(net "DPB_MISC_ALERT_O_R")
	)
	(segment
		(start 50.500026 -138.999722)
		(end 50.500026 -138.999976)
		(width 0.127)
		(layer "F.Cu")
		(net "DPB_MISC_ALERT_O_R")
	)
	(via
		(at 50.902108 -137.710926)
		(size 0.6096)
		(drill 0.3048)
		(layers "F.Cu" "B.Cu")
		(net "DPB_MISC_ALERT_O_R")
	)
	(via
		(at 50.899822 -138.599926)
		(size 0.4572)
		(drill 0.2032)
		(layers "F.Cu" "B.Cu")
		(net "DPB_MISC_ALERT_O_R")
	)
	(segment
		(start 50.9016 -137.711434)
		(end 50.9016 -138.598148)
		(width 0.127)
		(layer "B.Cu")
		(net "DPB_MISC_ALERT_O_R")
	)
	(segment
		(start 50.9016 -137.710418)
		(end 50.902108 -137.710926)
		(width 0.127)
		(layer "B.Cu")
		(net "DPB_MISC_ALERT_O_R")
	)
	(segment
		(start 50.902108 -137.710926)
		(end 50.9016 -137.711434)
		(width 0.127)
		(layer "B.Cu")
		(net "DPB_MISC_ALERT_O_R")
	)
	(segment
		(start 49.787302 -136.20115)
		(end 49.970944 -136.20115)
		(width 0.127)
		(layer "B.Cu")
		(net "DPB_MISC_ALERT_O_R")
	)
	(segment
		(start 50.9016 -137.131806)
		(end 50.9016 -137.710418)
		(width 0.127)
		(layer "B.Cu")
		(net "DPB_MISC_ALERT_O_R")
	)
	(segment
		(start 50.9016 -138.598148)
		(end 50.899822 -138.599926)
		(width 0.127)
		(layer "B.Cu")
		(net "DPB_MISC_ALERT_O_R")
	)
	(segment
		(start 49.970944 -136.20115)
		(end 50.9016 -137.131806)
		(width 0.127)
		(layer "B.Cu")
		(net "DPB_MISC_ALERT_O_R")
	)
	(via
		(at 84.2264 -130.2766)
		(size 0.6096)
		(drill 0.3048)
		(layers "F.Cu" "B.Cu")
		(net "BMC_TO_EXP_RESET_OUT_R")
	)
	(segment
		(start 84.13623 -130.36677)
		(end 83.57997 -130.36677)
		(width 0.127)
		(layer "B.Cu")
		(net "BMC_TO_EXP_RESET_OUT_R")
	)
	(segment
		(start 83.9724 -129.3749)
		(end 83.9724 -129.794)
		(width 0.127)
		(layer "B.Cu")
		(net "BMC_TO_EXP_RESET_OUT_R")
	)
	(segment
		(start 83.9724 -129.794)
		(end 84.2264 -130.048)
		(width 0.127)
		(layer "B.Cu")
		(net "BMC_TO_EXP_RESET_OUT_R")
	)
	(segment
		(start 84.2264 -130.048)
		(end 84.2264 -130.2766)
		(width 0.127)
		(layer "B.Cu")
		(net "BMC_TO_EXP_RESET_OUT_R")
	)
	(segment
		(start 83.4898 -130.2766)
		(end 82.0039 -130.2766)
		(width 0.127)
		(layer "B.Cu")
		(net "BMC_TO_EXP_RESET_OUT_R")
	)
	(segment
		(start 83.57997 -130.36677)
		(end 83.4898 -130.2766)
		(width 0.127)
		(layer "B.Cu")
		(net "BMC_TO_EXP_RESET_OUT_R")
	)
	(segment
		(start 84.2264 -130.2766)
		(end 84.13623 -130.36677)
		(width 0.127)
		(layer "B.Cu")
		(net "BMC_TO_EXP_RESET_OUT_R")
	)
	(segment
		(start 59.419744 -141.732)
		(end 59.336178 -141.648434)
		(width 0.127)
		(layer "F.Cu")
		(net "BMC_TO_EXP_RESET_OUT")
	)
	(segment
		(start 61.8998 -141.1097)
		(end 61.2775 -141.732)
		(width 0.127)
		(layer "F.Cu")
		(net "BMC_TO_EXP_RESET_OUT")
	)
	(segment
		(start 61.2775 -141.732)
		(end 59.419744 -141.732)
		(width 0.127)
		(layer "F.Cu")
		(net "BMC_TO_EXP_RESET_OUT")
	)
	(segment
		(start 53.699918 -143.800068)
		(end 54.099968 -143.400018)
		(width 0.127)
		(layer "F.Cu")
		(net "BMC_TO_EXP_RESET_OUT")
	)
	(via
		(at 54.099968 -143.400018)
		(size 0.4572)
		(drill 0.2032)
		(layers "F.Cu" "B.Cu")
		(net "BMC_TO_EXP_RESET_OUT")
	)
	(via
		(at 59.336178 -141.648434)
		(size 0.508)
		(drill 0.254)
		(layers "F.Cu" "B.Cu")
		(net "BMC_TO_EXP_RESET_OUT")
	)
	(via
		(at 85.09 -127.1524)
		(size 0.508)
		(drill 0.254)
		(layers "F.Cu" "B.Cu")
		(net "BMC_TO_EXP_RESET_OUT")
	)
	(via
		(at 61.6204 -129.4892)
		(size 0.508)
		(drill 0.254)
		(layers "F.Cu" "B.Cu")
		(net "BMC_TO_EXP_RESET_OUT")
	)
	(via
		(at 84.13496 -127.23368)
		(size 0.6096)
		(drill 0.3048)
		(layers "F.Cu" "B.Cu")
		(net "BMC_TO_EXP_RESET_OUT")
	)
	(segment
		(start 83.9724 -128.4859)
		(end 83.9724 -127.39624)
		(width 0.127)
		(layer "B.Cu")
		(net "BMC_TO_EXP_RESET_OUT")
	)
	(segment
		(start 83.9724 -127.39624)
		(end 84.13496 -127.23368)
		(width 0.127)
		(layer "B.Cu")
		(net "BMC_TO_EXP_RESET_OUT")
	)
	(segment
		(start 85.09 -127.1524)
		(end 84.21624 -127.1524)
		(width 0.127)
		(layer "B.Cu")
		(net "BMC_TO_EXP_RESET_OUT")
	)
	(segment
		(start 84.21624 -127.1524)
		(end 84.13496 -127.23368)
		(width 0.127)
		(layer "B.Cu")
		(net "BMC_TO_EXP_RESET_OUT")
	)
	(segment
		(start 58.508392 -134.612126)
		(end 58.639202 -134.742936)
		(width 0.127)
		(layer "In2.Cu")
		(net "BMC_TO_EXP_RESET_OUT")
	)
	(segment
		(start 61.6204 -129.4892)
		(end 61.6204 -130.256026)
		(width 0.127)
		(layer "In2.Cu")
		(net "BMC_TO_EXP_RESET_OUT")
	)
	(segment
		(start 58.508392 -133.368034)
		(end 58.508392 -134.612126)
		(width 0.127)
		(layer "In2.Cu")
		(net "BMC_TO_EXP_RESET_OUT")
	)
	(segment
		(start 58.639202 -134.742936)
		(end 58.639202 -140.951458)
		(width 0.127)
		(layer "In2.Cu")
		(net "BMC_TO_EXP_RESET_OUT")
	)
	(segment
		(start 61.6204 -130.256026)
		(end 58.508392 -133.368034)
		(width 0.127)
		(layer "In2.Cu")
		(net "BMC_TO_EXP_RESET_OUT")
	)
	(segment
		(start 58.639202 -140.951458)
		(end 59.336178 -141.648434)
		(width 0.127)
		(layer "In2.Cu")
		(net "BMC_TO_EXP_RESET_OUT")
	)
	(segment
		(start 62.0903 -129.9591)
		(end 61.6204 -129.4892)
		(width 0.127)
		(layer "In5.Cu")
		(net "BMC_TO_EXP_RESET_OUT")
	)
	(segment
		(start 70.9422 -129.5146)
		(end 70.4977 -129.9591)
		(width 0.127)
		(layer "In5.Cu")
		(net "BMC_TO_EXP_RESET_OUT")
	)
	(segment
		(start 85.09 -127.1524)
		(end 84.7852 -127.1524)
		(width 0.127)
		(layer "In5.Cu")
		(net "BMC_TO_EXP_RESET_OUT")
	)
	(segment
		(start 54.3433 -143.400018)
		(end 54.736492 -143.006826)
		(width 0.127)
		(layer "In5.Cu")
		(net "BMC_TO_EXP_RESET_OUT")
	)
	(segment
		(start 83.6422 -128.2954)
		(end 77.580236 -128.2954)
		(width 0.127)
		(layer "In5.Cu")
		(net "BMC_TO_EXP_RESET_OUT")
	)
	(segment
		(start 77.580236 -128.2954)
		(end 76.361036 -129.5146)
		(width 0.127)
		(layer "In5.Cu")
		(net "BMC_TO_EXP_RESET_OUT")
	)
	(segment
		(start 54.099968 -143.400018)
		(end 54.3433 -143.400018)
		(width 0.127)
		(layer "In5.Cu")
		(net "BMC_TO_EXP_RESET_OUT")
	)
	(segment
		(start 56.566054 -143.006826)
		(end 57.924446 -141.648434)
		(width 0.127)
		(layer "In5.Cu")
		(net "BMC_TO_EXP_RESET_OUT")
	)
	(segment
		(start 57.924446 -141.648434)
		(end 59.336178 -141.648434)
		(width 0.127)
		(layer "In5.Cu")
		(net "BMC_TO_EXP_RESET_OUT")
	)
	(segment
		(start 84.7852 -127.1524)
		(end 83.6422 -128.2954)
		(width 0.127)
		(layer "In5.Cu")
		(net "BMC_TO_EXP_RESET_OUT")
	)
	(segment
		(start 76.361036 -129.5146)
		(end 70.9422 -129.5146)
		(width 0.127)
		(layer "In5.Cu")
		(net "BMC_TO_EXP_RESET_OUT")
	)
	(segment
		(start 54.736492 -143.006826)
		(end 56.566054 -143.006826)
		(width 0.127)
		(layer "In5.Cu")
		(net "BMC_TO_EXP_RESET_OUT")
	)
	(segment
		(start 70.4977 -129.9591)
		(end 62.0903 -129.9591)
		(width 0.127)
		(layer "In5.Cu")
		(net "BMC_TO_EXP_RESET_OUT")
	)
	(segment
		(start 50.7619 -127.172466)
		(end 50.7619 -127.8382)
		(width 0.127)
		(layer "F.Cu")
		(net "SCC_RMT_FULL_PWR_EN")
	)
	(segment
		(start 49.7967 -127.8382)
		(end 50.7619 -127.8382)
		(width 0.127)
		(layer "F.Cu")
		(net "SCC_RMT_FULL_PWR_EN")
	)
	(segment
		(start 50.4952 -126.905766)
		(end 50.7619 -127.172466)
		(width 0.127)
		(layer "F.Cu")
		(net "SCC_RMT_FULL_PWR_EN")
	)
	(segment
		(start 50.4952 -124.418344)
		(end 50.4952 -126.905766)
		(width 0.127)
		(layer "F.Cu")
		(net "SCC_RMT_FULL_PWR_EN")
	)
	(segment
		(start 49.380394 -123.303538)
		(end 50.4952 -124.418344)
		(width 0.127)
		(layer "F.Cu")
		(net "SCC_RMT_FULL_PWR_EN")
	)
	(segment
		(start 49.657 -127.6985)
		(end 49.7967 -127.8382)
		(width 0.127)
		(layer "F.Cu")
		(net "SCC_RMT_FULL_PWR_EN")
	)
	(via
		(at 49.380394 -123.303538)
		(size 0.508)
		(drill 0.254)
		(layers "F.Cu" "B.Cu")
		(net "SCC_RMT_FULL_PWR_EN")
	)
	(via
		(at 86.3346 -115.316)
		(size 0.508)
		(drill 0.254)
		(layers "F.Cu" "B.Cu")
		(net "SCC_RMT_FULL_PWR_EN")
	)
	(segment
		(start 127.544068 -27.845512)
		(end 119.764556 -20.066)
		(width 0.127)
		(layer "In2.Cu")
		(net "SCC_RMT_FULL_PWR_EN")
	)
	(segment
		(start 87.5284 -99.914456)
		(end 88.8873 -101.273356)
		(width 0.127)
		(layer "In2.Cu")
		(net "SCC_RMT_FULL_PWR_EN")
	)
	(segment
		(start 86.487 -53.370226)
		(end 87.5792 -54.462426)
		(width 0.127)
		(layer "In2.Cu")
		(net "SCC_RMT_FULL_PWR_EN")
	)
	(segment
		(start 135.1788 -30.631638)
		(end 132.392674 -27.845512)
		(width 0.127)
		(layer "In2.Cu")
		(net "SCC_RMT_FULL_PWR_EN")
	)
	(segment
		(start 88.8873 -108.721144)
		(end 86.6267 -110.981744)
		(width 0.127)
		(layer "In2.Cu")
		(net "SCC_RMT_FULL_PWR_EN")
	)
	(segment
		(start 115.308888 -17.469104)
		(end 98.190304 -17.469104)
		(width 0.127)
		(layer "In2.Cu")
		(net "SCC_RMT_FULL_PWR_EN")
	)
	(segment
		(start 87.01532 -97.748344)
		(end 87.5284 -98.261424)
		(width 0.127)
		(layer "In2.Cu")
		(net "SCC_RMT_FULL_PWR_EN")
	)
	(segment
		(start 86.6267 -110.981744)
		(end 86.6267 -113.8047)
		(width 0.127)
		(layer "In2.Cu")
		(net "SCC_RMT_FULL_PWR_EN")
	)
	(segment
		(start 117.905784 -20.066)
		(end 115.308888 -17.469104)
		(width 0.127)
		(layer "In2.Cu")
		(net "SCC_RMT_FULL_PWR_EN")
	)
	(segment
		(start 135.899906 -45.39996)
		(end 135.1788 -44.678854)
		(width 0.127)
		(layer "In2.Cu")
		(net "SCC_RMT_FULL_PWR_EN")
	)
	(segment
		(start 84.819744 -9.688576)
		(end 83.706208 -10.802112)
		(width 0.127)
		(layer "In2.Cu")
		(net "SCC_RMT_FULL_PWR_EN")
	)
	(segment
		(start 83.706208 -10.802112)
		(end 83.706208 -31.908242)
		(width 0.127)
		(layer "In2.Cu")
		(net "SCC_RMT_FULL_PWR_EN")
	)
	(segment
		(start 119.764556 -20.066)
		(end 117.905784 -20.066)
		(width 0.127)
		(layer "In2.Cu")
		(net "SCC_RMT_FULL_PWR_EN")
	)
	(segment
		(start 87.5792 -54.462426)
		(end 87.5792 -94.157546)
		(width 0.127)
		(layer "In2.Cu")
		(net "SCC_RMT_FULL_PWR_EN")
	)
	(segment
		(start 86.6267 -113.8047)
		(end 86.3346 -114.0968)
		(width 0.127)
		(layer "In2.Cu")
		(net "SCC_RMT_FULL_PWR_EN")
	)
	(segment
		(start 88.8873 -101.273356)
		(end 88.8873 -108.721144)
		(width 0.127)
		(layer "In2.Cu")
		(net "SCC_RMT_FULL_PWR_EN")
	)
	(segment
		(start 95.173038 -14.451838)
		(end 95.173038 -11.179048)
		(width 0.127)
		(layer "In2.Cu")
		(net "SCC_RMT_FULL_PWR_EN")
	)
	(segment
		(start 98.190304 -17.469104)
		(end 95.173038 -14.451838)
		(width 0.127)
		(layer "In2.Cu")
		(net "SCC_RMT_FULL_PWR_EN")
	)
	(segment
		(start 87.5284 -98.261424)
		(end 87.5284 -99.914456)
		(width 0.127)
		(layer "In2.Cu")
		(net "SCC_RMT_FULL_PWR_EN")
	)
	(segment
		(start 95.173038 -11.179048)
		(end 93.682566 -9.688576)
		(width 0.127)
		(layer "In2.Cu")
		(net "SCC_RMT_FULL_PWR_EN")
	)
	(segment
		(start 93.682566 -9.688576)
		(end 84.819744 -9.688576)
		(width 0.127)
		(layer "In2.Cu")
		(net "SCC_RMT_FULL_PWR_EN")
	)
	(segment
		(start 86.487 -34.689034)
		(end 86.487 -53.370226)
		(width 0.127)
		(layer "In2.Cu")
		(net "SCC_RMT_FULL_PWR_EN")
	)
	(segment
		(start 135.1788 -44.678854)
		(end 135.1788 -30.631638)
		(width 0.127)
		(layer "In2.Cu")
		(net "SCC_RMT_FULL_PWR_EN")
	)
	(segment
		(start 86.3346 -114.0968)
		(end 86.3346 -115.316)
		(width 0.127)
		(layer "In2.Cu")
		(net "SCC_RMT_FULL_PWR_EN")
	)
	(segment
		(start 132.392674 -27.845512)
		(end 127.544068 -27.845512)
		(width 0.127)
		(layer "In2.Cu")
		(net "SCC_RMT_FULL_PWR_EN")
	)
	(segment
		(start 87.5792 -94.157546)
		(end 87.01532 -94.721426)
		(width 0.127)
		(layer "In2.Cu")
		(net "SCC_RMT_FULL_PWR_EN")
	)
	(segment
		(start 87.01532 -94.721426)
		(end 87.01532 -97.748344)
		(width 0.127)
		(layer "In2.Cu")
		(net "SCC_RMT_FULL_PWR_EN")
	)
	(segment
		(start 83.706208 -31.908242)
		(end 86.487 -34.689034)
		(width 0.127)
		(layer "In2.Cu")
		(net "SCC_RMT_FULL_PWR_EN")
	)
	(segment
		(start 72.968358 -118.2116)
		(end 66.528188 -118.2116)
		(width 0.127)
		(layer "In5.Cu")
		(net "SCC_RMT_FULL_PWR_EN")
	)
	(segment
		(start 86.3346 -115.316)
		(end 86.3346 -115.2652)
		(width 0.127)
		(layer "In5.Cu")
		(net "SCC_RMT_FULL_PWR_EN")
	)
	(segment
		(start 86.3346 -115.2652)
		(end 84.8614 -113.792)
		(width 0.127)
		(layer "In5.Cu")
		(net "SCC_RMT_FULL_PWR_EN")
	)
	(segment
		(start 77.387958 -113.792)
		(end 72.968358 -118.2116)
		(width 0.127)
		(layer "In5.Cu")
		(net "SCC_RMT_FULL_PWR_EN")
	)
	(segment
		(start 66.528188 -118.2116)
		(end 64.623188 -120.1166)
		(width 0.127)
		(layer "In5.Cu")
		(net "SCC_RMT_FULL_PWR_EN")
	)
	(segment
		(start 64.623188 -120.1166)
		(end 64.084708 -120.1166)
		(width 0.127)
		(layer "In5.Cu")
		(net "SCC_RMT_FULL_PWR_EN")
	)
	(segment
		(start 84.8614 -113.792)
		(end 77.387958 -113.792)
		(width 0.127)
		(layer "In5.Cu")
		(net "SCC_RMT_FULL_PWR_EN")
	)
	(segment
		(start 53.5432 -119.4562)
		(end 49.695862 -123.303538)
		(width 0.127)
		(layer "In5.Cu")
		(net "SCC_RMT_FULL_PWR_EN")
	)
	(segment
		(start 64.084454 -120.116854)
		(end 63.565786 -120.116854)
		(width 0.127)
		(layer "In5.Cu")
		(net "SCC_RMT_FULL_PWR_EN")
	)
	(segment
		(start 64.084708 -120.1166)
		(end 64.084454 -120.116854)
		(width 0.127)
		(layer "In5.Cu")
		(net "SCC_RMT_FULL_PWR_EN")
	)
	(segment
		(start 49.695862 -123.303538)
		(end 49.380394 -123.303538)
		(width 0.127)
		(layer "In5.Cu")
		(net "SCC_RMT_FULL_PWR_EN")
	)
	(segment
		(start 62.905132 -119.4562)
		(end 53.5432 -119.4562)
		(width 0.127)
		(layer "In5.Cu")
		(net "SCC_RMT_FULL_PWR_EN")
	)
	(segment
		(start 63.565786 -120.116854)
		(end 62.905132 -119.4562)
		(width 0.127)
		(layer "In5.Cu")
		(net "SCC_RMT_FULL_PWR_EN")
	)
	(segment
		(start 99.567746 -26.81351)
		(end 99.567746 -47.912782)
		(width 0.127)
		(layer "F.Cu")
		(net "SCC_LOC_FULL_PWR_EN")
	)
	(segment
		(start 106.695748 -22.509988)
		(end 103.871268 -22.509988)
		(width 0.127)
		(layer "F.Cu")
		(net "SCC_LOC_FULL_PWR_EN")
	)
	(segment
		(start 99.7458 -113.570766)
		(end 99.3648 -113.951766)
		(width 0.127)
		(layer "F.Cu")
		(net "SCC_LOC_FULL_PWR_EN")
	)
	(segment
		(start 99.567746 -47.912782)
		(end 99.7458 -48.090836)
		(width 0.127)
		(layer "F.Cu")
		(net "SCC_LOC_FULL_PWR_EN")
	)
	(segment
		(start 96.86798 -118.237)
		(end 97.0534 -118.05158)
		(width 0.127)
		(layer "F.Cu")
		(net "SCC_LOC_FULL_PWR_EN")
	)
	(segment
		(start 48.4886 -126.7714)
		(end 48.4886 -123.541536)
		(width 0.127)
		(layer "F.Cu")
		(net "SCC_LOC_FULL_PWR_EN")
	)
	(segment
		(start 110.4011 -18.804636)
		(end 106.695748 -22.509988)
		(width 0.127)
		(layer "F.Cu")
		(net "SCC_LOC_FULL_PWR_EN")
	)
	(segment
		(start 116.36756 -18.804636)
		(end 110.4011 -18.804636)
		(width 0.127)
		(layer "F.Cu")
		(net "SCC_LOC_FULL_PWR_EN")
	)
	(segment
		(start 135.899906 -44.000166)
		(end 136.471406 -43.428666)
		(width 0.127)
		(layer "F.Cu")
		(net "SCC_LOC_FULL_PWR_EN")
	)
	(segment
		(start 99.7458 -48.090836)
		(end 99.7458 -113.570766)
		(width 0.127)
		(layer "F.Cu")
		(net "SCC_LOC_FULL_PWR_EN")
	)
	(segment
		(start 97.0534 -118.05158)
		(end 97.0534 -117.942868)
		(width 0.127)
		(layer "F.Cu")
		(net "SCC_LOC_FULL_PWR_EN")
	)
	(segment
		(start 131.064254 -25.072086)
		(end 126.544832 -25.072086)
		(width 0.127)
		(layer "F.Cu")
		(net "SCC_LOC_FULL_PWR_EN")
	)
	(segment
		(start 99.3648 -113.9698)
		(end 99.3648 -113.951766)
		(width 0.127)
		(layer "F.Cu")
		(net "SCC_LOC_FULL_PWR_EN")
	)
	(segment
		(start 48.4886 -123.541536)
		(end 48.269144 -123.32208)
		(width 0.127)
		(layer "F.Cu")
		(net "SCC_LOC_FULL_PWR_EN")
	)
	(segment
		(start 136.471406 -43.428666)
		(end 136.471406 -30.479238)
		(width 0.127)
		(layer "F.Cu")
		(net "SCC_LOC_FULL_PWR_EN")
	)
	(segment
		(start 126.544832 -25.072086)
		(end 121.454418 -19.981672)
		(width 0.127)
		(layer "F.Cu")
		(net "SCC_LOC_FULL_PWR_EN")
	)
	(segment
		(start 48.6156 -126.8984)
		(end 48.4886 -126.7714)
		(width 0.127)
		(layer "F.Cu")
		(net "SCC_LOC_FULL_PWR_EN")
	)
	(segment
		(start 103.871268 -22.509988)
		(end 99.567746 -26.81351)
		(width 0.127)
		(layer "F.Cu")
		(net "SCC_LOC_FULL_PWR_EN")
	)
	(segment
		(start 97.0534 -117.942868)
		(end 97.409 -117.587268)
		(width 0.127)
		(layer "F.Cu")
		(net "SCC_LOC_FULL_PWR_EN")
	)
	(segment
		(start 117.544596 -19.981672)
		(end 116.36756 -18.804636)
		(width 0.127)
		(layer "F.Cu")
		(net "SCC_LOC_FULL_PWR_EN")
	)
	(segment
		(start 48.6156 -127.5969)
		(end 48.6156 -126.8984)
		(width 0.127)
		(layer "F.Cu")
		(net "SCC_LOC_FULL_PWR_EN")
	)
	(segment
		(start 99.3648 -113.951766)
		(end 99.346766 -113.951766)
		(width 0.127)
		(layer "F.Cu")
		(net "SCC_LOC_FULL_PWR_EN")
	)
	(segment
		(start 121.454418 -19.981672)
		(end 117.544596 -19.981672)
		(width 0.127)
		(layer "F.Cu")
		(net "SCC_LOC_FULL_PWR_EN")
	)
	(segment
		(start 97.409 -115.9256)
		(end 99.3648 -113.9698)
		(width 0.127)
		(layer "F.Cu")
		(net "SCC_LOC_FULL_PWR_EN")
	)
	(segment
		(start 97.409 -117.587268)
		(end 97.409 -115.9256)
		(width 0.127)
		(layer "F.Cu")
		(net "SCC_LOC_FULL_PWR_EN")
	)
	(segment
		(start 136.471406 -30.479238)
		(end 131.064254 -25.072086)
		(width 0.127)
		(layer "F.Cu")
		(net "SCC_LOC_FULL_PWR_EN")
	)
	(via
		(at 99.346766 -113.951766)
		(size 0.6604)
		(drill 0.3302)
		(layers "F.Cu" "B.Cu")
		(net "SCC_LOC_FULL_PWR_EN")
	)
	(via
		(at 96.86798 -118.237)
		(size 0.508)
		(drill 0.254)
		(layers "F.Cu" "B.Cu")
		(net "SCC_LOC_FULL_PWR_EN")
	)
	(via
		(at 48.269144 -123.32208)
		(size 0.508)
		(drill 0.254)
		(layers "F.Cu" "B.Cu")
		(net "SCC_LOC_FULL_PWR_EN")
	)
	(segment
		(start 48.8442 -124.4727)
		(end 48.8442 -123.897136)
		(width 0.127)
		(layer "B.Cu")
		(net "SCC_LOC_FULL_PWR_EN")
	)
	(segment
		(start 48.8442 -123.897136)
		(end 48.269144 -123.32208)
		(width 0.127)
		(layer "B.Cu")
		(net "SCC_LOC_FULL_PWR_EN")
	)
	(segment
		(start 66.3702 -117.8306)
		(end 64.4652 -119.7356)
		(width 0.127)
		(layer "In5.Cu")
		(net "SCC_LOC_FULL_PWR_EN")
	)
	(segment
		(start 95.2754 -117.0178)
		(end 88.7222 -117.0178)
		(width 0.127)
		(layer "In5.Cu")
		(net "SCC_LOC_FULL_PWR_EN")
	)
	(segment
		(start 52.516024 -119.0752)
		(end 48.269144 -123.32208)
		(width 0.127)
		(layer "In5.Cu")
		(net "SCC_LOC_FULL_PWR_EN")
	)
	(segment
		(start 64.4652 -119.7356)
		(end 63.72352 -119.7356)
		(width 0.127)
		(layer "In5.Cu")
		(net "SCC_LOC_FULL_PWR_EN")
	)
	(segment
		(start 63.72352 -119.7356)
		(end 63.06312 -119.0752)
		(width 0.127)
		(layer "In5.Cu")
		(net "SCC_LOC_FULL_PWR_EN")
	)
	(segment
		(start 96.4946 -118.237)
		(end 95.2754 -117.0178)
		(width 0.127)
		(layer "In5.Cu")
		(net "SCC_LOC_FULL_PWR_EN")
	)
	(segment
		(start 96.86798 -118.237)
		(end 96.4946 -118.237)
		(width 0.127)
		(layer "In5.Cu")
		(net "SCC_LOC_FULL_PWR_EN")
	)
	(segment
		(start 77.22997 -113.411)
		(end 72.81037 -117.8306)
		(width 0.127)
		(layer "In5.Cu")
		(net "SCC_LOC_FULL_PWR_EN")
	)
	(segment
		(start 85.1154 -113.411)
		(end 77.22997 -113.411)
		(width 0.127)
		(layer "In5.Cu")
		(net "SCC_LOC_FULL_PWR_EN")
	)
	(segment
		(start 88.7222 -117.0178)
		(end 85.1154 -113.411)
		(width 0.127)
		(layer "In5.Cu")
		(net "SCC_LOC_FULL_PWR_EN")
	)
	(segment
		(start 72.81037 -117.8306)
		(end 66.3702 -117.8306)
		(width 0.127)
		(layer "In5.Cu")
		(net "SCC_LOC_FULL_PWR_EN")
	)
	(segment
		(start 63.06312 -119.0752)
		(end 52.516024 -119.0752)
		(width 0.127)
		(layer "In5.Cu")
		(net "SCC_LOC_FULL_PWR_EN")
	)
	(segment
		(start 88.369394 -62.739016)
		(end 87.574628 -62.739016)
		(width 0.127)
		(layer "F.Cu")
		(net "NCSI_TXEN_R")
	)
	(segment
		(start 82.268822 -60.950094)
		(end 82.369406 -60.84951)
		(width 0.127)
		(layer "F.Cu")
		(net "NCSI_TXEN_R")
	)
	(segment
		(start 85.685122 -60.84951)
		(end 86.204298 -61.368686)
		(width 0.127)
		(layer "F.Cu")
		(net "NCSI_TXEN_R")
	)
	(segment
		(start 79.925164 -60.950094)
		(end 82.268822 -60.950094)
		(width 0.127)
		(layer "F.Cu")
		(net "NCSI_TXEN_R")
	)
	(segment
		(start 87.574628 -62.739016)
		(end 86.204298 -61.368686)
		(width 0.127)
		(layer "F.Cu")
		(net "NCSI_TXEN_R")
	)
	(segment
		(start 82.369406 -60.84951)
		(end 85.685122 -60.84951)
		(width 0.127)
		(layer "F.Cu")
		(net "NCSI_TXEN_R")
	)
	(via
		(at 86.204298 -61.368686)
		(size 0.6604)
		(drill 0.3302)
		(layers "F.Cu" "B.Cu")
		(net "NCSI_TXEN_R")
	)
	(segment
		(start 53.299614 -147.40001)
		(end 53.299614 -147.399756)
		(width 0.127)
		(layer "F.Cu")
		(net "NCSI_TXEN")
	)
	(segment
		(start 92.648786 -88.940386)
		(end 92.648786 -65.442846)
		(width 0.127)
		(layer "F.Cu")
		(net "NCSI_TXEN")
	)
	(segment
		(start 92.036646 -64.830706)
		(end 92.035884 -64.830706)
		(width 0.127)
		(layer "F.Cu")
		(net "NCSI_TXEN")
	)
	(segment
		(start 92.648786 -65.442846)
		(end 92.036646 -64.830706)
		(width 0.127)
		(layer "F.Cu")
		(net "NCSI_TXEN")
	)
	(segment
		(start 95.8342 -92.1258)
		(end 92.648786 -88.940386)
		(width 0.127)
		(layer "F.Cu")
		(net "NCSI_TXEN")
	)
	(segment
		(start 92.035884 -64.830706)
		(end 89.944194 -62.739016)
		(width 0.127)
		(layer "F.Cu")
		(net "NCSI_TXEN")
	)
	(segment
		(start 89.944194 -62.739016)
		(end 89.258394 -62.739016)
		(width 0.127)
		(layer "F.Cu")
		(net "NCSI_TXEN")
	)
	(segment
		(start 53.299614 -147.399756)
		(end 52.899818 -146.99996)
		(width 0.127)
		(layer "F.Cu")
		(net "NCSI_TXEN")
	)
	(via
		(at 53.299614 -147.40001)
		(size 0.4572)
		(drill 0.2032)
		(layers "F.Cu" "B.Cu")
		(net "NCSI_TXEN")
	)
	(via
		(at 74.66838 -143.491458)
		(size 0.508)
		(drill 0.254)
		(layers "F.Cu" "B.Cu")
		(net "NCSI_TXEN")
	)
	(via
		(at 92.036646 -64.830706)
		(size 0.6604)
		(drill 0.3302)
		(layers "F.Cu" "B.Cu")
		(net "NCSI_TXEN")
	)
	(via
		(at 97.314004 -143.551148)
		(size 0.508)
		(drill 0.254)
		(layers "F.Cu" "B.Cu")
		(net "NCSI_TXEN")
	)
	(via
		(at 95.8342 -92.1258)
		(size 0.508)
		(drill 0.254)
		(layers "F.Cu" "B.Cu")
		(net "NCSI_TXEN")
	)
	(segment
		(start 75.32878 -142.831058)
		(end 74.66838 -143.491458)
		(width 0.127)
		(layer "B.Cu")
		(net "NCSI_TXEN")
	)
	(segment
		(start 75.35672 -141.303756)
		(end 75.35672 -142.497302)
		(width 0.127)
		(layer "B.Cu")
		(net "NCSI_TXEN")
	)
	(segment
		(start 75.32878 -142.525242)
		(end 75.32878 -142.831058)
		(width 0.127)
		(layer "B.Cu")
		(net "NCSI_TXEN")
	)
	(segment
		(start 75.35672 -142.497302)
		(end 75.32878 -142.525242)
		(width 0.127)
		(layer "B.Cu")
		(net "NCSI_TXEN")
	)
	(segment
		(start 96.841818 -136.369552)
		(end 96.841818 -126.189486)
		(width 0.127)
		(layer "In2.Cu")
		(net "NCSI_TXEN")
	)
	(segment
		(start 98.8695 -141.995652)
		(end 98.8695 -138.397234)
		(width 0.127)
		(layer "In2.Cu")
		(net "NCSI_TXEN")
	)
	(segment
		(start 95.211138 -113.491518)
		(end 95.211138 -112.941862)
		(width 0.127)
		(layer "In2.Cu")
		(net "NCSI_TXEN")
	)
	(segment
		(start 96.3422 -111.8108)
		(end 96.3422 -92.6338)
		(width 0.127)
		(layer "In2.Cu")
		(net "NCSI_TXEN")
	)
	(segment
		(start 95.211138 -112.941862)
		(end 96.3422 -111.8108)
		(width 0.127)
		(layer "In2.Cu")
		(net "NCSI_TXEN")
	)
	(segment
		(start 95.47352 -113.7539)
		(end 95.211138 -113.491518)
		(width 0.127)
		(layer "In2.Cu")
		(net "NCSI_TXEN")
	)
	(segment
		(start 96.841818 -126.189486)
		(end 95.909892 -125.25756)
		(width 0.127)
		(layer "In2.Cu")
		(net "NCSI_TXEN")
	)
	(segment
		(start 97.314004 -143.551148)
		(end 98.8695 -141.995652)
		(width 0.127)
		(layer "In2.Cu")
		(net "NCSI_TXEN")
	)
	(segment
		(start 95.47352 -114.53368)
		(end 95.47352 -113.7539)
		(width 0.127)
		(layer "In2.Cu")
		(net "NCSI_TXEN")
	)
	(segment
		(start 95.358204 -114.648996)
		(end 95.47352 -114.53368)
		(width 0.127)
		(layer "In2.Cu")
		(net "NCSI_TXEN")
	)
	(segment
		(start 95.909892 -122.089926)
		(end 95.358204 -121.538238)
		(width 0.127)
		(layer "In2.Cu")
		(net "NCSI_TXEN")
	)
	(segment
		(start 98.8695 -138.397234)
		(end 96.841818 -136.369552)
		(width 0.127)
		(layer "In2.Cu")
		(net "NCSI_TXEN")
	)
	(segment
		(start 95.358204 -121.538238)
		(end 95.358204 -114.648996)
		(width 0.127)
		(layer "In2.Cu")
		(net "NCSI_TXEN")
	)
	(segment
		(start 96.3422 -92.6338)
		(end 95.8342 -92.1258)
		(width 0.127)
		(layer "In2.Cu")
		(net "NCSI_TXEN")
	)
	(segment
		(start 95.909892 -125.25756)
		(end 95.909892 -122.089926)
		(width 0.127)
		(layer "In2.Cu")
		(net "NCSI_TXEN")
	)
	(segment
		(start 56.13654 -147.79371)
		(end 58.05805 -145.8722)
		(width 0.127)
		(layer "In5.Cu")
		(net "NCSI_TXEN")
	)
	(segment
		(start 75.680316 -143.491458)
		(end 76.486258 -144.2974)
		(width 0.127)
		(layer "In5.Cu")
		(net "NCSI_TXEN")
	)
	(segment
		(start 59.8424 -145.8722)
		(end 60.1218 -145.5928)
		(width 0.127)
		(layer "In5.Cu")
		(net "NCSI_TXEN")
	)
	(segment
		(start 78.8924 -144.2974)
		(end 79.3496 -144.7546)
		(width 0.127)
		(layer "In5.Cu")
		(net "NCSI_TXEN")
	)
	(segment
		(start 74.66838 -143.491458)
		(end 75.680316 -143.491458)
		(width 0.127)
		(layer "In5.Cu")
		(net "NCSI_TXEN")
	)
	(segment
		(start 97.314004 -143.557244)
		(end 97.314004 -143.551148)
		(width 0.127)
		(layer "In5.Cu")
		(net "NCSI_TXEN")
	)
	(segment
		(start 60.1218 -145.5928)
		(end 66.616834 -145.5928)
		(width 0.127)
		(layer "In5.Cu")
		(net "NCSI_TXEN")
	)
	(segment
		(start 87.85098 -144.47266)
		(end 93.2688 -144.47266)
		(width 0.127)
		(layer "In5.Cu")
		(net "NCSI_TXEN")
	)
	(segment
		(start 74.05751 -144.102328)
		(end 74.66838 -143.491458)
		(width 0.127)
		(layer "In5.Cu")
		(net "NCSI_TXEN")
	)
	(segment
		(start 87.56904 -144.7546)
		(end 87.85098 -144.47266)
		(width 0.127)
		(layer "In5.Cu")
		(net "NCSI_TXEN")
	)
	(segment
		(start 93.2688 -144.47266)
		(end 93.378528 -144.582388)
		(width 0.127)
		(layer "In5.Cu")
		(net "NCSI_TXEN")
	)
	(segment
		(start 96.28886 -144.582388)
		(end 97.314004 -143.557244)
		(width 0.127)
		(layer "In5.Cu")
		(net "NCSI_TXEN")
	)
	(segment
		(start 76.486258 -144.2974)
		(end 78.8924 -144.2974)
		(width 0.127)
		(layer "In5.Cu")
		(net "NCSI_TXEN")
	)
	(segment
		(start 58.05805 -145.8722)
		(end 59.8424 -145.8722)
		(width 0.127)
		(layer "In5.Cu")
		(net "NCSI_TXEN")
	)
	(segment
		(start 66.616834 -145.5928)
		(end 66.858134 -145.3515)
		(width 0.127)
		(layer "In5.Cu")
		(net "NCSI_TXEN")
	)
	(segment
		(start 69.765672 -144.102328)
		(end 74.05751 -144.102328)
		(width 0.127)
		(layer "In5.Cu")
		(net "NCSI_TXEN")
	)
	(segment
		(start 66.858134 -145.3515)
		(end 68.5165 -145.3515)
		(width 0.127)
		(layer "In5.Cu")
		(net "NCSI_TXEN")
	)
	(segment
		(start 68.5165 -145.3515)
		(end 69.765672 -144.102328)
		(width 0.127)
		(layer "In5.Cu")
		(net "NCSI_TXEN")
	)
	(segment
		(start 53.693314 -147.79371)
		(end 56.13654 -147.79371)
		(width 0.127)
		(layer "In5.Cu")
		(net "NCSI_TXEN")
	)
	(segment
		(start 79.3496 -144.7546)
		(end 87.56904 -144.7546)
		(width 0.127)
		(layer "In5.Cu")
		(net "NCSI_TXEN")
	)
	(segment
		(start 93.378528 -144.582388)
		(end 96.28886 -144.582388)
		(width 0.127)
		(layer "In5.Cu")
		(net "NCSI_TXEN")
	)
	(segment
		(start 53.299614 -147.40001)
		(end 53.693314 -147.79371)
		(width 0.127)
		(layer "In5.Cu")
		(net "NCSI_TXEN")
	)
	(segment
		(start 59.658758 -153.9748)
		(end 60.6806 -154.996642)
		(width 0.127)
		(layer "F.Cu")
		(net "NCSI_TXD1_R")
	)
	(segment
		(start 60.6806 -154.996642)
		(end 60.6806 -155.447492)
		(width 0.127)
		(layer "F.Cu")
		(net "NCSI_TXD1_R")
	)
	(segment
		(start 58.847482 -153.496518)
		(end 59.325764 -153.9748)
		(width 0.127)
		(layer "F.Cu")
		(net "NCSI_TXD1_R")
	)
	(segment
		(start 60.950602 -155.717494)
		(end 61.024008 -155.7909)
		(width 0.127)
		(layer "F.Cu")
		(net "NCSI_TXD1_R")
	)
	(segment
		(start 61.024008 -155.7909)
		(end 61.9506 -155.7909)
		(width 0.127)
		(layer "F.Cu")
		(net "NCSI_TXD1_R")
	)
	(segment
		(start 59.325764 -153.9748)
		(end 59.658758 -153.9748)
		(width 0.127)
		(layer "F.Cu")
		(net "NCSI_TXD1_R")
	)
	(segment
		(start 60.6806 -155.447492)
		(end 60.950602 -155.717494)
		(width 0.127)
		(layer "F.Cu")
		(net "NCSI_TXD1_R")
	)
	(segment
		(start 58.847482 -152.938988)
		(end 58.847482 -153.496518)
		(width 0.127)
		(layer "F.Cu")
		(net "NCSI_TXD1_R")
	)
	(segment
		(start 56.099964 -150.199852)
		(end 56.108346 -150.199852)
		(width 0.127)
		(layer "F.Cu")
		(net "NCSI_TXD1_R")
	)
	(segment
		(start 56.108346 -150.199852)
		(end 58.847482 -152.938988)
		(width 0.127)
		(layer "F.Cu")
		(net "NCSI_TXD1_R")
	)
	(via
		(at 60.950602 -155.717494)
		(size 0.6604)
		(drill 0.3302)
		(layers "F.Cu" "B.Cu")
		(net "NCSI_TXD1_R")
	)
	(segment
		(start 65.786 -156.718)
		(end 65.786 -156.590238)
		(width 0.127)
		(layer "F.Cu")
		(net "NCSI_TXD1")
	)
	(segment
		(start 65.786 -156.590238)
		(end 64.986662 -155.7909)
		(width 0.127)
		(layer "F.Cu")
		(net "NCSI_TXD1")
	)
	(segment
		(start 84.90204 -64.97828)
		(end 85.390482 -64.97828)
		(width 0.127)
		(layer "F.Cu")
		(net "NCSI_TXD1")
	)
	(segment
		(start 88.250268 -66.557144)
		(end 89.5096 -67.816476)
		(width 0.127)
		(layer "F.Cu")
		(net "NCSI_TXD1")
	)
	(segment
		(start 64.986662 -155.7909)
		(end 63.9826 -155.7909)
		(width 0.127)
		(layer "F.Cu")
		(net "NCSI_TXD1")
	)
	(segment
		(start 75.475084 -64.950086)
		(end 77.480668 -64.950086)
		(width 0.127)
		(layer "F.Cu")
		(net "NCSI_TXD1")
	)
	(segment
		(start 85.390482 -64.97828)
		(end 86.969346 -66.557144)
		(width 0.127)
		(layer "F.Cu")
		(net "NCSI_TXD1")
	)
	(segment
		(start 63.9826 -155.7909)
		(end 63.0936 -156.6799)
		(width 0.127)
		(layer "F.Cu")
		(net "NCSI_TXD1")
	)
	(segment
		(start 63.0936 -156.6799)
		(end 62.9666 -156.6799)
		(width 0.127)
		(layer "F.Cu")
		(net "NCSI_TXD1")
	)
	(segment
		(start 86.969346 -66.557144)
		(end 88.250268 -66.557144)
		(width 0.127)
		(layer "F.Cu")
		(net "NCSI_TXD1")
	)
	(segment
		(start 77.480668 -64.950086)
		(end 77.828648 -64.602106)
		(width 0.127)
		(layer "F.Cu")
		(net "NCSI_TXD1")
	)
	(segment
		(start 91.245182 -96.318832)
		(end 92.380054 -96.318832)
		(width 0.127)
		(layer "F.Cu")
		(net "NCSI_TXD1")
	)
	(segment
		(start 62.9666 -156.6799)
		(end 61.9506 -156.6799)
		(width 0.127)
		(layer "F.Cu")
		(net "NCSI_TXD1")
	)
	(segment
		(start 89.5096 -67.816476)
		(end 89.5096 -94.58325)
		(width 0.127)
		(layer "F.Cu")
		(net "NCSI_TXD1")
	)
	(segment
		(start 89.5096 -94.58325)
		(end 91.245182 -96.318832)
		(width 0.127)
		(layer "F.Cu")
		(net "NCSI_TXD1")
	)
	(via
		(at 92.380054 -96.318832)
		(size 0.508)
		(drill 0.254)
		(layers "F.Cu" "B.Cu")
		(net "NCSI_TXD1")
	)
	(via
		(at 77.828648 -64.602106)
		(size 0.508)
		(drill 0.254)
		(layers "F.Cu" "B.Cu")
		(net "NCSI_TXD1")
	)
	(via
		(at 82.4484 -64.1604)
		(size 0.6096)
		(drill 0.3048)
		(layers "F.Cu" "B.Cu")
		(net "NCSI_TXD1")
	)
	(via
		(at 63.36411 -116.332)
		(size 0.508)
		(drill 0.254)
		(layers "F.Cu" "B.Cu")
		(net "NCSI_TXD1")
	)
	(via
		(at 65.786 -156.718)
		(size 0.508)
		(drill 0.254)
		(layers "F.Cu" "B.Cu")
		(net "NCSI_TXD1")
	)
	(via
		(at 84.90204 -64.97828)
		(size 0.508)
		(drill 0.254)
		(layers "F.Cu" "B.Cu")
		(net "NCSI_TXD1")
	)
	(segment
		(start 84.90204 -64.97828)
		(end 83.26628 -64.97828)
		(width 0.127)
		(layer "B.Cu")
		(net "NCSI_TXD1")
	)
	(segment
		(start 64.153034 -114.681)
		(end 63.36411 -115.469924)
		(width 0.127)
		(layer "B.Cu")
		(net "NCSI_TXD1")
	)
	(segment
		(start 91.8718 -106.058716)
		(end 84.763102 -113.167414)
		(width 0.127)
		(layer "B.Cu")
		(net "NCSI_TXD1")
	)
	(segment
		(start 65.5828 -114.681)
		(end 64.153034 -114.681)
		(width 0.127)
		(layer "B.Cu")
		(net "NCSI_TXD1")
	)
	(segment
		(start 82.423 -64.135)
		(end 78.295754 -64.135)
		(width 0.127)
		(layer "B.Cu")
		(net "NCSI_TXD1")
	)
	(segment
		(start 84.763102 -113.167414)
		(end 76.135484 -113.167414)
		(width 0.127)
		(layer "B.Cu")
		(net "NCSI_TXD1")
	)
	(segment
		(start 92.380054 -96.318832)
		(end 91.8718 -96.827086)
		(width 0.127)
		(layer "B.Cu")
		(net "NCSI_TXD1")
	)
	(segment
		(start 83.26628 -64.97828)
		(end 82.4484 -64.1604)
		(width 0.127)
		(layer "B.Cu")
		(net "NCSI_TXD1")
	)
	(segment
		(start 73.732898 -115.57)
		(end 66.4718 -115.57)
		(width 0.127)
		(layer "B.Cu")
		(net "NCSI_TXD1")
	)
	(segment
		(start 78.295754 -64.135)
		(end 77.828648 -64.602106)
		(width 0.127)
		(layer "B.Cu")
		(net "NCSI_TXD1")
	)
	(segment
		(start 76.135484 -113.167414)
		(end 73.732898 -115.57)
		(width 0.127)
		(layer "B.Cu")
		(net "NCSI_TXD1")
	)
	(segment
		(start 66.4718 -115.57)
		(end 65.5828 -114.681)
		(width 0.127)
		(layer "B.Cu")
		(net "NCSI_TXD1")
	)
	(segment
		(start 82.4484 -64.1604)
		(end 82.423 -64.135)
		(width 0.127)
		(layer "B.Cu")
		(net "NCSI_TXD1")
	)
	(segment
		(start 63.36411 -115.469924)
		(end 63.36411 -116.332)
		(width 0.127)
		(layer "B.Cu")
		(net "NCSI_TXD1")
	)
	(segment
		(start 91.8718 -96.827086)
		(end 91.8718 -106.058716)
		(width 0.127)
		(layer "B.Cu")
		(net "NCSI_TXD1")
	)
	(segment
		(start 60.578492 -136.869678)
		(end 60.578492 -137.686542)
		(width 0.127)
		(layer "In2.Cu")
		(net "NCSI_TXD1")
	)
	(segment
		(start 60.578492 -137.686542)
		(end 61.76645 -138.8745)
		(width 0.127)
		(layer "In2.Cu")
		(net "NCSI_TXD1")
	)
	(segment
		(start 61.76645 -138.8745)
		(end 61.840618 -138.8745)
		(width 0.127)
		(layer "In2.Cu")
		(net "NCSI_TXD1")
	)
	(segment
		(start 60.275216 -134.475474)
		(end 60.275216 -136.566402)
		(width 0.127)
		(layer "In2.Cu")
		(net "NCSI_TXD1")
	)
	(segment
		(start 63.6524 -131.09829)
		(end 60.275216 -134.475474)
		(width 0.127)
		(layer "In2.Cu")
		(net "NCSI_TXD1")
	)
	(segment
		(start 63.151004 -117.650768)
		(end 63.151004 -127.913638)
		(width 0.127)
		(layer "In2.Cu")
		(net "NCSI_TXD1")
	)
	(segment
		(start 62.1157 -139.149582)
		(end 62.1157 -139.539218)
		(width 0.127)
		(layer "In2.Cu")
		(net "NCSI_TXD1")
	)
	(segment
		(start 62.1157 -139.539218)
		(end 61.8617 -139.793218)
		(width 0.127)
		(layer "In2.Cu")
		(net "NCSI_TXD1")
	)
	(segment
		(start 63.36411 -117.437662)
		(end 63.151004 -117.650768)
		(width 0.127)
		(layer "In2.Cu")
		(net "NCSI_TXD1")
	)
	(segment
		(start 63.1571 -154.0891)
		(end 65.786 -156.718)
		(width 0.127)
		(layer "In2.Cu")
		(net "NCSI_TXD1")
	)
	(segment
		(start 61.840618 -138.8745)
		(end 62.1157 -139.149582)
		(width 0.127)
		(layer "In2.Cu")
		(net "NCSI_TXD1")
	)
	(segment
		(start 63.6524 -128.415034)
		(end 63.6524 -131.09829)
		(width 0.127)
		(layer "In2.Cu")
		(net "NCSI_TXD1")
	)
	(segment
		(start 61.8617 -148.1709)
		(end 63.1571 -149.4663)
		(width 0.127)
		(layer "In2.Cu")
		(net "NCSI_TXD1")
	)
	(segment
		(start 63.36411 -116.332)
		(end 63.36411 -117.437662)
		(width 0.127)
		(layer "In2.Cu")
		(net "NCSI_TXD1")
	)
	(segment
		(start 61.8617 -139.793218)
		(end 61.8617 -148.1709)
		(width 0.127)
		(layer "In2.Cu")
		(net "NCSI_TXD1")
	)
	(segment
		(start 63.1571 -149.4663)
		(end 63.1571 -154.0891)
		(width 0.127)
		(layer "In2.Cu")
		(net "NCSI_TXD1")
	)
	(segment
		(start 63.151004 -127.913638)
		(end 63.6524 -128.415034)
		(width 0.127)
		(layer "In2.Cu")
		(net "NCSI_TXD1")
	)
	(segment
		(start 60.275216 -136.566402)
		(end 60.578492 -136.869678)
		(width 0.127)
		(layer "In2.Cu")
		(net "NCSI_TXD1")
	)
	(segment
		(start 52.099972 -146.99996)
		(end 52.099972 -147.000214)
		(width 0.127)
		(layer "F.Cu")
		(net "NCSI_TXD0_R")
	)
	(segment
		(start 52.099972 -147.000214)
		(end 52.499768 -147.40001)
		(width 0.127)
		(layer "F.Cu")
		(net "NCSI_TXD0_R")
	)
	(via
		(at 52.499768 -147.40001)
		(size 0.4572)
		(drill 0.2032)
		(layers "F.Cu" "B.Cu")
		(net "NCSI_TXD0_R")
	)
	(via
		(at 68.1228 -146.9898)
		(size 0.508)
		(drill 0.254)
		(layers "F.Cu" "B.Cu")
		(net "NCSI_TXD0_R")
	)
	(via
		(at 67.2465 -147.3835)
		(size 0.6096)
		(drill 0.3048)
		(layers "F.Cu" "B.Cu")
		(net "NCSI_TXD0_R")
	)
	(segment
		(start 67.2465 -147.3835)
		(end 67.2465 -148.336)
		(width 0.127)
		(layer "B.Cu")
		(net "NCSI_TXD0_R")
	)
	(segment
		(start 67.6402 -146.9898)
		(end 67.2465 -147.3835)
		(width 0.127)
		(layer "B.Cu")
		(net "NCSI_TXD0_R")
	)
	(segment
		(start 68.1228 -146.9898)
		(end 67.6402 -146.9898)
		(width 0.127)
		(layer "B.Cu")
		(net "NCSI_TXD0_R")
	)
	(segment
		(start 67.2465 -148.336)
		(end 67.3735 -148.463)
		(width 0.127)
		(layer "B.Cu")
		(net "NCSI_TXD0_R")
	)
	(segment
		(start 66.480182 -146.675348)
		(end 64.88176 -146.675348)
		(width 0.127)
		(layer "In5.Cu")
		(net "NCSI_TXD0_R")
	)
	(segment
		(start 64.472312 -146.2659)
		(end 59.558936 -146.2659)
		(width 0.127)
		(layer "In5.Cu")
		(net "NCSI_TXD0_R")
	)
	(segment
		(start 55.904892 -148.59381)
		(end 53.1368 -148.59381)
		(width 0.127)
		(layer "In5.Cu")
		(net "NCSI_TXD0_R")
	)
	(segment
		(start 52.893468 -147.79371)
		(end 52.499768 -147.40001)
		(width 0.127)
		(layer "In5.Cu")
		(net "NCSI_TXD0_R")
	)
	(segment
		(start 53.1368 -148.59381)
		(end 52.893468 -148.350478)
		(width 0.127)
		(layer "In5.Cu")
		(net "NCSI_TXD0_R")
	)
	(segment
		(start 64.88176 -146.675348)
		(end 64.472312 -146.2659)
		(width 0.127)
		(layer "In5.Cu")
		(net "NCSI_TXD0_R")
	)
	(segment
		(start 57.572402 -146.9263)
		(end 55.904892 -148.59381)
		(width 0.127)
		(layer "In5.Cu")
		(net "NCSI_TXD0_R")
	)
	(segment
		(start 59.558936 -146.2659)
		(end 58.898536 -146.9263)
		(width 0.127)
		(layer "In5.Cu")
		(net "NCSI_TXD0_R")
	)
	(segment
		(start 66.794634 -146.9898)
		(end 66.480182 -146.675348)
		(width 0.127)
		(layer "In5.Cu")
		(net "NCSI_TXD0_R")
	)
	(segment
		(start 58.898536 -146.9263)
		(end 57.572402 -146.9263)
		(width 0.127)
		(layer "In5.Cu")
		(net "NCSI_TXD0_R")
	)
	(segment
		(start 52.893468 -148.350478)
		(end 52.893468 -147.79371)
		(width 0.127)
		(layer "In5.Cu")
		(net "NCSI_TXD0_R")
	)
	(segment
		(start 68.1228 -146.9898)
		(end 66.794634 -146.9898)
		(width 0.127)
		(layer "In5.Cu")
		(net "NCSI_TXD0_R")
	)
	(segment
		(start 88.460834 -66.049144)
		(end 90.0176 -67.60591)
		(width 0.127)
		(layer "F.Cu")
		(net "NCSI_TXD0")
	)
	(segment
		(start 87.179912 -66.049144)
		(end 88.460834 -66.049144)
		(width 0.127)
		(layer "F.Cu")
		(net "NCSI_TXD0")
	)
	(segment
		(start 77.19441 -64.149986)
		(end 77.564742 -63.779654)
		(width 0.127)
		(layer "F.Cu")
		(net "NCSI_TXD0")
	)
	(segment
		(start 91.245436 -95.455486)
		(end 92.350844 -95.455486)
		(width 0.127)
		(layer "F.Cu")
		(net "NCSI_TXD0")
	)
	(segment
		(start 90.0176 -94.22765)
		(end 91.245436 -95.455486)
		(width 0.127)
		(layer "F.Cu")
		(net "NCSI_TXD0")
	)
	(segment
		(start 90.0176 -67.60591)
		(end 90.0176 -94.22765)
		(width 0.127)
		(layer "F.Cu")
		(net "NCSI_TXD0")
	)
	(segment
		(start 85.23478 -64.104012)
		(end 87.179912 -66.049144)
		(width 0.127)
		(layer "F.Cu")
		(net "NCSI_TXD0")
	)
	(segment
		(start 84.907628 -64.104012)
		(end 85.23478 -64.104012)
		(width 0.127)
		(layer "F.Cu")
		(net "NCSI_TXD0")
	)
	(segment
		(start 75.475084 -64.149986)
		(end 77.19441 -64.149986)
		(width 0.127)
		(layer "F.Cu")
		(net "NCSI_TXD0")
	)
	(via
		(at 81.7626 -63.3476)
		(size 0.6096)
		(drill 0.3048)
		(layers "F.Cu" "B.Cu")
		(net "NCSI_TXD0")
	)
	(via
		(at 69.347588 -147.510754)
		(size 0.508)
		(drill 0.254)
		(layers "F.Cu" "B.Cu")
		(net "NCSI_TXD0")
	)
	(via
		(at 69.4436 -114.2238)
		(size 0.508)
		(drill 0.254)
		(layers "F.Cu" "B.Cu")
		(net "NCSI_TXD0")
	)
	(via
		(at 77.564742 -63.779654)
		(size 0.508)
		(drill 0.254)
		(layers "F.Cu" "B.Cu")
		(net "NCSI_TXD0")
	)
	(via
		(at 92.350844 -95.455486)
		(size 0.508)
		(drill 0.254)
		(layers "F.Cu" "B.Cu")
		(net "NCSI_TXD0")
	)
	(via
		(at 84.907628 -64.104012)
		(size 0.508)
		(drill 0.254)
		(layers "F.Cu" "B.Cu")
		(net "NCSI_TXD0")
	)
	(segment
		(start 81.7372 -63.3476)
		(end 81.7626 -63.3476)
		(width 0.127)
		(layer "B.Cu")
		(net "NCSI_TXD0")
	)
	(segment
		(start 77.564742 -63.779654)
		(end 77.793596 -63.5508)
		(width 0.127)
		(layer "B.Cu")
		(net "NCSI_TXD0")
	)
	(segment
		(start 84.552536 -112.659414)
		(end 91.2368 -105.97515)
		(width 0.127)
		(layer "B.Cu")
		(net "NCSI_TXD0")
	)
	(segment
		(start 73.522332 -115.062)
		(end 75.924918 -112.659414)
		(width 0.127)
		(layer "B.Cu")
		(net "NCSI_TXD0")
	)
	(segment
		(start 82.931 -63.3476)
		(end 83.687412 -64.104012)
		(width 0.127)
		(layer "B.Cu")
		(net "NCSI_TXD0")
	)
	(segment
		(start 68.786248 -148.3995)
		(end 68.722748 -148.463)
		(width 0.127)
		(layer "B.Cu")
		(net "NCSI_TXD0")
	)
	(segment
		(start 68.722748 -148.463)
		(end 68.2625 -148.463)
		(width 0.127)
		(layer "B.Cu")
		(net "NCSI_TXD0")
	)
	(segment
		(start 81.7626 -63.3476)
		(end 82.931 -63.3476)
		(width 0.127)
		(layer "B.Cu")
		(net "NCSI_TXD0")
	)
	(segment
		(start 91.2368 -105.97515)
		(end 91.2368 -96.56953)
		(width 0.127)
		(layer "B.Cu")
		(net "NCSI_TXD0")
	)
	(segment
		(start 91.2368 -96.56953)
		(end 92.350844 -95.455486)
		(width 0.127)
		(layer "B.Cu")
		(net "NCSI_TXD0")
	)
	(segment
		(start 83.687412 -64.104012)
		(end 84.907628 -64.104012)
		(width 0.127)
		(layer "B.Cu")
		(net "NCSI_TXD0")
	)
	(segment
		(start 69.3166 -147.541742)
		(end 69.347588 -147.510754)
		(width 0.127)
		(layer "B.Cu")
		(net "NCSI_TXD0")
	)
	(segment
		(start 68.2625 -149.479)
		(end 68.2625 -148.463)
		(width 0.127)
		(layer "B.Cu")
		(net "NCSI_TXD0")
	)
	(segment
		(start 69.3166 -148.3995)
		(end 69.3166 -147.541742)
		(width 0.127)
		(layer "B.Cu")
		(net "NCSI_TXD0")
	)
	(segment
		(start 69.4436 -114.2238)
		(end 70.2818 -115.062)
		(width 0.127)
		(layer "B.Cu")
		(net "NCSI_TXD0")
	)
	(segment
		(start 69.3166 -148.3995)
		(end 68.786248 -148.3995)
		(width 0.127)
		(layer "B.Cu")
		(net "NCSI_TXD0")
	)
	(segment
		(start 70.2818 -115.062)
		(end 73.522332 -115.062)
		(width 0.127)
		(layer "B.Cu")
		(net "NCSI_TXD0")
	)
	(segment
		(start 81.534 -63.5508)
		(end 81.7372 -63.3476)
		(width 0.127)
		(layer "B.Cu")
		(net "NCSI_TXD0")
	)
	(segment
		(start 75.924918 -112.659414)
		(end 84.552536 -112.659414)
		(width 0.127)
		(layer "B.Cu")
		(net "NCSI_TXD0")
	)
	(segment
		(start 77.793596 -63.5508)
		(end 81.534 -63.5508)
		(width 0.127)
		(layer "B.Cu")
		(net "NCSI_TXD0")
	)
	(segment
		(start 67.98691 -120.370092)
		(end 67.147186 -121.209816)
		(width 0.127)
		(layer "In2.Cu")
		(net "NCSI_TXD0")
	)
	(segment
		(start 67.98691 -115.321588)
		(end 67.98691 -120.370092)
		(width 0.127)
		(layer "In2.Cu")
		(net "NCSI_TXD0")
	)
	(segment
		(start 68.03771 -141.804644)
		(end 68.594224 -142.361158)
		(width 0.127)
		(layer "In2.Cu")
		(net "NCSI_TXD0")
	)
	(segment
		(start 67.8815 -129.963418)
		(end 68.0593 -130.141218)
		(width 0.127)
		(layer "In2.Cu")
		(net "NCSI_TXD0")
	)
	(segment
		(start 67.147186 -126.520702)
		(end 67.8815 -127.255016)
		(width 0.127)
		(layer "In2.Cu")
		(net "NCSI_TXD0")
	)
	(segment
		(start 68.0593 -130.141218)
		(end 68.0593 -140.972286)
		(width 0.127)
		(layer "In2.Cu")
		(net "NCSI_TXD0")
	)
	(segment
		(start 68.0593 -140.972286)
		(end 68.03771 -140.993876)
		(width 0.127)
		(layer "In2.Cu")
		(net "NCSI_TXD0")
	)
	(segment
		(start 68.594224 -142.361158)
		(end 68.594224 -146.75739)
		(width 0.127)
		(layer "In2.Cu")
		(net "NCSI_TXD0")
	)
	(segment
		(start 67.8815 -127.255016)
		(end 67.8815 -129.963418)
		(width 0.127)
		(layer "In2.Cu")
		(net "NCSI_TXD0")
	)
	(segment
		(start 69.084698 -114.2238)
		(end 67.98691 -115.321588)
		(width 0.127)
		(layer "In2.Cu")
		(net "NCSI_TXD0")
	)
	(segment
		(start 68.594224 -146.75739)
		(end 69.347588 -147.510754)
		(width 0.127)
		(layer "In2.Cu")
		(net "NCSI_TXD0")
	)
	(segment
		(start 67.147186 -121.209816)
		(end 67.147186 -126.520702)
		(width 0.127)
		(layer "In2.Cu")
		(net "NCSI_TXD0")
	)
	(segment
		(start 69.4436 -114.2238)
		(end 69.084698 -114.2238)
		(width 0.127)
		(layer "In2.Cu")
		(net "NCSI_TXD0")
	)
	(segment
		(start 68.03771 -140.993876)
		(end 68.03771 -141.804644)
		(width 0.127)
		(layer "In2.Cu")
		(net "NCSI_TXD0")
	)
	(segment
		(start 87.269828 -68.841112)
		(end 88.362028 -68.841112)
		(width 0.127)
		(layer "F.Cu")
		(net "NCSI_RXD1_R")
	)
	(segment
		(start 87.269828 -68.841112)
		(end 86.8934 -68.464684)
		(width 0.127)
		(layer "F.Cu")
		(net "NCSI_RXD1_R")
	)
	(segment
		(start 81.985866 -66.491358)
		(end 81.927192 -66.550032)
		(width 0.127)
		(layer "F.Cu")
		(net "NCSI_RXD1_R")
	)
	(segment
		(start 81.927192 -66.550032)
		(end 79.925164 -66.550032)
		(width 0.127)
		(layer "F.Cu")
		(net "NCSI_RXD1_R")
	)
	(segment
		(start 86.8934 -68.464684)
		(end 86.8934 -68.216018)
		(width 0.127)
		(layer "F.Cu")
		(net "NCSI_RXD1_R")
	)
	(segment
		(start 85.16874 -66.491358)
		(end 81.985866 -66.491358)
		(width 0.127)
		(layer "F.Cu")
		(net "NCSI_RXD1_R")
	)
	(segment
		(start 86.8934 -68.216018)
		(end 85.16874 -66.491358)
		(width 0.127)
		(layer "F.Cu")
		(net "NCSI_RXD1_R")
	)
	(via
		(at 87.269828 -68.841112)
		(size 0.6604)
		(drill 0.3302)
		(layers "F.Cu" "B.Cu")
		(net "NCSI_RXD1_R")
	)
	(segment
		(start 88.4936 -95.395034)
		(end 88.4936 -69.861684)
		(width 0.127)
		(layer "F.Cu")
		(net "NCSI_RXD1")
	)
	(segment
		(start 53.699664 -149.400006)
		(end 53.299868 -149.799802)
		(width 0.127)
		(layer "F.Cu")
		(net "NCSI_RXD1")
	)
	(segment
		(start 91.144598 -98.046032)
		(end 88.4936 -95.395034)
		(width 0.127)
		(layer "F.Cu")
		(net "NCSI_RXD1")
	)
	(segment
		(start 88.4936 -69.861684)
		(end 88.362028 -69.730112)
		(width 0.127)
		(layer "F.Cu")
		(net "NCSI_RXD1")
	)
	(segment
		(start 53.699918 -149.400006)
		(end 53.699664 -149.400006)
		(width 0.127)
		(layer "F.Cu")
		(net "NCSI_RXD1")
	)
	(segment
		(start 92.380562 -98.046032)
		(end 91.144598 -98.046032)
		(width 0.127)
		(layer "F.Cu")
		(net "NCSI_RXD1")
	)
	(via
		(at 89.956132 -109.3216)
		(size 0.6096)
		(drill 0.3048)
		(layers "F.Cu" "B.Cu")
		(net "NCSI_RXD1")
	)
	(via
		(at 63.1952 -147.828)
		(size 0.508)
		(drill 0.254)
		(layers "F.Cu" "B.Cu")
		(net "NCSI_RXD1")
	)
	(via
		(at 53.299868 -149.799802)
		(size 0.4572)
		(drill 0.2032)
		(layers "F.Cu" "B.Cu")
		(net "NCSI_RXD1")
	)
	(via
		(at 64.3636 -115.189)
		(size 0.508)
		(drill 0.254)
		(layers "F.Cu" "B.Cu")
		(net "NCSI_RXD1")
	)
	(via
		(at 92.380562 -98.046032)
		(size 0.508)
		(drill 0.254)
		(layers "F.Cu" "B.Cu")
		(net "NCSI_RXD1")
	)
	(segment
		(start 92.418408 -106.859324)
		(end 92.418408 -98.083878)
		(width 0.127)
		(layer "B.Cu")
		(net "NCSI_RXD1")
	)
	(segment
		(start 92.418408 -98.083878)
		(end 92.380562 -98.046032)
		(width 0.127)
		(layer "B.Cu")
		(net "NCSI_RXD1")
	)
	(segment
		(start 89.956132 -109.357668)
		(end 89.956132 -109.3216)
		(width 0.127)
		(layer "B.Cu")
		(net "NCSI_RXD1")
	)
	(segment
		(start 65.2526 -116.078)
		(end 73.943464 -116.078)
		(width 0.127)
		(layer "B.Cu")
		(net "NCSI_RXD1")
	)
	(segment
		(start 64.3636 -115.189)
		(end 65.2526 -116.078)
		(width 0.127)
		(layer "B.Cu")
		(net "NCSI_RXD1")
	)
	(segment
		(start 85.638386 -113.675414)
		(end 89.956132 -109.357668)
		(width 0.127)
		(layer "B.Cu")
		(net "NCSI_RXD1")
	)
	(segment
		(start 73.943464 -116.078)
		(end 76.34605 -113.675414)
		(width 0.127)
		(layer "B.Cu")
		(net "NCSI_RXD1")
	)
	(segment
		(start 76.34605 -113.675414)
		(end 85.638386 -113.675414)
		(width 0.127)
		(layer "B.Cu")
		(net "NCSI_RXD1")
	)
	(segment
		(start 89.956132 -109.3216)
		(end 92.418408 -106.859324)
		(width 0.127)
		(layer "B.Cu")
		(net "NCSI_RXD1")
	)
	(segment
		(start 62.6237 -140.037312)
		(end 62.482984 -140.178028)
		(width 0.127)
		(layer "In2.Cu")
		(net "NCSI_RXD1")
	)
	(segment
		(start 61.201046 -136.760966)
		(end 61.201046 -137.59053)
		(width 0.127)
		(layer "In2.Cu")
		(net "NCSI_RXD1")
	)
	(segment
		(start 61.977016 -138.3665)
		(end 62.051184 -138.3665)
		(width 0.127)
		(layer "In2.Cu")
		(net "NCSI_RXD1")
	)
	(segment
		(start 60.783216 -134.68604)
		(end 60.783216 -136.343136)
		(width 0.127)
		(layer "In2.Cu")
		(net "NCSI_RXD1")
	)
	(segment
		(start 61.201046 -137.59053)
		(end 61.977016 -138.3665)
		(width 0.127)
		(layer "In2.Cu")
		(net "NCSI_RXD1")
	)
	(segment
		(start 64.1604 -128.204468)
		(end 64.1604 -131.308856)
		(width 0.127)
		(layer "In2.Cu")
		(net "NCSI_RXD1")
	)
	(segment
		(start 64.407288 -115.232688)
		(end 64.407288 -117.639338)
		(width 0.127)
		(layer "In2.Cu")
		(net "NCSI_RXD1")
	)
	(segment
		(start 64.1604 -131.308856)
		(end 60.783216 -134.68604)
		(width 0.127)
		(layer "In2.Cu")
		(net "NCSI_RXD1")
	)
	(segment
		(start 64.407288 -117.639338)
		(end 63.659004 -118.387622)
		(width 0.127)
		(layer "In2.Cu")
		(net "NCSI_RXD1")
	)
	(segment
		(start 62.051184 -138.3665)
		(end 62.6237 -138.939016)
		(width 0.127)
		(layer "In2.Cu")
		(net "NCSI_RXD1")
	)
	(segment
		(start 62.482984 -140.178028)
		(end 62.482984 -147.115784)
		(width 0.127)
		(layer "In2.Cu")
		(net "NCSI_RXD1")
	)
	(segment
		(start 62.6237 -138.939016)
		(end 62.6237 -140.037312)
		(width 0.127)
		(layer "In2.Cu")
		(net "NCSI_RXD1")
	)
	(segment
		(start 63.659004 -127.703072)
		(end 64.1604 -128.204468)
		(width 0.127)
		(layer "In2.Cu")
		(net "NCSI_RXD1")
	)
	(segment
		(start 60.783216 -136.343136)
		(end 61.201046 -136.760966)
		(width 0.127)
		(layer "In2.Cu")
		(net "NCSI_RXD1")
	)
	(segment
		(start 64.3636 -115.189)
		(end 64.407288 -115.232688)
		(width 0.127)
		(layer "In2.Cu")
		(net "NCSI_RXD1")
	)
	(segment
		(start 62.482984 -147.115784)
		(end 63.1952 -147.828)
		(width 0.127)
		(layer "In2.Cu")
		(net "NCSI_RXD1")
	)
	(segment
		(start 63.659004 -118.387622)
		(end 63.659004 -127.703072)
		(width 0.127)
		(layer "In2.Cu")
		(net "NCSI_RXD1")
	)
	(segment
		(start 57.924954 -148.5265)
		(end 59.5249 -148.5265)
		(width 0.127)
		(layer "In5.Cu")
		(net "NCSI_RXD1")
	)
	(segment
		(start 56.257444 -150.193756)
		(end 57.531508 -148.919692)
		(width 0.127)
		(layer "In5.Cu")
		(net "NCSI_RXD1")
	)
	(segment
		(start 62.6491 -147.2819)
		(end 63.1952 -147.828)
		(width 0.127)
		(layer "In5.Cu")
		(net "NCSI_RXD1")
	)
	(segment
		(start 59.5249 -148.5265)
		(end 60.7695 -147.2819)
		(width 0.127)
		(layer "In5.Cu")
		(net "NCSI_RXD1")
	)
	(segment
		(start 53.299868 -149.799802)
		(end 53.693822 -150.193756)
		(width 0.127)
		(layer "In5.Cu")
		(net "NCSI_RXD1")
	)
	(segment
		(start 57.531508 -148.919692)
		(end 57.924954 -148.5265)
		(width 0.127)
		(layer "In5.Cu")
		(net "NCSI_RXD1")
	)
	(segment
		(start 53.693822 -150.193756)
		(end 56.257444 -150.193756)
		(width 0.127)
		(layer "In5.Cu")
		(net "NCSI_RXD1")
	)
	(segment
		(start 60.7695 -147.2819)
		(end 62.6491 -147.2819)
		(width 0.127)
		(layer "In5.Cu")
		(net "NCSI_RXD1")
	)
	(segment
		(start 81.406492 -65.749932)
		(end 79.925164 -65.749932)
		(width 0.127)
		(layer "F.Cu")
		(net "NCSI_RXD0_R")
	)
	(segment
		(start 85.241384 -65.601596)
		(end 81.554828 -65.601596)
		(width 0.127)
		(layer "F.Cu")
		(net "NCSI_RXD0_R")
	)
	(segment
		(start 81.554828 -65.601596)
		(end 81.406492 -65.749932)
		(width 0.127)
		(layer "F.Cu")
		(net "NCSI_RXD0_R")
	)
	(segment
		(start 87.1474 -67.507612)
		(end 86.36 -66.720212)
		(width 0.127)
		(layer "F.Cu")
		(net "NCSI_RXD0_R")
	)
	(segment
		(start 87.485728 -67.507612)
		(end 87.1474 -67.507612)
		(width 0.127)
		(layer "F.Cu")
		(net "NCSI_RXD0_R")
	)
	(segment
		(start 86.36 -66.720212)
		(end 85.241384 -65.601596)
		(width 0.127)
		(layer "F.Cu")
		(net "NCSI_RXD0_R")
	)
	(via
		(at 86.36 -66.720212)
		(size 0.6604)
		(drill 0.3302)
		(layers "F.Cu" "B.Cu")
		(net "NCSI_RXD0_R")
	)
	(segment
		(start 90.999564 -97.182432)
		(end 89.0016 -95.184468)
		(width 0.127)
		(layer "F.Cu")
		(net "NCSI_RXD0")
	)
	(segment
		(start 58.934604 -156.370274)
		(end 59.048142 -156.370274)
		(width 0.127)
		(layer "F.Cu")
		(net "NCSI_RXD0")
	)
	(segment
		(start 92.379546 -97.182432)
		(end 90.999564 -97.182432)
		(width 0.127)
		(layer "F.Cu")
		(net "NCSI_RXD0")
	)
	(segment
		(start 56.34736 -152.002998)
		(end 57.496456 -153.152094)
		(width 0.127)
		(layer "F.Cu")
		(net "NCSI_RXD0")
	)
	(segment
		(start 59.458098 -156.78023)
		(end 59.458098 -156.981652)
		(width 0.127)
		(layer "F.Cu")
		(net "NCSI_RXD0")
	)
	(segment
		(start 59.048142 -156.370274)
		(end 59.458098 -156.78023)
		(width 0.127)
		(layer "F.Cu")
		(net "NCSI_RXD0")
	)
	(segment
		(start 57.496456 -153.152094)
		(end 57.496456 -154.932126)
		(width 0.127)
		(layer "F.Cu")
		(net "NCSI_RXD0")
	)
	(segment
		(start 57.496456 -154.932126)
		(end 58.934604 -156.370274)
		(width 0.127)
		(layer "F.Cu")
		(net "NCSI_RXD0")
	)
	(segment
		(start 89.0016 -68.134484)
		(end 88.374728 -67.507612)
		(width 0.127)
		(layer "F.Cu")
		(net "NCSI_RXD0")
	)
	(segment
		(start 89.0016 -95.184468)
		(end 89.0016 -68.134484)
		(width 0.127)
		(layer "F.Cu")
		(net "NCSI_RXD0")
	)
	(segment
		(start 56.30291 -152.002998)
		(end 56.34736 -152.002998)
		(width 0.127)
		(layer "F.Cu")
		(net "NCSI_RXD0")
	)
	(segment
		(start 56.099964 -151.800052)
		(end 56.30291 -152.002998)
		(width 0.127)
		(layer "F.Cu")
		(net "NCSI_RXD0")
	)
	(via
		(at 61.595 -116.5606)
		(size 0.508)
		(drill 0.254)
		(layers "F.Cu" "B.Cu")
		(net "NCSI_RXD0")
	)
	(via
		(at 89.305638 -111.472726)
		(size 0.6096)
		(drill 0.3048)
		(layers "F.Cu" "B.Cu")
		(net "NCSI_RXD0")
	)
	(via
		(at 92.379546 -97.182432)
		(size 0.508)
		(drill 0.254)
		(layers "F.Cu" "B.Cu")
		(net "NCSI_RXD0")
	)
	(via
		(at 59.458098 -156.981652)
		(size 0.508)
		(drill 0.254)
		(layers "F.Cu" "B.Cu")
		(net "NCSI_RXD0")
	)
	(segment
		(start 76.556616 -114.183414)
		(end 86.59495 -114.183414)
		(width 0.127)
		(layer "B.Cu")
		(net "NCSI_RXD0")
	)
	(segment
		(start 93.08846 -107.689904)
		(end 93.08846 -97.891346)
		(width 0.127)
		(layer "B.Cu")
		(net "NCSI_RXD0")
	)
	(segment
		(start 62.036198 -117.001798)
		(end 63.744348 -117.001798)
		(width 0.127)
		(layer "B.Cu")
		(net "NCSI_RXD0")
	)
	(segment
		(start 63.81115 -117.0686)
		(end 73.67143 -117.0686)
		(width 0.127)
		(layer "B.Cu")
		(net "NCSI_RXD0")
	)
	(segment
		(start 63.744348 -117.001798)
		(end 63.81115 -117.0686)
		(width 0.127)
		(layer "B.Cu")
		(net "NCSI_RXD0")
	)
	(segment
		(start 86.59495 -114.183414)
		(end 89.305638 -111.472726)
		(width 0.127)
		(layer "B.Cu")
		(net "NCSI_RXD0")
	)
	(segment
		(start 73.67143 -117.0686)
		(end 76.556616 -114.183414)
		(width 0.127)
		(layer "B.Cu")
		(net "NCSI_RXD0")
	)
	(segment
		(start 61.595 -116.5606)
		(end 62.036198 -117.001798)
		(width 0.127)
		(layer "B.Cu")
		(net "NCSI_RXD0")
	)
	(segment
		(start 93.08846 -97.891346)
		(end 92.379546 -97.182432)
		(width 0.127)
		(layer "B.Cu")
		(net "NCSI_RXD0")
	)
	(segment
		(start 89.305638 -111.472726)
		(end 93.08846 -107.689904)
		(width 0.127)
		(layer "B.Cu")
		(net "NCSI_RXD0")
	)
	(segment
		(start 60.3123 -151.4094)
		(end 60.3123 -156.409136)
		(width 0.127)
		(layer "In2.Cu")
		(net "NCSI_RXD0")
	)
	(segment
		(start 60.3123 -156.409136)
		(end 59.739784 -156.981652)
		(width 0.127)
		(layer "In2.Cu")
		(net "NCSI_RXD0")
	)
	(segment
		(start 61.0616 -117.094)
		(end 61.0616 -118.5164)
		(width 0.127)
		(layer "In2.Cu")
		(net "NCSI_RXD0")
	)
	(segment
		(start 58.2295 -140.605764)
		(end 58.2295 -149.3266)
		(width 0.127)
		(layer "In2.Cu")
		(net "NCSI_RXD0")
	)
	(segment
		(start 59.739784 -156.981652)
		(end 59.458098 -156.981652)
		(width 0.127)
		(layer "In2.Cu")
		(net "NCSI_RXD0")
	)
	(segment
		(start 57.2135 -134.2771)
		(end 57.4929 -134.5565)
		(width 0.127)
		(layer "In2.Cu")
		(net "NCSI_RXD0")
	)
	(segment
		(start 58.410602 -140.07719)
		(end 58.410602 -140.424662)
		(width 0.127)
		(layer "In2.Cu")
		(net "NCSI_RXD0")
	)
	(segment
		(start 57.679082 -132.7912)
		(end 57.2135 -133.256782)
		(width 0.127)
		(layer "In2.Cu")
		(net "NCSI_RXD0")
	)
	(segment
		(start 58.410602 -140.424662)
		(end 58.2295 -140.605764)
		(width 0.127)
		(layer "In2.Cu")
		(net "NCSI_RXD0")
	)
	(segment
		(start 57.2135 -133.256782)
		(end 57.2135 -134.2771)
		(width 0.127)
		(layer "In2.Cu")
		(net "NCSI_RXD0")
	)
	(segment
		(start 59.957462 -119.620538)
		(end 59.957462 -126.647194)
		(width 0.127)
		(layer "In2.Cu")
		(net "NCSI_RXD0")
	)
	(segment
		(start 60.825634 -128.491234)
		(end 61.1124 -128.778)
		(width 0.127)
		(layer "In2.Cu")
		(net "NCSI_RXD0")
	)
	(segment
		(start 57.4929 -134.5565)
		(end 57.4929 -139.159488)
		(width 0.127)
		(layer "In2.Cu")
		(net "NCSI_RXD0")
	)
	(segment
		(start 57.4929 -139.159488)
		(end 58.410602 -140.07719)
		(width 0.127)
		(layer "In2.Cu")
		(net "NCSI_RXD0")
	)
	(segment
		(start 60.825634 -127.515366)
		(end 60.825634 -128.491234)
		(width 0.127)
		(layer "In2.Cu")
		(net "NCSI_RXD0")
	)
	(segment
		(start 59.957462 -126.647194)
		(end 60.825634 -127.515366)
		(width 0.127)
		(layer "In2.Cu")
		(net "NCSI_RXD0")
	)
	(segment
		(start 58.2295 -149.3266)
		(end 60.3123 -151.4094)
		(width 0.127)
		(layer "In2.Cu")
		(net "NCSI_RXD0")
	)
	(segment
		(start 61.1124 -130.04546)
		(end 58.36666 -132.7912)
		(width 0.127)
		(layer "In2.Cu")
		(net "NCSI_RXD0")
	)
	(segment
		(start 58.36666 -132.7912)
		(end 57.679082 -132.7912)
		(width 0.127)
		(layer "In2.Cu")
		(net "NCSI_RXD0")
	)
	(segment
		(start 61.1124 -128.778)
		(end 61.1124 -130.04546)
		(width 0.127)
		(layer "In2.Cu")
		(net "NCSI_RXD0")
	)
	(segment
		(start 61.595 -116.5606)
		(end 61.0616 -117.094)
		(width 0.127)
		(layer "In2.Cu")
		(net "NCSI_RXD0")
	)
	(segment
		(start 61.0616 -118.5164)
		(end 59.957462 -119.620538)
		(width 0.127)
		(layer "In2.Cu")
		(net "NCSI_RXD0")
	)
	(segment
		(start 77.52715 -62.093094)
		(end 77.585316 -62.093094)
		(width 0.127)
		(layer "F.Cu")
		(net "NCSI_RX_ER_R")
	)
	(segment
		(start 84.886292 -63.201296)
		(end 85.05063 -63.201296)
		(width 0.127)
		(layer "F.Cu")
		(net "NCSI_RX_ER_R")
	)
	(segment
		(start 85.05063 -63.201296)
		(end 87.324946 -65.475612)
		(width 0.127)
		(layer "F.Cu")
		(net "NCSI_RX_ER_R")
	)
	(segment
		(start 87.324946 -65.475612)
		(end 88.400128 -65.475612)
		(width 0.127)
		(layer "F.Cu")
		(net "NCSI_RX_ER_R")
	)
	(segment
		(start 75.475084 -62.55004)
		(end 77.070204 -62.55004)
		(width 0.127)
		(layer "F.Cu")
		(net "NCSI_RX_ER_R")
	)
	(segment
		(start 77.070204 -62.55004)
		(end 77.52715 -62.093094)
		(width 0.127)
		(layer "F.Cu")
		(net "NCSI_RX_ER_R")
	)
	(via
		(at 77.585316 -62.093094)
		(size 0.508)
		(drill 0.254)
		(layers "F.Cu" "B.Cu")
		(net "NCSI_RX_ER_R")
	)
	(via
		(at 84.886292 -63.201296)
		(size 0.508)
		(drill 0.254)
		(layers "F.Cu" "B.Cu")
		(net "NCSI_RX_ER_R")
	)
	(via
		(at 79.4512 -62.093094)
		(size 0.6096)
		(drill 0.3048)
		(layers "F.Cu" "B.Cu")
		(net "NCSI_RX_ER_R")
	)
	(segment
		(start 83.77809 -62.093094)
		(end 79.4512 -62.093094)
		(width 0.127)
		(layer "B.Cu")
		(net "NCSI_RX_ER_R")
	)
	(segment
		(start 79.4512 -62.093094)
		(end 77.585316 -62.093094)
		(width 0.127)
		(layer "B.Cu")
		(net "NCSI_RX_ER_R")
	)
	(segment
		(start 84.886292 -63.201296)
		(end 83.77809 -62.093094)
		(width 0.127)
		(layer "B.Cu")
		(net "NCSI_RX_ER_R")
	)
	(segment
		(start 90.5256 -93.815916)
		(end 91.268042 -94.558358)
		(width 0.127)
		(layer "F.Cu")
		(net "NCSI_RX_ER")
	)
	(segment
		(start 54.500018 -150.999952)
		(end 54.500018 -150.999444)
		(width 0.127)
		(layer "F.Cu")
		(net "NCSI_RX_ER")
	)
	(segment
		(start 54.500018 -150.999444)
		(end 54.100222 -150.599648)
		(width 0.127)
		(layer "F.Cu")
		(net "NCSI_RX_ER")
	)
	(segment
		(start 89.289128 -65.475612)
		(end 90.5256 -66.712084)
		(width 0.127)
		(layer "F.Cu")
		(net "NCSI_RX_ER")
	)
	(segment
		(start 90.5256 -66.712084)
		(end 90.5256 -93.815916)
		(width 0.127)
		(layer "F.Cu")
		(net "NCSI_RX_ER")
	)
	(via
		(at 62.451996 -116.453412)
		(size 0.508)
		(drill 0.254)
		(layers "F.Cu" "B.Cu")
		(net "NCSI_RX_ER")
	)
	(via
		(at 86.234778 -110.146592)
		(size 0.6096)
		(drill 0.3048)
		(layers "F.Cu" "B.Cu")
		(net "NCSI_RX_ER")
	)
	(via
		(at 54.100222 -150.599648)
		(size 0.4572)
		(drill 0.2032)
		(layers "F.Cu" "B.Cu")
		(net "NCSI_RX_ER")
	)
	(via
		(at 91.268042 -94.558358)
		(size 0.508)
		(drill 0.254)
		(layers "F.Cu" "B.Cu")
		(net "NCSI_RX_ER")
	)
	(via
		(at 60.2234 -149.86)
		(size 0.508)
		(drill 0.254)
		(layers "F.Cu" "B.Cu")
		(net "NCSI_RX_ER")
	)
	(segment
		(start 65.793366 -114.173)
		(end 63.942468 -114.173)
		(width 0.127)
		(layer "B.Cu")
		(net "NCSI_RX_ER")
	)
	(segment
		(start 68.188332 -114.4016)
		(end 66.021966 -114.4016)
		(width 0.127)
		(layer "B.Cu")
		(net "NCSI_RX_ER")
	)
	(segment
		(start 91.3257 -95.39097)
		(end 91.3257 -94.616016)
		(width 0.127)
		(layer "B.Cu")
		(net "NCSI_RX_ER")
	)
	(segment
		(start 75.714352 -112.151414)
		(end 73.311766 -114.554)
		(width 0.127)
		(layer "B.Cu")
		(net "NCSI_RX_ER")
	)
	(segment
		(start 69.833998 -113.699798)
		(end 68.890134 -113.699798)
		(width 0.127)
		(layer "B.Cu")
		(net "NCSI_RX_ER")
	)
	(segment
		(start 62.451996 -115.663472)
		(end 62.451996 -116.453412)
		(width 0.127)
		(layer "B.Cu")
		(net "NCSI_RX_ER")
	)
	(segment
		(start 84.229956 -112.151414)
		(end 75.714352 -112.151414)
		(width 0.127)
		(layer "B.Cu")
		(net "NCSI_RX_ER")
	)
	(segment
		(start 91.3257 -94.616016)
		(end 91.268042 -94.558358)
		(width 0.127)
		(layer "B.Cu")
		(net "NCSI_RX_ER")
	)
	(segment
		(start 90.678 -96.03867)
		(end 91.3257 -95.39097)
		(width 0.127)
		(layer "B.Cu")
		(net "NCSI_RX_ER")
	)
	(segment
		(start 63.942468 -114.173)
		(end 62.451996 -115.663472)
		(width 0.127)
		(layer "B.Cu")
		(net "NCSI_RX_ER")
	)
	(segment
		(start 70.6882 -114.554)
		(end 69.833998 -113.699798)
		(width 0.127)
		(layer "B.Cu")
		(net "NCSI_RX_ER")
	)
	(segment
		(start 66.021966 -114.4016)
		(end 65.793366 -114.173)
		(width 0.127)
		(layer "B.Cu")
		(net "NCSI_RX_ER")
	)
	(segment
		(start 86.234778 -110.146592)
		(end 90.678 -105.70337)
		(width 0.127)
		(layer "B.Cu")
		(net "NCSI_RX_ER")
	)
	(segment
		(start 86.234778 -110.146592)
		(end 84.229956 -112.151414)
		(width 0.127)
		(layer "B.Cu")
		(net "NCSI_RX_ER")
	)
	(segment
		(start 68.890134 -113.699798)
		(end 68.188332 -114.4016)
		(width 0.127)
		(layer "B.Cu")
		(net "NCSI_RX_ER")
	)
	(segment
		(start 73.311766 -114.554)
		(end 70.6882 -114.554)
		(width 0.127)
		(layer "B.Cu")
		(net "NCSI_RX_ER")
	)
	(segment
		(start 90.678 -105.70337)
		(end 90.678 -96.03867)
		(width 0.127)
		(layer "B.Cu")
		(net "NCSI_RX_ER")
	)
	(segment
		(start 62.1284 -130.466592)
		(end 58.923936 -133.671056)
		(width 0.127)
		(layer "In2.Cu")
		(net "NCSI_RX_ER")
	)
	(segment
		(start 61.5696 -118.12651)
		(end 61.5696 -128.487932)
		(width 0.127)
		(layer "In2.Cu")
		(net "NCSI_RX_ER")
	)
	(segment
		(start 62.451996 -116.453412)
		(end 62.451996 -117.244114)
		(width 0.127)
		(layer "In2.Cu")
		(net "NCSI_RX_ER")
	)
	(segment
		(start 62.451996 -117.244114)
		(end 61.5696 -118.12651)
		(width 0.127)
		(layer "In2.Cu")
		(net "NCSI_RX_ER")
	)
	(segment
		(start 62.1284 -129.046732)
		(end 62.1284 -130.466592)
		(width 0.127)
		(layer "In2.Cu")
		(net "NCSI_RX_ER")
	)
	(segment
		(start 58.923936 -139.035536)
		(end 60.263278 -140.374878)
		(width 0.127)
		(layer "In2.Cu")
		(net "NCSI_RX_ER")
	)
	(segment
		(start 58.923936 -133.671056)
		(end 58.923936 -139.035536)
		(width 0.127)
		(layer "In2.Cu")
		(net "NCSI_RX_ER")
	)
	(segment
		(start 60.263278 -149.820122)
		(end 60.2234 -149.86)
		(width 0.127)
		(layer "In2.Cu")
		(net "NCSI_RX_ER")
	)
	(segment
		(start 60.263278 -140.374878)
		(end 60.263278 -149.820122)
		(width 0.127)
		(layer "In2.Cu")
		(net "NCSI_RX_ER")
	)
	(segment
		(start 61.5696 -128.487932)
		(end 62.1284 -129.046732)
		(width 0.127)
		(layer "In2.Cu")
		(net "NCSI_RX_ER")
	)
	(segment
		(start 56.7182 -150.9014)
		(end 55.0418 -150.9014)
		(width 0.127)
		(layer "In5.Cu")
		(net "NCSI_RX_ER")
	)
	(segment
		(start 60.198 -149.8346)
		(end 57.785 -149.8346)
		(width 0.127)
		(layer "In5.Cu")
		(net "NCSI_RX_ER")
	)
	(segment
		(start 57.785 -149.8346)
		(end 56.7182 -150.9014)
		(width 0.127)
		(layer "In5.Cu")
		(net "NCSI_RX_ER")
	)
	(segment
		(start 54.740048 -150.599648)
		(end 54.100222 -150.599648)
		(width 0.127)
		(layer "In5.Cu")
		(net "NCSI_RX_ER")
	)
	(segment
		(start 55.0418 -150.9014)
		(end 54.740048 -150.599648)
		(width 0.127)
		(layer "In5.Cu")
		(net "NCSI_RX_ER")
	)
	(segment
		(start 60.2234 -149.86)
		(end 60.198 -149.8346)
		(width 0.127)
		(layer "In5.Cu")
		(net "NCSI_RX_ER")
	)
	(segment
		(start 87.930736 -61.517022)
		(end 86.64067 -60.226956)
		(width 0.127)
		(layer "F.Cu")
		(net "NCSI_RCSDV_R")
	)
	(segment
		(start 83.860386 -59.82081)
		(end 86.234524 -59.82081)
		(width 0.127)
		(layer "F.Cu")
		(net "NCSI_RCSDV_R")
	)
	(segment
		(start 83.38947 -59.349894)
		(end 83.860386 -59.82081)
		(width 0.127)
		(layer "F.Cu")
		(net "NCSI_RCSDV_R")
	)
	(segment
		(start 79.925164 -59.349894)
		(end 83.38947 -59.349894)
		(width 0.127)
		(layer "F.Cu")
		(net "NCSI_RCSDV_R")
	)
	(segment
		(start 86.234524 -59.82081)
		(end 86.64067 -60.226956)
		(width 0.127)
		(layer "F.Cu")
		(net "NCSI_RCSDV_R")
	)
	(segment
		(start 88.369648 -61.517022)
		(end 87.930736 -61.517022)
		(width 0.127)
		(layer "F.Cu")
		(net "NCSI_RCSDV_R")
	)
	(via
		(at 86.64067 -60.226956)
		(size 0.6604)
		(drill 0.3302)
		(layers "F.Cu" "B.Cu")
		(net "NCSI_RCSDV_R")
	)
	(segment
		(start 77.308202 -113.8428)
		(end 85.437218 -113.8428)
		(width 0.127)
		(layer "F.Cu")
		(net "NCSI_RCSDV")
	)
	(segment
		(start 72.659494 -127.604012)
		(end 72.659494 -118.491508)
		(width 0.127)
		(layer "F.Cu")
		(net "NCSI_RCSDV")
	)
	(segment
		(start 93.461586 -111.409988)
		(end 90.341704 -111.409988)
		(width 0.127)
		(layer "F.Cu")
		(net "NCSI_RCSDV")
	)
	(segment
		(start 93.664786 -64.920876)
		(end 93.664786 -88.519254)
		(width 0.127)
		(layer "F.Cu")
		(net "NCSI_RCSDV")
	)
	(segment
		(start 90.341704 -111.409988)
		(end 89.966292 -111.7854)
		(width 0.127)
		(layer "F.Cu")
		(net "NCSI_RCSDV")
	)
	(segment
		(start 96.8121 -108.059474)
		(end 93.461586 -111.409988)
		(width 0.127)
		(layer "F.Cu")
		(net "NCSI_RCSDV")
	)
	(segment
		(start 85.437218 -113.8428)
		(end 87.494618 -111.7854)
		(width 0.127)
		(layer "F.Cu")
		(net "NCSI_RCSDV")
	)
	(segment
		(start 89.966292 -111.7854)
		(end 88.3412 -111.7854)
		(width 0.127)
		(layer "F.Cu")
		(net "NCSI_RCSDV")
	)
	(segment
		(start 96.8121 -91.666568)
		(end 96.8121 -108.059474)
		(width 0.127)
		(layer "F.Cu")
		(net "NCSI_RCSDV")
	)
	(segment
		(start 72.659494 -118.491508)
		(end 77.308202 -113.8428)
		(width 0.127)
		(layer "F.Cu")
		(net "NCSI_RCSDV")
	)
	(segment
		(start 89.258648 -61.517022)
		(end 90.260932 -61.517022)
		(width 0.127)
		(layer "F.Cu")
		(net "NCSI_RCSDV")
	)
	(segment
		(start 90.260932 -61.517022)
		(end 93.664786 -64.920876)
		(width 0.127)
		(layer "F.Cu")
		(net "NCSI_RCSDV")
	)
	(segment
		(start 93.664786 -88.519254)
		(end 96.8121 -91.666568)
		(width 0.127)
		(layer "F.Cu")
		(net "NCSI_RCSDV")
	)
	(segment
		(start 54.500018 -150.199852)
		(end 54.500018 -150.199344)
		(width 0.127)
		(layer "F.Cu")
		(net "NCSI_RCSDV")
	)
	(segment
		(start 54.500018 -150.199344)
		(end 54.899814 -149.799548)
		(width 0.127)
		(layer "F.Cu")
		(net "NCSI_RCSDV")
	)
	(segment
		(start 87.494618 -111.7854)
		(end 88.3412 -111.7854)
		(width 0.127)
		(layer "F.Cu")
		(net "NCSI_RCSDV")
	)
	(via
		(at 72.4916 -145.429224)
		(size 0.508)
		(drill 0.254)
		(layers "F.Cu" "B.Cu")
		(net "NCSI_RCSDV")
	)
	(via
		(at 54.899814 -149.799548)
		(size 0.4572)
		(drill 0.2032)
		(layers "F.Cu" "B.Cu")
		(net "NCSI_RCSDV")
	)
	(via
		(at 72.659494 -127.604012)
		(size 0.508)
		(drill 0.254)
		(layers "F.Cu" "B.Cu")
		(net "NCSI_RCSDV")
	)
	(via
		(at 88.3412 -111.7854)
		(size 0.6604)
		(drill 0.3302)
		(layers "F.Cu" "B.Cu")
		(net "NCSI_RCSDV")
	)
	(segment
		(start 72.5043 -138.449812)
		(end 72.1233 -138.830812)
		(width 0.127)
		(layer "In2.Cu")
		(net "NCSI_RCSDV")
	)
	(segment
		(start 72.1233 -142.183866)
		(end 72.12965 -142.190216)
		(width 0.127)
		(layer "In2.Cu")
		(net "NCSI_RCSDV")
	)
	(segment
		(start 72.5043 -127.759206)
		(end 72.5043 -138.449812)
		(width 0.127)
		(layer "In2.Cu")
		(net "NCSI_RCSDV")
	)
	(segment
		(start 72.1233 -138.830812)
		(end 72.1233 -142.183866)
		(width 0.127)
		(layer "In2.Cu")
		(net "NCSI_RCSDV")
	)
	(segment
		(start 72.12965 -142.190216)
		(end 72.12965 -145.067274)
		(width 0.127)
		(layer "In2.Cu")
		(net "NCSI_RCSDV")
	)
	(segment
		(start 72.659494 -127.604012)
		(end 72.5043 -127.759206)
		(width 0.127)
		(layer "In2.Cu")
		(net "NCSI_RCSDV")
	)
	(segment
		(start 72.12965 -145.067274)
		(end 72.4916 -145.429224)
		(width 0.127)
		(layer "In2.Cu")
		(net "NCSI_RCSDV")
	)
	(segment
		(start 72.24522 -146.60118)
		(end 70.788276 -148.058124)
		(width 0.127)
		(layer "In5.Cu")
		(net "NCSI_RCSDV")
	)
	(segment
		(start 59.6265 -146.7739)
		(end 59.1185 -147.2819)
		(width 0.127)
		(layer "In5.Cu")
		(net "NCSI_RCSDV")
	)
	(segment
		(start 56.045862 -149.4536)
		(end 55.0926 -149.4536)
		(width 0.127)
		(layer "In5.Cu")
		(net "NCSI_RCSDV")
	)
	(segment
		(start 70.788276 -148.058124)
		(end 69.090794 -148.058124)
		(width 0.127)
		(layer "In5.Cu")
		(net "NCSI_RCSDV")
	)
	(segment
		(start 64.008 -147.8534)
		(end 62.9285 -146.7739)
		(width 0.127)
		(layer "In5.Cu")
		(net "NCSI_RCSDV")
	)
	(segment
		(start 54.899814 -149.646386)
		(end 54.899814 -149.799548)
		(width 0.127)
		(layer "In5.Cu")
		(net "NCSI_RCSDV")
	)
	(segment
		(start 64.894714 -147.8534)
		(end 64.008 -147.8534)
		(width 0.127)
		(layer "In5.Cu")
		(net "NCSI_RCSDV")
	)
	(segment
		(start 59.1185 -147.2819)
		(end 58.217562 -147.2819)
		(width 0.127)
		(layer "In5.Cu")
		(net "NCSI_RCSDV")
	)
	(segment
		(start 58.217562 -147.2819)
		(end 56.045862 -149.4536)
		(width 0.127)
		(layer "In5.Cu")
		(net "NCSI_RCSDV")
	)
	(segment
		(start 72.24522 -145.63598)
		(end 72.24522 -146.60118)
		(width 0.127)
		(layer "In5.Cu")
		(net "NCSI_RCSDV")
	)
	(segment
		(start 69.090794 -148.058124)
		(end 68.53047 -147.4978)
		(width 0.127)
		(layer "In5.Cu")
		(net "NCSI_RCSDV")
	)
	(segment
		(start 65.250314 -147.4978)
		(end 64.894714 -147.8534)
		(width 0.127)
		(layer "In5.Cu")
		(net "NCSI_RCSDV")
	)
	(segment
		(start 72.451976 -145.429224)
		(end 72.24522 -145.63598)
		(width 0.127)
		(layer "In5.Cu")
		(net "NCSI_RCSDV")
	)
	(segment
		(start 55.0926 -149.4536)
		(end 54.899814 -149.646386)
		(width 0.127)
		(layer "In5.Cu")
		(net "NCSI_RCSDV")
	)
	(segment
		(start 72.4916 -145.429224)
		(end 72.451976 -145.429224)
		(width 0.127)
		(layer "In5.Cu")
		(net "NCSI_RCSDV")
	)
	(segment
		(start 68.53047 -147.4978)
		(end 65.250314 -147.4978)
		(width 0.127)
		(layer "In5.Cu")
		(net "NCSI_RCSDV")
	)
	(segment
		(start 62.9285 -146.7739)
		(end 59.6265 -146.7739)
		(width 0.127)
		(layer "In5.Cu")
		(net "NCSI_RCSDV")
	)
	(segment
		(start 66.724276 -147.828)
		(end 67.9704 -147.828)
		(width 0.127)
		(layer "F.Cu")
		(net "NCSI_RCLK_R")
	)
	(segment
		(start 68.241926 -145.913348)
		(end 67.894454 -145.913348)
		(width 0.127)
		(layer "F.Cu")
		(net "NCSI_RCLK_R")
	)
	(segment
		(start 66.40957 -146.805396)
		(end 66.40957 -147.068286)
		(width 0.127)
		(layer "F.Cu")
		(net "NCSI_RCLK_R")
	)
	(segment
		(start 67.288156 -146.519646)
		(end 66.69532 -146.519646)
		(width 0.127)
		(layer "F.Cu")
		(net "NCSI_RCLK_R")
	)
	(segment
		(start 66.40957 -147.068286)
		(end 66.40957 -147.513294)
		(width 0.127)
		(layer "F.Cu")
		(net "NCSI_RCLK_R")
	)
	(segment
		(start 66.40957 -147.513294)
		(end 66.724276 -147.828)
		(width 0.127)
		(layer "F.Cu")
		(net "NCSI_RCLK_R")
	)
	(segment
		(start 67.894454 -145.913348)
		(end 67.288156 -146.519646)
		(width 0.127)
		(layer "F.Cu")
		(net "NCSI_RCLK_R")
	)
	(segment
		(start 66.69532 -146.519646)
		(end 66.40957 -146.805396)
		(width 0.127)
		(layer "F.Cu")
		(net "NCSI_RCLK_R")
	)
	(via
		(at 66.40957 -147.068286)
		(size 0.6604)
		(drill 0.3302)
		(layers "F.Cu" "B.Cu")
		(net "NCSI_RCLK_R")
	)
	(segment
		(start 70.2564 -122.8598)
		(end 70.254114 -122.862086)
		(width 0.127)
		(layer "F.Cu")
		(net "NCSI_RCLK")
	)
	(segment
		(start 86.996016 -110.901988)
		(end 86.096602 -111.801402)
		(width 0.127)
		(layer "F.Cu")
		(net "NCSI_RCLK")
	)
	(segment
		(start 76.855828 -112.8522)
		(end 71.9836 -117.724428)
		(width 0.127)
		(layer "F.Cu")
		(net "NCSI_RCLK")
	)
	(segment
		(start 96.3041 -107.848908)
		(end 93.25102 -110.901988)
		(width 0.127)
		(layer "F.Cu")
		(net "NCSI_RCLK")
	)
	(segment
		(start 71.9836 -117.724428)
		(end 71.9836 -119.700548)
		(width 0.127)
		(layer "F.Cu")
		(net "NCSI_RCLK")
	)
	(segment
		(start 93.156786 -88.72982)
		(end 96.3041 -91.877134)
		(width 0.127)
		(layer "F.Cu")
		(net "NCSI_RCLK")
	)
	(segment
		(start 85.045804 -112.8522)
		(end 76.855828 -112.8522)
		(width 0.127)
		(layer "F.Cu")
		(net "NCSI_RCLK")
	)
	(segment
		(start 83.471004 -60.149994)
		(end 83.64982 -60.32881)
		(width 0.127)
		(layer "F.Cu")
		(net "NCSI_RCLK")
	)
	(segment
		(start 85.937598 -60.32881)
		(end 87.7951 -62.186312)
		(width 0.127)
		(layer "F.Cu")
		(net "NCSI_RCLK")
	)
	(segment
		(start 86.096602 -111.801402)
		(end 85.045804 -112.8522)
		(width 0.127)
		(layer "F.Cu")
		(net "NCSI_RCLK")
	)
	(segment
		(start 96.3041 -91.877134)
		(end 96.3041 -107.848908)
		(width 0.127)
		(layer "F.Cu")
		(net "NCSI_RCLK")
	)
	(segment
		(start 83.64982 -60.32881)
		(end 85.937598 -60.32881)
		(width 0.127)
		(layer "F.Cu")
		(net "NCSI_RCLK")
	)
	(segment
		(start 79.925164 -60.149994)
		(end 83.471004 -60.149994)
		(width 0.127)
		(layer "F.Cu")
		(net "NCSI_RCLK")
	)
	(segment
		(start 93.156786 -65.134998)
		(end 93.156786 -88.72982)
		(width 0.127)
		(layer "F.Cu")
		(net "NCSI_RCLK")
	)
	(segment
		(start 90.2081 -62.186312)
		(end 93.156786 -65.134998)
		(width 0.127)
		(layer "F.Cu")
		(net "NCSI_RCLK")
	)
	(segment
		(start 87.7951 -62.186312)
		(end 90.2081 -62.186312)
		(width 0.127)
		(layer "F.Cu")
		(net "NCSI_RCLK")
	)
	(segment
		(start 71.9836 -119.700548)
		(end 70.2564 -121.427748)
		(width 0.127)
		(layer "F.Cu")
		(net "NCSI_RCLK")
	)
	(segment
		(start 93.25102 -110.901988)
		(end 86.996016 -110.901988)
		(width 0.127)
		(layer "F.Cu")
		(net "NCSI_RCLK")
	)
	(segment
		(start 70.2564 -121.427748)
		(end 70.2564 -122.8598)
		(width 0.127)
		(layer "F.Cu")
		(net "NCSI_RCLK")
	)
	(segment
		(start 69.255386 -145.913348)
		(end 70.015608 -146.67357)
		(width 0.127)
		(layer "F.Cu")
		(net "NCSI_RCLK")
	)
	(segment
		(start 69.130926 -145.913348)
		(end 69.255386 -145.913348)
		(width 0.127)
		(layer "F.Cu")
		(net "NCSI_RCLK")
	)
	(via
		(at 86.096602 -111.801402)
		(size 0.6604)
		(drill 0.3302)
		(layers "F.Cu" "B.Cu")
		(net "NCSI_RCLK")
	)
	(via
		(at 70.254114 -122.862086)
		(size 0.508)
		(drill 0.254)
		(layers "F.Cu" "B.Cu")
		(net "NCSI_RCLK")
	)
	(via
		(at 70.015608 -146.67357)
		(size 0.508)
		(drill 0.254)
		(layers "F.Cu" "B.Cu")
		(net "NCSI_RCLK")
	)
	(segment
		(start 69.610224 -136.19099)
		(end 69.342254 -135.92302)
		(width 0.127)
		(layer "In2.Cu")
		(net "NCSI_RCLK")
	)
	(segment
		(start 70.2564 -123.642882)
		(end 70.2564 -122.864372)
		(width 0.127)
		(layer "In2.Cu")
		(net "NCSI_RCLK")
	)
	(segment
		(start 69.342254 -135.92302)
		(end 69.342254 -124.557028)
		(width 0.127)
		(layer "In2.Cu")
		(net "NCSI_RCLK")
	)
	(segment
		(start 69.342254 -124.557028)
		(end 70.2564 -123.642882)
		(width 0.127)
		(layer "In2.Cu")
		(net "NCSI_RCLK")
	)
	(segment
		(start 70.015608 -146.67357)
		(end 70.019418 -146.67357)
		(width 0.127)
		(layer "In2.Cu")
		(net "NCSI_RCLK")
	)
	(segment
		(start 69.610224 -146.264376)
		(end 69.610224 -136.19099)
		(width 0.127)
		(layer "In2.Cu")
		(net "NCSI_RCLK")
	)
	(segment
		(start 70.2564 -122.864372)
		(end 70.254114 -122.862086)
		(width 0.127)
		(layer "In2.Cu")
		(net "NCSI_RCLK")
	)
	(segment
		(start 70.019418 -146.67357)
		(end 69.610224 -146.264376)
		(width 0.127)
		(layer "In2.Cu")
		(net "NCSI_RCLK")
	)
	(segment
		(start 52.899818 -142.999968)
		(end 53.299868 -142.599918)
		(width 0.127)
		(layer "F.Cu")
		(net "I2C_COMP_ALERT_N")
	)
	(via
		(at 53.299868 -142.599918)
		(size 0.4572)
		(drill 0.2032)
		(layers "F.Cu" "B.Cu")
		(net "I2C_COMP_ALERT_N")
	)
	(via
		(at 78.1431 -151.384)
		(size 0.508)
		(drill 0.254)
		(layers "F.Cu" "B.Cu")
		(net "I2C_COMP_ALERT_N")
	)
	(via
		(at 66.2686 -140.6906)
		(size 0.508)
		(drill 0.254)
		(layers "F.Cu" "B.Cu")
		(net "I2C_COMP_ALERT_N")
	)
	(via
		(at 65.151 -140.4366)
		(size 0.6096)
		(drill 0.3048)
		(layers "F.Cu" "B.Cu")
		(net "I2C_COMP_ALERT_N")
	)
	(via
		(at 70.920356 -150.211282)
		(size 0.508)
		(drill 0.254)
		(layers "F.Cu" "B.Cu")
		(net "I2C_COMP_ALERT_N")
	)
	(segment
		(start 77.817726 -151.9428)
		(end 77.0255 -151.9428)
		(width 0.127)
		(layer "B.Cu")
		(net "I2C_COMP_ALERT_N")
	)
	(segment
		(start 65.405 -140.6906)
		(end 65.151 -140.4366)
		(width 0.127)
		(layer "B.Cu")
		(net "I2C_COMP_ALERT_N")
	)
	(segment
		(start 64.975994 -139.270232)
		(end 64.975994 -140.261594)
		(width 0.127)
		(layer "B.Cu")
		(net "I2C_COMP_ALERT_N")
	)
	(segment
		(start 78.68031 -151.92121)
		(end 78.1431 -151.384)
		(width 0.127)
		(layer "B.Cu")
		(net "I2C_COMP_ALERT_N")
	)
	(segment
		(start 78.338426 -152.4635)
		(end 77.817726 -151.9428)
		(width 0.127)
		(layer "B.Cu")
		(net "I2C_COMP_ALERT_N")
	)
	(segment
		(start 78.68031 -152.4635)
		(end 78.338426 -152.4635)
		(width 0.127)
		(layer "B.Cu")
		(net "I2C_COMP_ALERT_N")
	)
	(segment
		(start 64.975994 -140.261594)
		(end 65.151 -140.4366)
		(width 0.127)
		(layer "B.Cu")
		(net "I2C_COMP_ALERT_N")
	)
	(segment
		(start 78.68031 -152.4635)
		(end 78.68031 -151.92121)
		(width 0.127)
		(layer "B.Cu")
		(net "I2C_COMP_ALERT_N")
	)
	(segment
		(start 66.2686 -140.6906)
		(end 65.405 -140.6906)
		(width 0.127)
		(layer "B.Cu")
		(net "I2C_COMP_ALERT_N")
	)
	(segment
		(start 70.917816 -150.211282)
		(end 70.920356 -150.211282)
		(width 0.127)
		(layer "In2.Cu")
		(net "I2C_COMP_ALERT_N")
	)
	(segment
		(start 67.6529 -146.5453)
		(end 67.6529 -147.219924)
		(width 0.127)
		(layer "In2.Cu")
		(net "I2C_COMP_ALERT_N")
	)
	(segment
		(start 67.6529 -147.219924)
		(end 68.71208 -148.279104)
		(width 0.127)
		(layer "In2.Cu")
		(net "I2C_COMP_ALERT_N")
	)
	(segment
		(start 68.71208 -149.869398)
		(end 69.426582 -150.5839)
		(width 0.127)
		(layer "In2.Cu")
		(net "I2C_COMP_ALERT_N")
	)
	(segment
		(start 69.426582 -150.5839)
		(end 70.545198 -150.5839)
		(width 0.127)
		(layer "In2.Cu")
		(net "I2C_COMP_ALERT_N")
	)
	(segment
		(start 68.71208 -148.279104)
		(end 68.71208 -149.869398)
		(width 0.127)
		(layer "In2.Cu")
		(net "I2C_COMP_ALERT_N")
	)
	(segment
		(start 67.8434 -142.6464)
		(end 67.8434 -146.3548)
		(width 0.127)
		(layer "In2.Cu")
		(net "I2C_COMP_ALERT_N")
	)
	(segment
		(start 66.2686 -141.0716)
		(end 67.8434 -142.6464)
		(width 0.127)
		(layer "In2.Cu")
		(net "I2C_COMP_ALERT_N")
	)
	(segment
		(start 67.8434 -146.3548)
		(end 67.6529 -146.5453)
		(width 0.127)
		(layer "In2.Cu")
		(net "I2C_COMP_ALERT_N")
	)
	(segment
		(start 66.2686 -140.6906)
		(end 66.2686 -141.0716)
		(width 0.127)
		(layer "In2.Cu")
		(net "I2C_COMP_ALERT_N")
	)
	(segment
		(start 70.545198 -150.5839)
		(end 70.917816 -150.211282)
		(width 0.127)
		(layer "In2.Cu")
		(net "I2C_COMP_ALERT_N")
	)
	(segment
		(start 75.463146 -150.563326)
		(end 76.28382 -151.384)
		(width 0.127)
		(layer "In5.Cu")
		(net "I2C_COMP_ALERT_N")
	)
	(segment
		(start 56.101996 -143.794226)
		(end 53.137054 -143.794226)
		(width 0.127)
		(layer "In5.Cu")
		(net "I2C_COMP_ALERT_N")
	)
	(segment
		(start 57.712864 -142.183358)
		(end 56.101996 -143.794226)
		(width 0.127)
		(layer "In5.Cu")
		(net "I2C_COMP_ALERT_N")
	)
	(segment
		(start 73.96607 -150.563326)
		(end 75.463146 -150.563326)
		(width 0.127)
		(layer "In5.Cu")
		(net "I2C_COMP_ALERT_N")
	)
	(segment
		(start 61.9252 -141.3256)
		(end 61.067442 -142.183358)
		(width 0.127)
		(layer "In5.Cu")
		(net "I2C_COMP_ALERT_N")
	)
	(segment
		(start 52.906168 -142.993618)
		(end 53.299868 -142.599918)
		(width 0.127)
		(layer "In5.Cu")
		(net "I2C_COMP_ALERT_N")
	)
	(segment
		(start 52.906168 -143.56334)
		(end 52.906168 -142.993618)
		(width 0.127)
		(layer "In5.Cu")
		(net "I2C_COMP_ALERT_N")
	)
	(segment
		(start 66.2686 -140.6906)
		(end 65.6336 -141.3256)
		(width 0.127)
		(layer "In5.Cu")
		(net "I2C_COMP_ALERT_N")
	)
	(segment
		(start 70.920356 -150.211282)
		(end 73.614026 -150.211282)
		(width 0.127)
		(layer "In5.Cu")
		(net "I2C_COMP_ALERT_N")
	)
	(segment
		(start 65.6336 -141.3256)
		(end 61.9252 -141.3256)
		(width 0.127)
		(layer "In5.Cu")
		(net "I2C_COMP_ALERT_N")
	)
	(segment
		(start 53.137054 -143.794226)
		(end 52.906168 -143.56334)
		(width 0.127)
		(layer "In5.Cu")
		(net "I2C_COMP_ALERT_N")
	)
	(segment
		(start 76.28382 -151.384)
		(end 78.1431 -151.384)
		(width 0.127)
		(layer "In5.Cu")
		(net "I2C_COMP_ALERT_N")
	)
	(segment
		(start 73.614026 -150.211282)
		(end 73.96607 -150.563326)
		(width 0.127)
		(layer "In5.Cu")
		(net "I2C_COMP_ALERT_N")
	)
	(segment
		(start 61.067442 -142.183358)
		(end 57.712864 -142.183358)
		(width 0.127)
		(layer "In5.Cu")
		(net "I2C_COMP_ALERT_N")
	)
	(via
		(at 88.432894 -150.434294)
		(size 0.6096)
		(drill 0.3048)
		(layers "F.Cu" "B.Cu")
		(net "I2C_BMC_COMP_SDA_R")
	)
	(segment
		(start 85.725508 -151.057102)
		(end 87.401908 -151.057102)
		(width 0.127)
		(layer "B.Cu")
		(net "I2C_BMC_COMP_SDA_R")
	)
	(segment
		(start 87.810086 -151.057102)
		(end 88.432894 -150.434294)
		(width 0.127)
		(layer "B.Cu")
		(net "I2C_BMC_COMP_SDA_R")
	)
	(segment
		(start 89.281 -149.586188)
		(end 88.432894 -150.434294)
		(width 0.127)
		(layer "B.Cu")
		(net "I2C_BMC_COMP_SDA_R")
	)
	(segment
		(start 87.401908 -151.057102)
		(end 87.810086 -151.057102)
		(width 0.127)
		(layer "B.Cu")
		(net "I2C_BMC_COMP_SDA_R")
	)
	(segment
		(start 89.281 -149.23516)
		(end 89.281 -149.586188)
		(width 0.127)
		(layer "B.Cu")
		(net "I2C_BMC_COMP_SDA_R")
	)
	(segment
		(start 61.687964 -146.588988)
		(end 61.546232 -146.73072)
		(width 0.127)
		(layer "F.Cu")
		(net "I2C_BMC_COMP_SDA_OUT")
	)
	(segment
		(start 62.857888 -146.588988)
		(end 61.687964 -146.588988)
		(width 0.127)
		(layer "F.Cu")
		(net "I2C_BMC_COMP_SDA_OUT")
	)
	(segment
		(start 65.538096 -147.66798)
		(end 66.001392 -148.131276)
		(width 0.127)
		(layer "F.Cu")
		(net "I2C_BMC_COMP_SDA_OUT")
	)
	(segment
		(start 63.93688 -147.66798)
		(end 65.538096 -147.66798)
		(width 0.127)
		(layer "F.Cu")
		(net "I2C_BMC_COMP_SDA_OUT")
	)
	(segment
		(start 61.546232 -146.73072)
		(end 61.546232 -147.74926)
		(width 0.127)
		(layer "F.Cu")
		(net "I2C_BMC_COMP_SDA_OUT")
	)
	(segment
		(start 63.1571 -146.8882)
		(end 63.93688 -147.66798)
		(width 0.127)
		(layer "F.Cu")
		(net "I2C_BMC_COMP_SDA_OUT")
	)
	(segment
		(start 63.1571 -146.8882)
		(end 62.857888 -146.588988)
		(width 0.127)
		(layer "F.Cu")
		(net "I2C_BMC_COMP_SDA_OUT")
	)
	(via
		(at 66.001392 -148.131276)
		(size 0.508)
		(drill 0.254)
		(layers "F.Cu" "B.Cu")
		(net "I2C_BMC_COMP_SDA_OUT")
	)
	(via
		(at 61.687964 -146.588988)
		(size 0.6604)
		(drill 0.3302)
		(layers "F.Cu" "B.Cu")
		(net "I2C_BMC_COMP_SDA_OUT")
	)
	(via
		(at 85.578442 -148.170646)
		(size 0.508)
		(drill 0.254)
		(layers "F.Cu" "B.Cu")
		(net "I2C_BMC_COMP_SDA_OUT")
	)
	(segment
		(start 87.401908 -150.168102)
		(end 87.401908 -148.862796)
		(width 0.127)
		(layer "B.Cu")
		(net "I2C_BMC_COMP_SDA_OUT")
	)
	(segment
		(start 87.401908 -148.862796)
		(end 86.709758 -148.170646)
		(width 0.127)
		(layer "B.Cu")
		(net "I2C_BMC_COMP_SDA_OUT")
	)
	(segment
		(start 85.725508 -150.406862)
		(end 87.163148 -150.406862)
		(width 0.127)
		(layer "B.Cu")
		(net "I2C_BMC_COMP_SDA_OUT")
	)
	(segment
		(start 86.709758 -148.170646)
		(end 85.578442 -148.170646)
		(width 0.127)
		(layer "B.Cu")
		(net "I2C_BMC_COMP_SDA_OUT")
	)
	(segment
		(start 87.163148 -150.406862)
		(end 87.401908 -150.168102)
		(width 0.127)
		(layer "B.Cu")
		(net "I2C_BMC_COMP_SDA_OUT")
	)
	(segment
		(start 75.642724 -148.566124)
		(end 76.933552 -149.856952)
		(width 0.127)
		(layer "In5.Cu")
		(net "I2C_BMC_COMP_SDA_OUT")
	)
	(segment
		(start 76.933552 -149.856952)
		(end 81.191354 -149.856952)
		(width 0.127)
		(layer "In5.Cu")
		(net "I2C_BMC_COMP_SDA_OUT")
	)
	(segment
		(start 68.880228 -148.566124)
		(end 75.642724 -148.566124)
		(width 0.127)
		(layer "In5.Cu")
		(net "I2C_BMC_COMP_SDA_OUT")
	)
	(segment
		(start 68.44538 -148.131276)
		(end 68.880228 -148.566124)
		(width 0.127)
		(layer "In5.Cu")
		(net "I2C_BMC_COMP_SDA_OUT")
	)
	(segment
		(start 66.001392 -148.131276)
		(end 68.44538 -148.131276)
		(width 0.127)
		(layer "In5.Cu")
		(net "I2C_BMC_COMP_SDA_OUT")
	)
	(segment
		(start 81.191354 -149.856952)
		(end 82.87766 -148.170646)
		(width 0.127)
		(layer "In5.Cu")
		(net "I2C_BMC_COMP_SDA_OUT")
	)
	(segment
		(start 82.87766 -148.170646)
		(end 85.578442 -148.170646)
		(width 0.127)
		(layer "In5.Cu")
		(net "I2C_BMC_COMP_SDA_OUT")
	)
	(segment
		(start 100.943664 -140.720064)
		(end 99.568 -139.3444)
		(width 0.127)
		(layer "F.Cu")
		(net "I2C_BMC_COMP_SDA")
	)
	(segment
		(start 100.6856 -148.209)
		(end 100.943664 -147.950936)
		(width 0.127)
		(layer "F.Cu")
		(net "I2C_BMC_COMP_SDA")
	)
	(segment
		(start 97.917 -116.1542)
		(end 100.2538 -113.8174)
		(width 0.127)
		(layer "F.Cu")
		(net "I2C_BMC_COMP_SDA")
	)
	(segment
		(start 106.906314 -23.017988)
		(end 110.509812 -19.41449)
		(width 0.127)
		(layer "F.Cu")
		(net "I2C_BMC_COMP_SDA")
	)
	(segment
		(start 96.8502 -127.575056)
		(end 96.8502 -122.323098)
		(width 0.127)
		(layer "F.Cu")
		(net "I2C_BMC_COMP_SDA")
	)
	(segment
		(start 97.5614 -118.153434)
		(end 97.917 -117.797834)
		(width 0.127)
		(layer "F.Cu")
		(net "I2C_BMC_COMP_SDA")
	)
	(segment
		(start 116.233194 -19.41449)
		(end 121.71426 -24.895556)
		(width 0.127)
		(layer "F.Cu")
		(net "I2C_BMC_COMP_SDA")
	)
	(segment
		(start 97.5614 -119.1006)
		(end 97.5614 -118.153434)
		(width 0.127)
		(layer "F.Cu")
		(net "I2C_BMC_COMP_SDA")
	)
	(segment
		(start 100.075746 -47.702216)
		(end 100.075746 -27.024076)
		(width 0.127)
		(layer "F.Cu")
		(net "I2C_BMC_COMP_SDA")
	)
	(segment
		(start 97.7392 -128.464056)
		(end 96.8502 -127.575056)
		(width 0.127)
		(layer "F.Cu")
		(net "I2C_BMC_COMP_SDA")
	)
	(segment
		(start 96.8502 -122.323098)
		(end 96.548702 -122.0216)
		(width 0.127)
		(layer "F.Cu")
		(net "I2C_BMC_COMP_SDA")
	)
	(segment
		(start 121.71426 -24.895556)
		(end 121.71426 -27.553412)
		(width 0.127)
		(layer "F.Cu")
		(net "I2C_BMC_COMP_SDA")
	)
	(segment
		(start 99.568 -134.493254)
		(end 99.0092 -133.934454)
		(width 0.127)
		(layer "F.Cu")
		(net "I2C_BMC_COMP_SDA")
	)
	(segment
		(start 97.7392 -129.88671)
		(end 97.7392 -128.464056)
		(width 0.127)
		(layer "F.Cu")
		(net "I2C_BMC_COMP_SDA")
	)
	(segment
		(start 110.509812 -19.41449)
		(end 116.233194 -19.41449)
		(width 0.127)
		(layer "F.Cu")
		(net "I2C_BMC_COMP_SDA")
	)
	(segment
		(start 96.548702 -122.0216)
		(end 96.8502 -121.720102)
		(width 0.127)
		(layer "F.Cu")
		(net "I2C_BMC_COMP_SDA")
	)
	(segment
		(start 96.8502 -121.720102)
		(end 96.8502 -119.8118)
		(width 0.127)
		(layer "F.Cu")
		(net "I2C_BMC_COMP_SDA")
	)
	(segment
		(start 99.0092 -131.15671)
		(end 97.7392 -129.88671)
		(width 0.127)
		(layer "F.Cu")
		(net "I2C_BMC_COMP_SDA")
	)
	(segment
		(start 100.2538 -47.88027)
		(end 100.075746 -47.702216)
		(width 0.127)
		(layer "F.Cu")
		(net "I2C_BMC_COMP_SDA")
	)
	(segment
		(start 119.041672 -40.658288)
		(end 117.899942 -41.800018)
		(width 0.127)
		(layer "F.Cu")
		(net "I2C_BMC_COMP_SDA")
	)
	(segment
		(start 104.081834 -23.017988)
		(end 106.906314 -23.017988)
		(width 0.127)
		(layer "F.Cu")
		(net "I2C_BMC_COMP_SDA")
	)
	(segment
		(start 121.71426 -27.553412)
		(end 119.041672 -30.226)
		(width 0.127)
		(layer "F.Cu")
		(net "I2C_BMC_COMP_SDA")
	)
	(segment
		(start 99.0092 -133.934454)
		(end 99.0092 -131.15671)
		(width 0.127)
		(layer "F.Cu")
		(net "I2C_BMC_COMP_SDA")
	)
	(segment
		(start 100.943664 -147.950936)
		(end 100.943664 -140.720064)
		(width 0.127)
		(layer "F.Cu")
		(net "I2C_BMC_COMP_SDA")
	)
	(segment
		(start 99.568 -139.3444)
		(end 99.568 -134.493254)
		(width 0.127)
		(layer "F.Cu")
		(net "I2C_BMC_COMP_SDA")
	)
	(segment
		(start 97.917 -117.797834)
		(end 97.917 -116.1542)
		(width 0.127)
		(layer "F.Cu")
		(net "I2C_BMC_COMP_SDA")
	)
	(segment
		(start 100.075746 -27.024076)
		(end 104.081834 -23.017988)
		(width 0.127)
		(layer "F.Cu")
		(net "I2C_BMC_COMP_SDA")
	)
	(segment
		(start 119.041672 -30.226)
		(end 119.041672 -40.658288)
		(width 0.127)
		(layer "F.Cu")
		(net "I2C_BMC_COMP_SDA")
	)
	(segment
		(start 96.8502 -119.8118)
		(end 97.5614 -119.1006)
		(width 0.127)
		(layer "F.Cu")
		(net "I2C_BMC_COMP_SDA")
	)
	(segment
		(start 100.2538 -113.8174)
		(end 100.2538 -47.88027)
		(width 0.127)
		(layer "F.Cu")
		(net "I2C_BMC_COMP_SDA")
	)
	(via
		(at 100.6856 -148.209)
		(size 0.508)
		(drill 0.254)
		(layers "F.Cu" "B.Cu")
		(net "I2C_BMC_COMP_SDA")
	)
	(via
		(at 88.337136 -148.363686)
		(size 0.508)
		(drill 0.254)
		(layers "F.Cu" "B.Cu")
		(net "I2C_BMC_COMP_SDA")
	)
	(via
		(at 96.548702 -122.0216)
		(size 0.6604)
		(drill 0.3302)
		(layers "F.Cu" "B.Cu")
		(net "I2C_BMC_COMP_SDA")
	)
	(segment
		(start 89.281 -148.34616)
		(end 88.354662 -148.34616)
		(width 0.127)
		(layer "B.Cu")
		(net "I2C_BMC_COMP_SDA")
	)
	(segment
		(start 88.354662 -148.34616)
		(end 88.337136 -148.363686)
		(width 0.127)
		(layer "B.Cu")
		(net "I2C_BMC_COMP_SDA")
	)
	(segment
		(start 94.318836 -147.9296)
		(end 93.38818 -146.998944)
		(width 0.127)
		(layer "In5.Cu")
		(net "I2C_BMC_COMP_SDA")
	)
	(segment
		(start 91.18854 -146.998944)
		(end 89.823798 -148.363686)
		(width 0.127)
		(layer "In5.Cu")
		(net "I2C_BMC_COMP_SDA")
	)
	(segment
		(start 97.861882 -147.9296)
		(end 94.318836 -147.9296)
		(width 0.127)
		(layer "In5.Cu")
		(net "I2C_BMC_COMP_SDA")
	)
	(segment
		(start 89.823798 -148.363686)
		(end 88.337136 -148.363686)
		(width 0.127)
		(layer "In5.Cu")
		(net "I2C_BMC_COMP_SDA")
	)
	(segment
		(start 98.276918 -147.9296)
		(end 98.264218 -147.9423)
		(width 0.127)
		(layer "In5.Cu")
		(net "I2C_BMC_COMP_SDA")
	)
	(segment
		(start 100.6856 -148.209)
		(end 100.4062 -147.9296)
		(width 0.127)
		(layer "In5.Cu")
		(net "I2C_BMC_COMP_SDA")
	)
	(segment
		(start 97.874582 -147.9423)
		(end 97.861882 -147.9296)
		(width 0.127)
		(layer "In5.Cu")
		(net "I2C_BMC_COMP_SDA")
	)
	(segment
		(start 98.264218 -147.9423)
		(end 97.874582 -147.9423)
		(width 0.127)
		(layer "In5.Cu")
		(net "I2C_BMC_COMP_SDA")
	)
	(segment
		(start 100.4062 -147.9296)
		(end 98.276918 -147.9296)
		(width 0.127)
		(layer "In5.Cu")
		(net "I2C_BMC_COMP_SDA")
	)
	(segment
		(start 93.38818 -146.998944)
		(end 91.18854 -146.998944)
		(width 0.127)
		(layer "In5.Cu")
		(net "I2C_BMC_COMP_SDA")
	)
	(segment
		(start 86.868 -149.86)
		(end 86.868 -149.2885)
		(width 0.127)
		(layer "F.Cu")
		(net "I2C_BMC_COMP_SCL_R")
	)
	(segment
		(start 87.532464 -149.907498)
		(end 87.532464 -148.809964)
		(width 0.127)
		(layer "F.Cu")
		(net "I2C_BMC_COMP_SCL_R")
	)
	(segment
		(start 86.868 -149.2885)
		(end 87.4395 -148.717)
		(width 0.127)
		(layer "F.Cu")
		(net "I2C_BMC_COMP_SCL_R")
	)
	(segment
		(start 87.532464 -151.068786)
		(end 87.532464 -149.907498)
		(width 0.127)
		(layer "F.Cu")
		(net "I2C_BMC_COMP_SCL_R")
	)
	(segment
		(start 86.50224 -150.22576)
		(end 86.868 -149.86)
		(width 0.127)
		(layer "F.Cu")
		(net "I2C_BMC_COMP_SCL_R")
	)
	(segment
		(start 87.532464 -148.809964)
		(end 87.4395 -148.717)
		(width 0.127)
		(layer "F.Cu")
		(net "I2C_BMC_COMP_SCL_R")
	)
	(segment
		(start 85.7885 -150.22576)
		(end 86.50224 -150.22576)
		(width 0.127)
		(layer "F.Cu")
		(net "I2C_BMC_COMP_SCL_R")
	)
	(via
		(at 87.532464 -149.907498)
		(size 0.6604)
		(drill 0.3302)
		(layers "F.Cu" "B.Cu")
		(net "I2C_BMC_COMP_SCL_R")
	)
	(segment
		(start 85.895688 -148.717)
		(end 85.578442 -149.034246)
		(width 0.127)
		(layer "F.Cu")
		(net "I2C_BMC_COMP_SCL_OUT")
	)
	(segment
		(start 63.609982 -148.17598)
		(end 64.902334 -148.17598)
		(width 0.127)
		(layer "F.Cu")
		(net "I2C_BMC_COMP_SCL_OUT")
	)
	(segment
		(start 85.803994 -149.606)
		(end 85.217 -149.606)
		(width 0.127)
		(layer "F.Cu")
		(net "I2C_BMC_COMP_SCL_OUT")
	)
	(segment
		(start 84.963 -150.749)
		(end 85.09 -150.876)
		(width 0.127)
		(layer "F.Cu")
		(net "I2C_BMC_COMP_SCL_OUT")
	)
	(segment
		(start 62.9031 -148.7678)
		(end 63.018162 -148.7678)
		(width 0.127)
		(layer "F.Cu")
		(net "I2C_BMC_COMP_SCL_OUT")
	)
	(segment
		(start 65.330324 -148.60397)
		(end 65.00749 -148.281136)
		(width 0.127)
		(layer "F.Cu")
		(net "I2C_BMC_COMP_SCL_OUT")
	)
	(segment
		(start 85.217 -149.606)
		(end 84.963 -149.86)
		(width 0.127)
		(layer "F.Cu")
		(net "I2C_BMC_COMP_SCL_OUT")
	)
	(segment
		(start 84.963 -149.86)
		(end 84.963 -150.749)
		(width 0.127)
		(layer "F.Cu")
		(net "I2C_BMC_COMP_SCL_OUT")
	)
	(segment
		(start 61.8871 -148.7678)
		(end 62.9031 -148.7678)
		(width 0.127)
		(layer "F.Cu")
		(net "I2C_BMC_COMP_SCL_OUT")
	)
	(segment
		(start 63.018162 -148.7678)
		(end 63.609982 -148.17598)
		(width 0.127)
		(layer "F.Cu")
		(net "I2C_BMC_COMP_SCL_OUT")
	)
	(segment
		(start 64.902334 -148.17598)
		(end 65.00749 -148.281136)
		(width 0.127)
		(layer "F.Cu")
		(net "I2C_BMC_COMP_SCL_OUT")
	)
	(segment
		(start 86.5505 -148.859494)
		(end 85.803994 -149.606)
		(width 0.127)
		(layer "F.Cu")
		(net "I2C_BMC_COMP_SCL_OUT")
	)
	(segment
		(start 65.683384 -148.934424)
		(end 65.35293 -148.60397)
		(width 0.127)
		(layer "F.Cu")
		(net "I2C_BMC_COMP_SCL_OUT")
	)
	(segment
		(start 65.35293 -148.60397)
		(end 65.330324 -148.60397)
		(width 0.127)
		(layer "F.Cu")
		(net "I2C_BMC_COMP_SCL_OUT")
	)
	(segment
		(start 86.5505 -148.717)
		(end 85.895688 -148.717)
		(width 0.127)
		(layer "F.Cu")
		(net "I2C_BMC_COMP_SCL_OUT")
	)
	(segment
		(start 85.09 -150.876)
		(end 85.7885 -150.876)
		(width 0.127)
		(layer "F.Cu")
		(net "I2C_BMC_COMP_SCL_OUT")
	)
	(segment
		(start 86.5505 -148.717)
		(end 86.5505 -148.859494)
		(width 0.127)
		(layer "F.Cu")
		(net "I2C_BMC_COMP_SCL_OUT")
	)
	(via
		(at 85.578442 -149.034246)
		(size 0.508)
		(drill 0.254)
		(layers "F.Cu" "B.Cu")
		(net "I2C_BMC_COMP_SCL_OUT")
	)
	(via
		(at 65.00749 -148.281136)
		(size 0.6604)
		(drill 0.3302)
		(layers "F.Cu" "B.Cu")
		(net "I2C_BMC_COMP_SCL_OUT")
	)
	(via
		(at 65.683384 -148.934424)
		(size 0.508)
		(drill 0.254)
		(layers "F.Cu" "B.Cu")
		(net "I2C_BMC_COMP_SCL_OUT")
	)
	(segment
		(start 65.706498 -148.91131)
		(end 65.683384 -148.934424)
		(width 0.127)
		(layer "In5.Cu")
		(net "I2C_BMC_COMP_SCL_OUT")
	)
	(segment
		(start 74.692764 -149.074378)
		(end 68.669916 -149.074378)
		(width 0.127)
		(layer "In5.Cu")
		(net "I2C_BMC_COMP_SCL_OUT")
	)
	(segment
		(start 81.40192 -150.364952)
		(end 75.983338 -150.364952)
		(width 0.127)
		(layer "In5.Cu")
		(net "I2C_BMC_COMP_SCL_OUT")
	)
	(segment
		(start 68.669916 -149.074378)
		(end 68.506848 -148.91131)
		(width 0.127)
		(layer "In5.Cu")
		(net "I2C_BMC_COMP_SCL_OUT")
	)
	(segment
		(start 82.732626 -149.034246)
		(end 81.40192 -150.364952)
		(width 0.127)
		(layer "In5.Cu")
		(net "I2C_BMC_COMP_SCL_OUT")
	)
	(segment
		(start 68.506848 -148.91131)
		(end 65.706498 -148.91131)
		(width 0.127)
		(layer "In5.Cu")
		(net "I2C_BMC_COMP_SCL_OUT")
	)
	(segment
		(start 75.983338 -150.364952)
		(end 74.692764 -149.074378)
		(width 0.127)
		(layer "In5.Cu")
		(net "I2C_BMC_COMP_SCL_OUT")
	)
	(segment
		(start 85.578442 -149.034246)
		(end 82.732626 -149.034246)
		(width 0.127)
		(layer "In5.Cu")
		(net "I2C_BMC_COMP_SCL_OUT")
	)
	(segment
		(start 98.2472 -129.676144)
		(end 98.2472 -128.25349)
		(width 0.127)
		(layer "F.Cu")
		(net "I2C_BMC_COMP_SCL")
	)
	(segment
		(start 97.4344 -120.269)
		(end 98.0694 -119.634)
		(width 0.127)
		(layer "F.Cu")
		(net "I2C_BMC_COMP_SCL")
	)
	(segment
		(start 98.0694 -119.634)
		(end 98.0694 -118.364)
		(width 0.127)
		(layer "F.Cu")
		(net "I2C_BMC_COMP_SCL")
	)
	(segment
		(start 100.583746 -27.234642)
		(end 104.2924 -23.525988)
		(width 0.127)
		(layer "F.Cu")
		(net "I2C_BMC_COMP_SCL")
	)
	(segment
		(start 100.7618 -114.295936)
		(end 100.7618 -47.669704)
		(width 0.127)
		(layer "F.Cu")
		(net "I2C_BMC_COMP_SCL")
	)
	(segment
		(start 110.720378 -19.92249)
		(end 116.022628 -19.92249)
		(width 0.127)
		(layer "F.Cu")
		(net "I2C_BMC_COMP_SCL")
	)
	(segment
		(start 88.337136 -150.959058)
		(end 88.337136 -149.227286)
		(width 0.127)
		(layer "F.Cu")
		(net "I2C_BMC_COMP_SCL")
	)
	(segment
		(start 88.421464 -151.068786)
		(end 88.337136 -150.959058)
		(width 0.127)
		(layer "F.Cu")
		(net "I2C_BMC_COMP_SCL")
	)
	(segment
		(start 98.8949 -116.162836)
		(end 100.7618 -114.295936)
		(width 0.127)
		(layer "F.Cu")
		(net "I2C_BMC_COMP_SCL")
	)
	(segment
		(start 97.3836 -120.3198)
		(end 97.4344 -120.269)
		(width 0.127)
		(layer "F.Cu")
		(net "I2C_BMC_COMP_SCL")
	)
	(segment
		(start 99.5172 -133.723888)
		(end 99.5172 -130.946144)
		(width 0.127)
		(layer "F.Cu")
		(net "I2C_BMC_COMP_SCL")
	)
	(segment
		(start 121.20626 -27.342846)
		(end 118.533672 -30.015434)
		(width 0.127)
		(layer "F.Cu")
		(net "I2C_BMC_COMP_SCL")
	)
	(segment
		(start 118.533672 -39.76624)
		(end 117.899942 -40.39997)
		(width 0.127)
		(layer "F.Cu")
		(net "I2C_BMC_COMP_SCL")
	)
	(segment
		(start 100.076 -137.2362)
		(end 100.076 -134.282688)
		(width 0.127)
		(layer "F.Cu")
		(net "I2C_BMC_COMP_SCL")
	)
	(segment
		(start 107.11688 -23.525988)
		(end 110.720378 -19.92249)
		(width 0.127)
		(layer "F.Cu")
		(net "I2C_BMC_COMP_SCL")
	)
	(segment
		(start 98.0694 -118.364)
		(end 98.8949 -117.5385)
		(width 0.127)
		(layer "F.Cu")
		(net "I2C_BMC_COMP_SCL")
	)
	(segment
		(start 121.20626 -25.106122)
		(end 121.20626 -27.342846)
		(width 0.127)
		(layer "F.Cu")
		(net "I2C_BMC_COMP_SCL")
	)
	(segment
		(start 116.022628 -19.92249)
		(end 121.20626 -25.106122)
		(width 0.127)
		(layer "F.Cu")
		(net "I2C_BMC_COMP_SCL")
	)
	(segment
		(start 98.8949 -117.5385)
		(end 98.8949 -116.162836)
		(width 0.127)
		(layer "F.Cu")
		(net "I2C_BMC_COMP_SCL")
	)
	(segment
		(start 100.7618 -47.669704)
		(end 100.583746 -47.49165)
		(width 0.127)
		(layer "F.Cu")
		(net "I2C_BMC_COMP_SCL")
	)
	(segment
		(start 101.451664 -138.611864)
		(end 100.076 -137.2362)
		(width 0.127)
		(layer "F.Cu")
		(net "I2C_BMC_COMP_SCL")
	)
	(segment
		(start 100.076 -134.282688)
		(end 99.5172 -133.723888)
		(width 0.127)
		(layer "F.Cu")
		(net "I2C_BMC_COMP_SCL")
	)
	(segment
		(start 99.5172 -130.946144)
		(end 98.2472 -129.676144)
		(width 0.127)
		(layer "F.Cu")
		(net "I2C_BMC_COMP_SCL")
	)
	(segment
		(start 98.2472 -128.25349)
		(end 97.3836 -127.38989)
		(width 0.127)
		(layer "F.Cu")
		(net "I2C_BMC_COMP_SCL")
	)
	(segment
		(start 97.3836 -127.38989)
		(end 97.3836 -120.3198)
		(width 0.127)
		(layer "F.Cu")
		(net "I2C_BMC_COMP_SCL")
	)
	(segment
		(start 118.533672 -30.015434)
		(end 118.533672 -39.76624)
		(width 0.127)
		(layer "F.Cu")
		(net "I2C_BMC_COMP_SCL")
	)
	(segment
		(start 101.451664 -148.306536)
		(end 101.451664 -138.611864)
		(width 0.127)
		(layer "F.Cu")
		(net "I2C_BMC_COMP_SCL")
	)
	(segment
		(start 100.583746 -47.49165)
		(end 100.583746 -27.234642)
		(width 0.127)
		(layer "F.Cu")
		(net "I2C_BMC_COMP_SCL")
	)
	(segment
		(start 104.2924 -23.525988)
		(end 107.11688 -23.525988)
		(width 0.127)
		(layer "F.Cu")
		(net "I2C_BMC_COMP_SCL")
	)
	(segment
		(start 100.6602 -149.098)
		(end 101.451664 -148.306536)
		(width 0.127)
		(layer "F.Cu")
		(net "I2C_BMC_COMP_SCL")
	)
	(via
		(at 100.6602 -149.098)
		(size 0.508)
		(drill 0.254)
		(layers "F.Cu" "B.Cu")
		(net "I2C_BMC_COMP_SCL")
	)
	(via
		(at 97.4344 -120.269)
		(size 0.6604)
		(drill 0.3302)
		(layers "F.Cu" "B.Cu")
		(net "I2C_BMC_COMP_SCL")
	)
	(via
		(at 88.337136 -149.227286)
		(size 0.508)
		(drill 0.254)
		(layers "F.Cu" "B.Cu")
		(net "I2C_BMC_COMP_SCL")
	)
	(segment
		(start 100.6602 -149.098)
		(end 100.076 -148.5138)
		(width 0.127)
		(layer "In5.Cu")
		(net "I2C_BMC_COMP_SCL")
	)
	(segment
		(start 93.177614 -147.506944)
		(end 91.399106 -147.506944)
		(width 0.127)
		(layer "In5.Cu")
		(net "I2C_BMC_COMP_SCL")
	)
	(segment
		(start 88.66124 -148.903182)
		(end 88.337136 -149.227286)
		(width 0.127)
		(layer "In5.Cu")
		(net "I2C_BMC_COMP_SCL")
	)
	(segment
		(start 91.399106 -147.506944)
		(end 90.002868 -148.903182)
		(width 0.127)
		(layer "In5.Cu")
		(net "I2C_BMC_COMP_SCL")
	)
	(segment
		(start 100.076 -148.5138)
		(end 94.18447 -148.5138)
		(width 0.127)
		(layer "In5.Cu")
		(net "I2C_BMC_COMP_SCL")
	)
	(segment
		(start 94.18447 -148.5138)
		(end 93.177614 -147.506944)
		(width 0.127)
		(layer "In5.Cu")
		(net "I2C_BMC_COMP_SCL")
	)
	(segment
		(start 90.002868 -148.903182)
		(end 88.66124 -148.903182)
		(width 0.127)
		(layer "In5.Cu")
		(net "I2C_BMC_COMP_SCL")
	)
	(via
		(at 78.68031 -154.4828)
		(size 0.6096)
		(drill 0.3048)
		(layers "F.Cu" "B.Cu")
		(net "I2C_BMC_COMP_ALERT_N_R")
	)
	(segment
		(start 79.41437 -154.4828)
		(end 79.901288 -153.995882)
		(width 0.127)
		(layer "B.Cu")
		(net "I2C_BMC_COMP_ALERT_N_R")
	)
	(segment
		(start 78.68031 -154.4828)
		(end 78.68031 -153.3525)
		(width 0.127)
		(layer "B.Cu")
		(net "I2C_BMC_COMP_ALERT_N_R")
	)
	(segment
		(start 78.68031 -153.3525)
		(end 78.2955 -153.3525)
		(width 0.127)
		(layer "B.Cu")
		(net "I2C_BMC_COMP_ALERT_N_R")
	)
	(segment
		(start 78.2955 -153.3525)
		(end 77.53604 -152.59304)
		(width 0.127)
		(layer "B.Cu")
		(net "I2C_BMC_COMP_ALERT_N_R")
	)
	(segment
		(start 78.68031 -154.4828)
		(end 79.41437 -154.4828)
		(width 0.127)
		(layer "B.Cu")
		(net "I2C_BMC_COMP_ALERT_N_R")
	)
	(segment
		(start 77.53604 -152.59304)
		(end 77.0255 -152.59304)
		(width 0.127)
		(layer "B.Cu")
		(net "I2C_BMC_COMP_ALERT_N_R")
	)
	(via
		(at 89.589864 -149.99589)
		(size 0.508)
		(drill 0.254)
		(layers "F.Cu" "B.Cu")
		(net "I2C_BMC_COMP_ALERT_N")
	)
	(via
		(at 96.665288 -150.39213)
		(size 0.508)
		(drill 0.254)
		(layers "F.Cu" "B.Cu")
		(net "I2C_BMC_COMP_ALERT_N")
	)
	(via
		(at 88.239092 -152.322276)
		(size 0.6096)
		(drill 0.3048)
		(layers "F.Cu" "B.Cu")
		(net "I2C_BMC_COMP_ALERT_N")
	)
	(segment
		(start 83.881722 -154.219656)
		(end 81.014062 -154.219656)
		(width 0.127)
		(layer "B.Cu")
		(net "I2C_BMC_COMP_ALERT_N")
	)
	(segment
		(start 81.014062 -154.219656)
		(end 80.790288 -153.995882)
		(width 0.127)
		(layer "B.Cu")
		(net "I2C_BMC_COMP_ALERT_N")
	)
	(segment
		(start 89.589864 -149.99589)
		(end 89.085166 -150.500588)
		(width 0.127)
		(layer "B.Cu")
		(net "I2C_BMC_COMP_ALERT_N")
	)
	(segment
		(start 86.743794 -153.817574)
		(end 84.283804 -153.817574)
		(width 0.127)
		(layer "B.Cu")
		(net "I2C_BMC_COMP_ALERT_N")
	)
	(segment
		(start 89.085166 -150.500588)
		(end 89.085166 -151.476202)
		(width 0.127)
		(layer "B.Cu")
		(net "I2C_BMC_COMP_ALERT_N")
	)
	(segment
		(start 84.283804 -153.817574)
		(end 83.881722 -154.219656)
		(width 0.127)
		(layer "B.Cu")
		(net "I2C_BMC_COMP_ALERT_N")
	)
	(segment
		(start 88.239092 -152.322276)
		(end 86.743794 -153.817574)
		(width 0.127)
		(layer "B.Cu")
		(net "I2C_BMC_COMP_ALERT_N")
	)
	(segment
		(start 89.085166 -151.476202)
		(end 88.239092 -152.322276)
		(width 0.127)
		(layer "B.Cu")
		(net "I2C_BMC_COMP_ALERT_N")
	)
	(segment
		(start 95.452692 -83.22945)
		(end 95.452692 -83.972908)
		(width 0.127)
		(layer "In2.Cu")
		(net "I2C_BMC_COMP_ALERT_N")
	)
	(segment
		(start 96.638618 -145.322036)
		(end 94.9198 -147.040854)
		(width 0.127)
		(layer "In2.Cu")
		(net "I2C_BMC_COMP_ALERT_N")
	)
	(segment
		(start 94.9198 -148.646642)
		(end 96.665288 -150.39213)
		(width 0.127)
		(layer "In2.Cu")
		(net "I2C_BMC_COMP_ALERT_N")
	)
	(segment
		(start 94.9198 -147.040854)
		(end 94.9198 -148.646642)
		(width 0.127)
		(layer "In2.Cu")
		(net "I2C_BMC_COMP_ALERT_N")
	)
	(segment
		(start 94.8436 -84.582)
		(end 94.8436 -92.60967)
		(width 0.127)
		(layer "In2.Cu")
		(net "I2C_BMC_COMP_ALERT_N")
	)
	(segment
		(start 95.2246 -93.28912)
		(end 95.8342 -93.89872)
		(width 0.127)
		(layer "In2.Cu")
		(net "I2C_BMC_COMP_ALERT_N")
	)
	(segment
		(start 95.401892 -122.300492)
		(end 95.401892 -125.468126)
		(width 0.127)
		(layer "In2.Cu")
		(net "I2C_BMC_COMP_ALERT_N")
	)
	(segment
		(start 94.3864 -115.384834)
		(end 94.3864 -118.6688)
		(width 0.127)
		(layer "In2.Cu")
		(net "I2C_BMC_COMP_ALERT_N")
	)
	(segment
		(start 95.452692 -83.972908)
		(end 94.8436 -84.582)
		(width 0.127)
		(layer "In2.Cu")
		(net "I2C_BMC_COMP_ALERT_N")
	)
	(segment
		(start 96.638618 -137.978134)
		(end 96.638618 -145.322036)
		(width 0.127)
		(layer "In2.Cu")
		(net "I2C_BMC_COMP_ALERT_N")
	)
	(segment
		(start 95.8342 -93.89872)
		(end 95.8342 -111.600234)
		(width 0.127)
		(layer "In2.Cu")
		(net "I2C_BMC_COMP_ALERT_N")
	)
	(segment
		(start 94.0816 -113.352834)
		(end 94.0816 -115.080034)
		(width 0.127)
		(layer "In2.Cu")
		(net "I2C_BMC_COMP_ALERT_N")
	)
	(segment
		(start 96.333818 -137.673334)
		(end 96.638618 -137.978134)
		(width 0.127)
		(layer "In2.Cu")
		(net "I2C_BMC_COMP_ALERT_N")
	)
	(segment
		(start 94.8436 -82.620358)
		(end 95.452692 -83.22945)
		(width 0.127)
		(layer "In2.Cu")
		(net "I2C_BMC_COMP_ALERT_N")
	)
	(segment
		(start 96.333818 -126.400052)
		(end 96.333818 -137.673334)
		(width 0.127)
		(layer "In2.Cu")
		(net "I2C_BMC_COMP_ALERT_N")
	)
	(segment
		(start 94.8436 -64.8462)
		(end 94.8436 -82.620358)
		(width 0.127)
		(layer "In2.Cu")
		(net "I2C_BMC_COMP_ALERT_N")
	)
	(segment
		(start 119.70004 -40.600122)
		(end 120.77954 -39.520622)
		(width 0.127)
		(layer "In2.Cu")
		(net "I2C_BMC_COMP_ALERT_N")
	)
	(segment
		(start 120.77954 -29.766006)
		(end 114.35715 -23.343616)
		(width 0.127)
		(layer "In2.Cu")
		(net "I2C_BMC_COMP_ALERT_N")
	)
	(segment
		(start 104.089708 -23.343616)
		(end 97.713546 -29.719778)
		(width 0.127)
		(layer "In2.Cu")
		(net "I2C_BMC_COMP_ALERT_N")
	)
	(segment
		(start 94.850204 -119.132604)
		(end 94.850204 -121.748804)
		(width 0.127)
		(layer "In2.Cu")
		(net "I2C_BMC_COMP_ALERT_N")
	)
	(segment
		(start 97.713546 -34.439098)
		(end 95.377 -36.775644)
		(width 0.127)
		(layer "In2.Cu")
		(net "I2C_BMC_COMP_ALERT_N")
	)
	(segment
		(start 94.0816 -115.080034)
		(end 94.3864 -115.384834)
		(width 0.127)
		(layer "In2.Cu")
		(net "I2C_BMC_COMP_ALERT_N")
	)
	(segment
		(start 95.8342 -111.600234)
		(end 94.0816 -113.352834)
		(width 0.127)
		(layer "In2.Cu")
		(net "I2C_BMC_COMP_ALERT_N")
	)
	(segment
		(start 94.3864 -118.6688)
		(end 94.850204 -119.132604)
		(width 0.127)
		(layer "In2.Cu")
		(net "I2C_BMC_COMP_ALERT_N")
	)
	(segment
		(start 94.850204 -121.748804)
		(end 95.401892 -122.300492)
		(width 0.127)
		(layer "In2.Cu")
		(net "I2C_BMC_COMP_ALERT_N")
	)
	(segment
		(start 94.8436 -92.60967)
		(end 95.2246 -92.99067)
		(width 0.127)
		(layer "In2.Cu")
		(net "I2C_BMC_COMP_ALERT_N")
	)
	(segment
		(start 95.401892 -125.468126)
		(end 96.333818 -126.400052)
		(width 0.127)
		(layer "In2.Cu")
		(net "I2C_BMC_COMP_ALERT_N")
	)
	(segment
		(start 114.35715 -23.343616)
		(end 104.089708 -23.343616)
		(width 0.127)
		(layer "In2.Cu")
		(net "I2C_BMC_COMP_ALERT_N")
	)
	(segment
		(start 95.2246 -92.99067)
		(end 95.2246 -93.28912)
		(width 0.127)
		(layer "In2.Cu")
		(net "I2C_BMC_COMP_ALERT_N")
	)
	(segment
		(start 97.713546 -29.719778)
		(end 97.713546 -34.439098)
		(width 0.127)
		(layer "In2.Cu")
		(net "I2C_BMC_COMP_ALERT_N")
	)
	(segment
		(start 120.77954 -39.520622)
		(end 120.77954 -29.766006)
		(width 0.127)
		(layer "In2.Cu")
		(net "I2C_BMC_COMP_ALERT_N")
	)
	(segment
		(start 95.377 -64.3128)
		(end 94.8436 -64.8462)
		(width 0.127)
		(layer "In2.Cu")
		(net "I2C_BMC_COMP_ALERT_N")
	)
	(segment
		(start 95.377 -36.775644)
		(end 95.377 -64.3128)
		(width 0.127)
		(layer "In2.Cu")
		(net "I2C_BMC_COMP_ALERT_N")
	)
	(segment
		(start 95.344234 -150.39213)
		(end 93.072204 -148.1201)
		(width 0.127)
		(layer "In5.Cu")
		(net "I2C_BMC_COMP_ALERT_N")
	)
	(segment
		(start 92.297504 -148.1201)
		(end 90.421714 -149.99589)
		(width 0.127)
		(layer "In5.Cu")
		(net "I2C_BMC_COMP_ALERT_N")
	)
	(segment
		(start 93.072204 -148.1201)
		(end 92.297504 -148.1201)
		(width 0.127)
		(layer "In5.Cu")
		(net "I2C_BMC_COMP_ALERT_N")
	)
	(segment
		(start 96.665288 -150.39213)
		(end 95.344234 -150.39213)
		(width 0.127)
		(layer "In5.Cu")
		(net "I2C_BMC_COMP_ALERT_N")
	)
	(segment
		(start 90.421714 -149.99589)
		(end 89.589864 -149.99589)
		(width 0.127)
		(layer "In5.Cu")
		(net "I2C_BMC_COMP_ALERT_N")
	)
	(segment
		(start 70.19544 -175.9839)
		(end 70.19544 -177.09134)
		(width 0.127)
		(layer "F.Cu")
		(net "RST_BMC_EXTRST_N_1")
	)
	(segment
		(start 70.19544 -177.09134)
		(end 70.2056 -177.1015)
		(width 0.127)
		(layer "F.Cu")
		(net "RST_BMC_EXTRST_N_1")
	)
	(via
		(at 69.8754 -129.4892)
		(size 0.508)
		(drill 0.254)
		(layers "F.Cu" "B.Cu")
		(net "RST_BMC_EXTRST_N_1")
	)
	(via
		(at 40.132 -126.746)
		(size 0.508)
		(drill 0.254)
		(layers "F.Cu" "B.Cu")
		(net "RST_BMC_EXTRST_N_1")
	)
	(via
		(at 70.2056 -177.1015)
		(size 0.508)
		(drill 0.254)
		(layers "F.Cu" "B.Cu")
		(net "RST_BMC_EXTRST_N_1")
	)
	(via
		(at 65.6082 -128.2065)
		(size 0.6096)
		(drill 0.3048)
		(layers "F.Cu" "B.Cu")
		(net "RST_BMC_EXTRST_N_1")
	)
	(via
		(at 52.705 -128.476248)
		(size 0.508)
		(drill 0.254)
		(layers "F.Cu" "B.Cu")
		(net "RST_BMC_EXTRST_N_1")
	)
	(segment
		(start 69.8754 -129.4892)
		(end 68.5927 -128.2065)
		(width 0.127)
		(layer "B.Cu")
		(net "RST_BMC_EXTRST_N_1")
	)
	(segment
		(start 54.514242 -128.87452)
		(end 54.36616 -128.726438)
		(width 0.127)
		(layer "B.Cu")
		(net "RST_BMC_EXTRST_N_1")
	)
	(segment
		(start 53.242972 -128.07442)
		(end 52.869592 -128.4478)
		(width 0.127)
		(layer "B.Cu")
		(net "RST_BMC_EXTRST_N_1")
	)
	(segment
		(start 40.206676 -127.534416)
		(end 40.206676 -126.820676)
		(width 0.127)
		(layer "B.Cu")
		(net "RST_BMC_EXTRST_N_1")
	)
	(segment
		(start 40.206676 -126.820676)
		(end 40.132 -126.746)
		(width 0.127)
		(layer "B.Cu")
		(net "RST_BMC_EXTRST_N_1")
	)
	(segment
		(start 68.5927 -128.2065)
		(end 65.6082 -128.2065)
		(width 0.127)
		(layer "B.Cu")
		(net "RST_BMC_EXTRST_N_1")
	)
	(segment
		(start 52.733448 -128.4478)
		(end 52.705 -128.476248)
		(width 0.127)
		(layer "B.Cu")
		(net "RST_BMC_EXTRST_N_1")
	)
	(segment
		(start 63.15583 -126.5682)
		(end 58.408316 -126.5682)
		(width 0.127)
		(layer "B.Cu")
		(net "RST_BMC_EXTRST_N_1")
	)
	(segment
		(start 56.242458 -128.87452)
		(end 54.514242 -128.87452)
		(width 0.127)
		(layer "B.Cu")
		(net "RST_BMC_EXTRST_N_1")
	)
	(segment
		(start 58.408316 -126.5682)
		(end 56.87314 -128.103376)
		(width 0.127)
		(layer "B.Cu")
		(net "RST_BMC_EXTRST_N_1")
	)
	(segment
		(start 56.87314 -128.243838)
		(end 56.242458 -128.87452)
		(width 0.127)
		(layer "B.Cu")
		(net "RST_BMC_EXTRST_N_1")
	)
	(segment
		(start 56.87314 -128.103376)
		(end 56.87314 -128.243838)
		(width 0.127)
		(layer "B.Cu")
		(net "RST_BMC_EXTRST_N_1")
	)
	(segment
		(start 65.6082 -128.2065)
		(end 64.79413 -128.2065)
		(width 0.127)
		(layer "B.Cu")
		(net "RST_BMC_EXTRST_N_1")
	)
	(segment
		(start 54.36616 -128.726438)
		(end 54.36616 -128.07442)
		(width 0.127)
		(layer "B.Cu")
		(net "RST_BMC_EXTRST_N_1")
	)
	(segment
		(start 54.36616 -128.07442)
		(end 53.242972 -128.07442)
		(width 0.127)
		(layer "B.Cu")
		(net "RST_BMC_EXTRST_N_1")
	)
	(segment
		(start 64.79413 -128.2065)
		(end 63.15583 -126.5682)
		(width 0.127)
		(layer "B.Cu")
		(net "RST_BMC_EXTRST_N_1")
	)
	(segment
		(start 52.869592 -128.4478)
		(end 52.733448 -128.4478)
		(width 0.127)
		(layer "B.Cu")
		(net "RST_BMC_EXTRST_N_1")
	)
	(segment
		(start 73.290176 -170.727624)
		(end 73.290176 -174.016924)
		(width 0.127)
		(layer "In2.Cu")
		(net "RST_BMC_EXTRST_N_1")
	)
	(segment
		(start 71.2978 -164.0078)
		(end 72.10298 -164.81298)
		(width 0.127)
		(layer "In2.Cu")
		(net "RST_BMC_EXTRST_N_1")
	)
	(segment
		(start 72.10298 -164.81298)
		(end 72.10298 -169.540428)
		(width 0.127)
		(layer "In2.Cu")
		(net "RST_BMC_EXTRST_N_1")
	)
	(segment
		(start 73.290176 -174.016924)
		(end 70.2056 -177.1015)
		(width 0.127)
		(layer "In2.Cu")
		(net "RST_BMC_EXTRST_N_1")
	)
	(segment
		(start 69.8754 -129.4892)
		(end 69.8754 -135.7376)
		(width 0.127)
		(layer "In2.Cu")
		(net "RST_BMC_EXTRST_N_1")
	)
	(segment
		(start 70.732142 -145.662142)
		(end 70.732142 -145.891504)
		(width 0.127)
		(layer "In2.Cu")
		(net "RST_BMC_EXTRST_N_1")
	)
	(segment
		(start 73.2917 -157.622748)
		(end 71.2978 -159.616648)
		(width 0.127)
		(layer "In2.Cu")
		(net "RST_BMC_EXTRST_N_1")
	)
	(segment
		(start 70.118224 -135.980424)
		(end 70.118224 -145.048224)
		(width 0.127)
		(layer "In2.Cu")
		(net "RST_BMC_EXTRST_N_1")
	)
	(segment
		(start 69.8754 -135.7376)
		(end 70.118224 -135.980424)
		(width 0.127)
		(layer "In2.Cu")
		(net "RST_BMC_EXTRST_N_1")
	)
	(segment
		(start 73.2917 -148.451062)
		(end 73.2917 -157.622748)
		(width 0.127)
		(layer "In2.Cu")
		(net "RST_BMC_EXTRST_N_1")
	)
	(segment
		(start 70.732142 -145.891504)
		(end 73.2917 -148.451062)
		(width 0.127)
		(layer "In2.Cu")
		(net "RST_BMC_EXTRST_N_1")
	)
	(segment
		(start 72.10298 -169.540428)
		(end 73.290176 -170.727624)
		(width 0.127)
		(layer "In2.Cu")
		(net "RST_BMC_EXTRST_N_1")
	)
	(segment
		(start 71.2978 -159.616648)
		(end 71.2978 -164.0078)
		(width 0.127)
		(layer "In2.Cu")
		(net "RST_BMC_EXTRST_N_1")
	)
	(segment
		(start 70.118224 -145.048224)
		(end 70.732142 -145.662142)
		(width 0.127)
		(layer "In2.Cu")
		(net "RST_BMC_EXTRST_N_1")
	)
	(segment
		(start 52.4256 -128.196848)
		(end 52.705 -128.476248)
		(width 0.127)
		(layer "In5.Cu")
		(net "RST_BMC_EXTRST_N_1")
	)
	(segment
		(start 48.046386 -128.196848)
		(end 52.4256 -128.196848)
		(width 0.127)
		(layer "In5.Cu")
		(net "RST_BMC_EXTRST_N_1")
	)
	(segment
		(start 42.296588 -128.6891)
		(end 47.554134 -128.6891)
		(width 0.127)
		(layer "In5.Cu")
		(net "RST_BMC_EXTRST_N_1")
	)
	(segment
		(start 40.353488 -126.746)
		(end 42.296588 -128.6891)
		(width 0.127)
		(layer "In5.Cu")
		(net "RST_BMC_EXTRST_N_1")
	)
	(segment
		(start 47.554134 -128.6891)
		(end 48.046386 -128.196848)
		(width 0.127)
		(layer "In5.Cu")
		(net "RST_BMC_EXTRST_N_1")
	)
	(segment
		(start 40.132 -126.746)
		(end 40.353488 -126.746)
		(width 0.127)
		(layer "In5.Cu")
		(net "RST_BMC_EXTRST_N_1")
	)
	(segment
		(start 85.323934 -46.272958)
		(end 85.324188 -46.273212)
		(width 0.127)
		(layer "F.Cu")
		(net "MEZZA_PRSNT1_N")
	)
	(segment
		(start 79.925164 -48.950118)
		(end 79.925164 -48.436276)
		(width 0.127)
		(layer "F.Cu")
		(net "MEZZA_PRSNT1_N")
	)
	(segment
		(start 80.386428 -47.975012)
		(end 83.043268 -47.975012)
		(width 0.127)
		(layer "F.Cu")
		(net "MEZZA_PRSNT1_N")
	)
	(segment
		(start 79.925164 -48.436276)
		(end 80.386428 -47.975012)
		(width 0.127)
		(layer "F.Cu")
		(net "MEZZA_PRSNT1_N")
	)
	(segment
		(start 85.324188 -46.273212)
		(end 85.53958 -46.273212)
		(width 0.127)
		(layer "F.Cu")
		(net "MEZZA_PRSNT1_N")
	)
	(segment
		(start 87.269828 -45.320712)
		(end 86.492334 -45.320712)
		(width 0.127)
		(layer "F.Cu")
		(net "MEZZA_PRSNT1_N")
	)
	(segment
		(start 85.53958 -46.273212)
		(end 86.09457 -45.718476)
		(width 0.127)
		(layer "F.Cu")
		(net "MEZZA_PRSNT1_N")
	)
	(segment
		(start 84.745322 -46.272958)
		(end 85.323934 -46.272958)
		(width 0.127)
		(layer "F.Cu")
		(net "MEZZA_PRSNT1_N")
	)
	(segment
		(start 87.269828 -45.320712)
		(end 88.336628 -45.320712)
		(width 0.127)
		(layer "F.Cu")
		(net "MEZZA_PRSNT1_N")
	)
	(segment
		(start 86.492334 -45.320712)
		(end 86.09457 -45.718476)
		(width 0.127)
		(layer "F.Cu")
		(net "MEZZA_PRSNT1_N")
	)
	(segment
		(start 88.336628 -45.320712)
		(end 88.400128 -45.384212)
		(width 0.127)
		(layer "F.Cu")
		(net "MEZZA_PRSNT1_N")
	)
	(segment
		(start 83.043268 -47.975012)
		(end 84.745322 -46.272958)
		(width 0.127)
		(layer "F.Cu")
		(net "MEZZA_PRSNT1_N")
	)
	(via
		(at 86.09457 -45.718476)
		(size 0.6604)
		(drill 0.3302)
		(layers "F.Cu" "B.Cu")
		(net "MEZZA_PRSNT1_N")
	)
	(segment
		(start 75.475084 -96.149922)
		(end 77.000354 -96.149922)
		(width 0.127)
		(layer "F.Cu")
		(net "MEZZ_A_PRSNT_120_N")
	)
	(segment
		(start 77.000354 -96.149922)
		(end 77.1906 -96.340168)
		(width 0.127)
		(layer "F.Cu")
		(net "MEZZ_A_PRSNT_120_N")
	)
	(segment
		(start 77.1906 -96.340168)
		(end 77.1906 -96.665796)
		(width 0.127)
		(layer "F.Cu")
		(net "MEZZ_A_PRSNT_120_N")
	)
	(via
		(at 84.024724 -99.650296)
		(size 0.6096)
		(drill 0.3048)
		(layers "F.Cu" "B.Cu")
		(net "MEZZ_A_PRSNT_120_N")
	)
	(via
		(at 77.1906 -96.665796)
		(size 0.508)
		(drill 0.254)
		(layers "F.Cu" "B.Cu")
		(net "MEZZ_A_PRSNT_120_N")
	)
	(segment
		(start 84.024724 -99.650296)
		(end 85.536024 -99.650296)
		(width 0.127)
		(layer "B.Cu")
		(net "MEZZ_A_PRSNT_120_N")
	)
	(segment
		(start 82.2706 -97.4344)
		(end 81.501996 -96.665796)
		(width 0.127)
		(layer "B.Cu")
		(net "MEZZ_A_PRSNT_120_N")
	)
	(segment
		(start 83.3247 -98.481896)
		(end 82.277204 -97.4344)
		(width 0.127)
		(layer "B.Cu")
		(net "MEZZ_A_PRSNT_120_N")
	)
	(segment
		(start 83.3247 -99.411028)
		(end 83.3247 -98.494596)
		(width 0.127)
		(layer "B.Cu")
		(net "MEZZ_A_PRSNT_120_N")
	)
	(segment
		(start 83.3247 -98.494596)
		(end 83.3247 -98.481896)
		(width 0.127)
		(layer "B.Cu")
		(net "MEZZ_A_PRSNT_120_N")
	)
	(segment
		(start 81.501996 -96.665796)
		(end 77.1906 -96.665796)
		(width 0.127)
		(layer "B.Cu")
		(net "MEZZ_A_PRSNT_120_N")
	)
	(segment
		(start 83.563968 -99.650296)
		(end 83.3247 -99.411028)
		(width 0.127)
		(layer "B.Cu")
		(net "MEZZ_A_PRSNT_120_N")
	)
	(segment
		(start 84.024724 -99.650296)
		(end 83.563968 -99.650296)
		(width 0.127)
		(layer "B.Cu")
		(net "MEZZ_A_PRSNT_120_N")
	)
	(segment
		(start 82.277204 -97.4344)
		(end 82.2706 -97.4344)
		(width 0.127)
		(layer "B.Cu")
		(net "MEZZ_A_PRSNT_120_N")
	)
	(segment
		(start 92.204032 -139.727686)
		(end 92.201238 -139.73048)
		(width 0.127)
		(layer "F.Cu")
		(net "LED_POSTCODE_7")
	)
	(segment
		(start 91.811602 -139.73048)
		(end 91.808808 -139.727686)
		(width 0.127)
		(layer "F.Cu")
		(net "LED_POSTCODE_7")
	)
	(segment
		(start 89.765632 -131.619244)
		(end 91.821762 -131.619244)
		(width 0.127)
		(layer "F.Cu")
		(net "LED_POSTCODE_7")
	)
	(segment
		(start 92.733114 -139.727686)
		(end 92.204032 -139.727686)
		(width 0.127)
		(layer "F.Cu")
		(net "LED_POSTCODE_7")
	)
	(segment
		(start 92.201238 -139.73048)
		(end 91.811602 -139.73048)
		(width 0.127)
		(layer "F.Cu")
		(net "LED_POSTCODE_7")
	)
	(segment
		(start 53.699918 -139.800076)
		(end 54.099968 -139.400026)
		(width 0.127)
		(layer "F.Cu")
		(net "LED_POSTCODE_7")
	)
	(segment
		(start 93.8149 -133.612382)
		(end 93.8149 -138.6459)
		(width 0.127)
		(layer "F.Cu")
		(net "LED_POSTCODE_7")
	)
	(segment
		(start 91.821762 -131.619244)
		(end 93.8149 -133.612382)
		(width 0.127)
		(layer "F.Cu")
		(net "LED_POSTCODE_7")
	)
	(segment
		(start 85.5472 -130.2512)
		(end 86.377018 -131.081018)
		(width 0.127)
		(layer "F.Cu")
		(net "LED_POSTCODE_7")
	)
	(segment
		(start 91.808808 -139.727686)
		(end 90.357706 -139.727686)
		(width 0.127)
		(layer "F.Cu")
		(net "LED_POSTCODE_7")
	)
	(segment
		(start 89.227406 -131.081018)
		(end 89.765632 -131.619244)
		(width 0.127)
		(layer "F.Cu")
		(net "LED_POSTCODE_7")
	)
	(segment
		(start 85.5472 -128.6002)
		(end 85.5472 -129.54)
		(width 0.127)
		(layer "F.Cu")
		(net "LED_POSTCODE_7")
	)
	(segment
		(start 86.377018 -131.081018)
		(end 89.227406 -131.081018)
		(width 0.127)
		(layer "F.Cu")
		(net "LED_POSTCODE_7")
	)
	(segment
		(start 93.8149 -138.6459)
		(end 92.733114 -139.727686)
		(width 0.127)
		(layer "F.Cu")
		(net "LED_POSTCODE_7")
	)
	(segment
		(start 85.5472 -129.54)
		(end 85.5472 -130.2512)
		(width 0.127)
		(layer "F.Cu")
		(net "LED_POSTCODE_7")
	)
	(via
		(at 59.2074 -129.4892)
		(size 0.508)
		(drill 0.254)
		(layers "F.Cu" "B.Cu")
		(net "LED_POSTCODE_7")
	)
	(via
		(at 54.099968 -139.400026)
		(size 0.4572)
		(drill 0.2032)
		(layers "F.Cu" "B.Cu")
		(net "LED_POSTCODE_7")
	)
	(via
		(at 85.5472 -128.6002)
		(size 0.508)
		(drill 0.254)
		(layers "F.Cu" "B.Cu")
		(net "LED_POSTCODE_7")
	)
	(via
		(at 85.5472 -129.54)
		(size 0.6604)
		(drill 0.3302)
		(layers "F.Cu" "B.Cu")
		(net "LED_POSTCODE_7")
	)
	(segment
		(start 58.645552 -129.4892)
		(end 55.293768 -132.840984)
		(width 0.127)
		(layer "In2.Cu")
		(net "LED_POSTCODE_7")
	)
	(segment
		(start 55.06339 -138.993626)
		(end 54.506368 -138.993626)
		(width 0.127)
		(layer "In2.Cu")
		(net "LED_POSTCODE_7")
	)
	(segment
		(start 54.506368 -138.993626)
		(end 54.099968 -139.400026)
		(width 0.127)
		(layer "In2.Cu")
		(net "LED_POSTCODE_7")
	)
	(segment
		(start 55.293768 -132.840984)
		(end 55.293768 -138.763248)
		(width 0.127)
		(layer "In2.Cu")
		(net "LED_POSTCODE_7")
	)
	(segment
		(start 59.2074 -129.4892)
		(end 58.645552 -129.4892)
		(width 0.127)
		(layer "In2.Cu")
		(net "LED_POSTCODE_7")
	)
	(segment
		(start 55.293768 -138.763248)
		(end 55.06339 -138.993626)
		(width 0.127)
		(layer "In2.Cu")
		(net "LED_POSTCODE_7")
	)
	(segment
		(start 83.1596 -129.5146)
		(end 81.1022 -129.5146)
		(width 0.127)
		(layer "In5.Cu")
		(net "LED_POSTCODE_7")
	)
	(segment
		(start 83.4898 -129.1844)
		(end 83.1596 -129.5146)
		(width 0.127)
		(layer "In5.Cu")
		(net "LED_POSTCODE_7")
	)
	(segment
		(start 80.645 -129.0574)
		(end 77.896212 -129.0574)
		(width 0.127)
		(layer "In5.Cu")
		(net "LED_POSTCODE_7")
	)
	(segment
		(start 60.468764 -130.7211)
		(end 59.236864 -129.4892)
		(width 0.127)
		(layer "In5.Cu")
		(net "LED_POSTCODE_7")
	)
	(segment
		(start 81.1022 -129.5146)
		(end 80.645 -129.0574)
		(width 0.127)
		(layer "In5.Cu")
		(net "LED_POSTCODE_7")
	)
	(segment
		(start 84.963 -129.1844)
		(end 83.4898 -129.1844)
		(width 0.127)
		(layer "In5.Cu")
		(net "LED_POSTCODE_7")
	)
	(segment
		(start 76.676758 -130.276854)
		(end 71.257922 -130.276854)
		(width 0.127)
		(layer "In5.Cu")
		(net "LED_POSTCODE_7")
	)
	(segment
		(start 70.813676 -130.7211)
		(end 60.468764 -130.7211)
		(width 0.127)
		(layer "In5.Cu")
		(net "LED_POSTCODE_7")
	)
	(segment
		(start 59.236864 -129.4892)
		(end 59.2074 -129.4892)
		(width 0.127)
		(layer "In5.Cu")
		(net "LED_POSTCODE_7")
	)
	(segment
		(start 77.896212 -129.0574)
		(end 76.676758 -130.276854)
		(width 0.127)
		(layer "In5.Cu")
		(net "LED_POSTCODE_7")
	)
	(segment
		(start 71.257922 -130.276854)
		(end 70.813676 -130.7211)
		(width 0.127)
		(layer "In5.Cu")
		(net "LED_POSTCODE_7")
	)
	(segment
		(start 85.5472 -128.6002)
		(end 84.963 -129.1844)
		(width 0.127)
		(layer "In5.Cu")
		(net "LED_POSTCODE_7")
	)
	(segment
		(start 57.869074 -140.250926)
		(end 57.991502 -140.250926)
		(width 0.127)
		(layer "F.Cu")
		(net "LED_POSTCODE_6")
	)
	(segment
		(start 89.728802 -140.377926)
		(end 88.543638 -139.192762)
		(width 0.127)
		(layer "F.Cu")
		(net "LED_POSTCODE_6")
	)
	(segment
		(start 56.099964 -141.400022)
		(end 56.719978 -141.400022)
		(width 0.127)
		(layer "F.Cu")
		(net "LED_POSTCODE_6")
	)
	(segment
		(start 83.8708 -135.0772)
		(end 84.387944 -135.594344)
		(width 0.127)
		(layer "F.Cu")
		(net "LED_POSTCODE_6")
	)
	(segment
		(start 84.387944 -135.626602)
		(end 87.522558 -138.761216)
		(width 0.127)
		(layer "F.Cu")
		(net "LED_POSTCODE_6")
	)
	(segment
		(start 87.522558 -138.761216)
		(end 88.112092 -138.761216)
		(width 0.127)
		(layer "F.Cu")
		(net "LED_POSTCODE_6")
	)
	(segment
		(start 84.387944 -135.594344)
		(end 84.387944 -135.626602)
		(width 0.127)
		(layer "F.Cu")
		(net "LED_POSTCODE_6")
	)
	(segment
		(start 90.357706 -140.377926)
		(end 89.728802 -140.377926)
		(width 0.127)
		(layer "F.Cu")
		(net "LED_POSTCODE_6")
	)
	(segment
		(start 56.719978 -141.400022)
		(end 57.869074 -140.250926)
		(width 0.127)
		(layer "F.Cu")
		(net "LED_POSTCODE_6")
	)
	(segment
		(start 88.112092 -138.761216)
		(end 88.543638 -139.192762)
		(width 0.127)
		(layer "F.Cu")
		(net "LED_POSTCODE_6")
	)
	(via
		(at 88.543638 -139.192762)
		(size 0.6604)
		(drill 0.3302)
		(layers "F.Cu" "B.Cu")
		(net "LED_POSTCODE_6")
	)
	(via
		(at 60.6044 -129.5146)
		(size 0.508)
		(drill 0.254)
		(layers "F.Cu" "B.Cu")
		(net "LED_POSTCODE_6")
	)
	(via
		(at 82.1436 -128.91516)
		(size 0.508)
		(drill 0.254)
		(layers "F.Cu" "B.Cu")
		(net "LED_POSTCODE_6")
	)
	(via
		(at 57.991502 -140.250926)
		(size 0.508)
		(drill 0.254)
		(layers "F.Cu" "B.Cu")
		(net "LED_POSTCODE_6")
	)
	(via
		(at 83.8708 -135.0772)
		(size 0.508)
		(drill 0.254)
		(layers "F.Cu" "B.Cu")
		(net "LED_POSTCODE_6")
	)
	(segment
		(start 57.2643 -134.852664)
		(end 57.2643 -139.523724)
		(width 0.127)
		(layer "In2.Cu")
		(net "LED_POSTCODE_6")
	)
	(segment
		(start 57.75071 -132.001006)
		(end 56.7055 -133.046216)
		(width 0.127)
		(layer "In2.Cu")
		(net "LED_POSTCODE_6")
	)
	(segment
		(start 56.7055 -134.293864)
		(end 57.2643 -134.852664)
		(width 0.127)
		(layer "In2.Cu")
		(net "LED_POSTCODE_6")
	)
	(segment
		(start 82.1436 -128.91516)
		(end 83.82 -130.59156)
		(width 0.127)
		(layer "In2.Cu")
		(net "LED_POSTCODE_6")
	)
	(segment
		(start 83.82 -130.59156)
		(end 83.82 -131.3434)
		(width 0.127)
		(layer "In2.Cu")
		(net "LED_POSTCODE_6")
	)
	(segment
		(start 83.3882 -131.7752)
		(end 83.3882 -133.382258)
		(width 0.127)
		(layer "In2.Cu")
		(net "LED_POSTCODE_6")
	)
	(segment
		(start 60.6044 -129.834894)
		(end 58.438288 -132.001006)
		(width 0.127)
		(layer "In2.Cu")
		(net "LED_POSTCODE_6")
	)
	(segment
		(start 60.6044 -129.5146)
		(end 60.6044 -129.834894)
		(width 0.127)
		(layer "In2.Cu")
		(net "LED_POSTCODE_6")
	)
	(segment
		(start 83.82 -131.3434)
		(end 83.3882 -131.7752)
		(width 0.127)
		(layer "In2.Cu")
		(net "LED_POSTCODE_6")
	)
	(segment
		(start 57.2643 -139.523724)
		(end 57.991502 -140.250926)
		(width 0.127)
		(layer "In2.Cu")
		(net "LED_POSTCODE_6")
	)
	(segment
		(start 56.7055 -133.046216)
		(end 56.7055 -134.293864)
		(width 0.127)
		(layer "In2.Cu")
		(net "LED_POSTCODE_6")
	)
	(segment
		(start 83.3882 -133.382258)
		(end 83.8708 -133.864858)
		(width 0.127)
		(layer "In2.Cu")
		(net "LED_POSTCODE_6")
	)
	(segment
		(start 58.438288 -132.001006)
		(end 57.75071 -132.001006)
		(width 0.127)
		(layer "In2.Cu")
		(net "LED_POSTCODE_6")
	)
	(segment
		(start 83.8708 -133.864858)
		(end 83.8708 -135.0772)
		(width 0.127)
		(layer "In2.Cu")
		(net "LED_POSTCODE_6")
	)
	(segment
		(start 81.8896 -128.6764)
		(end 77.738224 -128.6764)
		(width 0.127)
		(layer "In5.Cu")
		(net "LED_POSTCODE_6")
	)
	(segment
		(start 61.566552 -130.3401)
		(end 60.741052 -129.5146)
		(width 0.127)
		(layer "In5.Cu")
		(net "LED_POSTCODE_6")
	)
	(segment
		(start 60.741052 -129.5146)
		(end 60.6044 -129.5146)
		(width 0.127)
		(layer "In5.Cu")
		(net "LED_POSTCODE_6")
	)
	(segment
		(start 71.100188 -129.8956)
		(end 70.655688 -130.3401)
		(width 0.127)
		(layer "In5.Cu")
		(net "LED_POSTCODE_6")
	)
	(segment
		(start 77.738224 -128.6764)
		(end 76.519024 -129.8956)
		(width 0.127)
		(layer "In5.Cu")
		(net "LED_POSTCODE_6")
	)
	(segment
		(start 70.655688 -130.3401)
		(end 61.566552 -130.3401)
		(width 0.127)
		(layer "In5.Cu")
		(net "LED_POSTCODE_6")
	)
	(segment
		(start 82.1436 -128.91516)
		(end 82.12836 -128.91516)
		(width 0.127)
		(layer "In5.Cu")
		(net "LED_POSTCODE_6")
	)
	(segment
		(start 76.519024 -129.8956)
		(end 71.100188 -129.8956)
		(width 0.127)
		(layer "In5.Cu")
		(net "LED_POSTCODE_6")
	)
	(segment
		(start 82.12836 -128.91516)
		(end 81.8896 -128.6764)
		(width 0.127)
		(layer "In5.Cu")
		(net "LED_POSTCODE_6")
	)
	(segment
		(start 56.966104 -138.842496)
		(end 56.966104 -139.987274)
		(width 0.127)
		(layer "F.Cu")
		(net "LED_POSTCODE_5")
	)
	(segment
		(start 90.357706 -141.028166)
		(end 89.294462 -141.028166)
		(width 0.127)
		(layer "F.Cu")
		(net "LED_POSTCODE_5")
	)
	(segment
		(start 85.527642 -137.668)
		(end 85.555074 -137.695432)
		(width 0.127)
		(layer "F.Cu")
		(net "LED_POSTCODE_5")
	)
	(segment
		(start 56.719978 -140.2334)
		(end 55.666386 -140.2334)
		(width 0.127)
		(layer "F.Cu")
		(net "LED_POSTCODE_5")
	)
	(segment
		(start 89.294462 -141.028166)
		(end 88.753188 -140.486892)
		(width 0.127)
		(layer "F.Cu")
		(net "LED_POSTCODE_5")
	)
	(segment
		(start 55.666386 -140.2334)
		(end 55.299864 -140.599922)
		(width 0.127)
		(layer "F.Cu")
		(net "LED_POSTCODE_5")
	)
	(segment
		(start 87.269828 -139.142216)
		(end 87.408512 -139.142216)
		(width 0.127)
		(layer "F.Cu")
		(net "LED_POSTCODE_5")
	)
	(segment
		(start 56.966104 -139.987274)
		(end 56.719978 -140.2334)
		(width 0.127)
		(layer "F.Cu")
		(net "LED_POSTCODE_5")
	)
	(segment
		(start 87.408512 -139.142216)
		(end 88.753188 -140.486892)
		(width 0.127)
		(layer "F.Cu")
		(net "LED_POSTCODE_5")
	)
	(segment
		(start 85.823044 -137.695432)
		(end 87.269828 -139.142216)
		(width 0.127)
		(layer "F.Cu")
		(net "LED_POSTCODE_5")
	)
	(segment
		(start 85.555074 -137.695432)
		(end 85.823044 -137.695432)
		(width 0.127)
		(layer "F.Cu")
		(net "LED_POSTCODE_5")
	)
	(segment
		(start 58.1152 -137.6934)
		(end 56.966104 -138.842496)
		(width 0.127)
		(layer "F.Cu")
		(net "LED_POSTCODE_5")
	)
	(via
		(at 58.1152 -137.6934)
		(size 0.508)
		(drill 0.254)
		(layers "F.Cu" "B.Cu")
		(net "LED_POSTCODE_5")
	)
	(via
		(at 85.527642 -137.668)
		(size 0.508)
		(drill 0.254)
		(layers "F.Cu" "B.Cu")
		(net "LED_POSTCODE_5")
	)
	(via
		(at 88.753188 -140.486892)
		(size 0.6604)
		(drill 0.3302)
		(layers "F.Cu" "B.Cu")
		(net "LED_POSTCODE_5")
	)
	(via
		(at 57.6834 -133.4516)
		(size 0.508)
		(drill 0.254)
		(layers "F.Cu" "B.Cu")
		(net "LED_POSTCODE_5")
	)
	(via
		(at 83.2612 -130.7846)
		(size 0.508)
		(drill 0.254)
		(layers "F.Cu" "B.Cu")
		(net "LED_POSTCODE_5")
	)
	(segment
		(start 83.299554 -134.062978)
		(end 83.299554 -136.11352)
		(width 0.127)
		(layer "In2.Cu")
		(net "LED_POSTCODE_5")
	)
	(segment
		(start 83.299554 -136.11352)
		(end 84.09686 -136.910826)
		(width 0.127)
		(layer "In2.Cu")
		(net "LED_POSTCODE_5")
	)
	(segment
		(start 84.371942 -137.448798)
		(end 85.28177 -137.448798)
		(width 0.127)
		(layer "In2.Cu")
		(net "LED_POSTCODE_5")
	)
	(segment
		(start 57.6834 -133.4516)
		(end 57.962292 -133.730492)
		(width 0.127)
		(layer "In2.Cu")
		(net "LED_POSTCODE_5")
	)
	(segment
		(start 57.962292 -133.730492)
		(end 57.962292 -137.540492)
		(width 0.127)
		(layer "In2.Cu")
		(net "LED_POSTCODE_5")
	)
	(segment
		(start 57.962292 -137.540492)
		(end 58.1152 -137.6934)
		(width 0.127)
		(layer "In2.Cu")
		(net "LED_POSTCODE_5")
	)
	(segment
		(start 83.2612 -130.7846)
		(end 83.208368 -130.7846)
		(width 0.127)
		(layer "In2.Cu")
		(net "LED_POSTCODE_5")
	)
	(segment
		(start 83.0072 -133.770624)
		(end 83.299554 -134.062978)
		(width 0.127)
		(layer "In2.Cu")
		(net "LED_POSTCODE_5")
	)
	(segment
		(start 85.28177 -137.448798)
		(end 85.500972 -137.668)
		(width 0.127)
		(layer "In2.Cu")
		(net "LED_POSTCODE_5")
	)
	(segment
		(start 83.0072 -130.985768)
		(end 83.0072 -133.770624)
		(width 0.127)
		(layer "In2.Cu")
		(net "LED_POSTCODE_5")
	)
	(segment
		(start 85.500972 -137.668)
		(end 85.527642 -137.668)
		(width 0.127)
		(layer "In2.Cu")
		(net "LED_POSTCODE_5")
	)
	(segment
		(start 84.09686 -137.173716)
		(end 84.371942 -137.448798)
		(width 0.127)
		(layer "In2.Cu")
		(net "LED_POSTCODE_5")
	)
	(segment
		(start 83.208368 -130.7846)
		(end 83.0072 -130.985768)
		(width 0.127)
		(layer "In2.Cu")
		(net "LED_POSTCODE_5")
	)
	(segment
		(start 84.09686 -136.910826)
		(end 84.09686 -137.173716)
		(width 0.127)
		(layer "In2.Cu")
		(net "LED_POSTCODE_5")
	)
	(segment
		(start 79.040482 -131.6482)
		(end 75.311 -131.6482)
		(width 0.127)
		(layer "In5.Cu")
		(net "LED_POSTCODE_5")
	)
	(segment
		(start 75.311 -131.6482)
		(end 74.7522 -131.0894)
		(width 0.127)
		(layer "In5.Cu")
		(net "LED_POSTCODE_5")
	)
	(segment
		(start 59.4614 -131.6736)
		(end 57.6834 -133.4516)
		(width 0.127)
		(layer "In5.Cu")
		(net "LED_POSTCODE_5")
	)
	(segment
		(start 70.939152 -131.6736)
		(end 59.4614 -131.6736)
		(width 0.127)
		(layer "In5.Cu")
		(net "LED_POSTCODE_5")
	)
	(segment
		(start 74.7522 -131.0894)
		(end 71.523352 -131.0894)
		(width 0.127)
		(layer "In5.Cu")
		(net "LED_POSTCODE_5")
	)
	(segment
		(start 83.2612 -130.7846)
		(end 79.904082 -130.7846)
		(width 0.127)
		(layer "In5.Cu")
		(net "LED_POSTCODE_5")
	)
	(segment
		(start 71.523352 -131.0894)
		(end 70.939152 -131.6736)
		(width 0.127)
		(layer "In5.Cu")
		(net "LED_POSTCODE_5")
	)
	(segment
		(start 79.904082 -130.7846)
		(end 79.040482 -131.6482)
		(width 0.127)
		(layer "In5.Cu")
		(net "LED_POSTCODE_5")
	)
	(segment
		(start 57.9374 -138.557)
		(end 57.35066 -139.14374)
		(width 0.127)
		(layer "F.Cu")
		(net "LED_POSTCODE_4")
	)
	(segment
		(start 83.160362 -138.048746)
		(end 83.389216 -138.2776)
		(width 0.127)
		(layer "F.Cu")
		(net "LED_POSTCODE_4")
	)
	(segment
		(start 83.389216 -138.2776)
		(end 83.947 -138.2776)
		(width 0.127)
		(layer "F.Cu")
		(net "LED_POSTCODE_4")
	)
	(segment
		(start 57.35066 -139.92606)
		(end 56.676798 -140.599922)
		(width 0.127)
		(layer "F.Cu")
		(net "LED_POSTCODE_4")
	)
	(segment
		(start 56.676798 -140.599922)
		(end 56.099964 -140.599922)
		(width 0.127)
		(layer "F.Cu")
		(net "LED_POSTCODE_4")
	)
	(segment
		(start 85.5472 -138.6078)
		(end 86.101682 -138.6078)
		(width 0.127)
		(layer "F.Cu")
		(net "LED_POSTCODE_4")
	)
	(segment
		(start 84.2772 -138.6078)
		(end 85.5472 -138.6078)
		(width 0.127)
		(layer "F.Cu")
		(net "LED_POSTCODE_4")
	)
	(segment
		(start 89.172288 -141.678406)
		(end 90.357706 -141.678406)
		(width 0.127)
		(layer "F.Cu")
		(net "LED_POSTCODE_4")
	)
	(segment
		(start 57.35066 -139.14374)
		(end 57.35066 -139.92606)
		(width 0.127)
		(layer "F.Cu")
		(net "LED_POSTCODE_4")
	)
	(segment
		(start 86.101682 -138.6078)
		(end 89.172288 -141.678406)
		(width 0.127)
		(layer "F.Cu")
		(net "LED_POSTCODE_4")
	)
	(segment
		(start 83.947 -138.2776)
		(end 84.2772 -138.6078)
		(width 0.127)
		(layer "F.Cu")
		(net "LED_POSTCODE_4")
	)
	(via
		(at 85.5472 -138.6078)
		(size 0.6604)
		(drill 0.3302)
		(layers "F.Cu" "B.Cu")
		(net "LED_POSTCODE_4")
	)
	(via
		(at 83.160362 -138.048746)
		(size 0.508)
		(drill 0.254)
		(layers "F.Cu" "B.Cu")
		(net "LED_POSTCODE_4")
	)
	(via
		(at 57.9374 -138.557)
		(size 0.508)
		(drill 0.254)
		(layers "F.Cu" "B.Cu")
		(net "LED_POSTCODE_4")
	)
	(segment
		(start 69.576188 -138.9634)
		(end 73.70826 -138.9634)
		(width 0.127)
		(layer "In5.Cu")
		(net "LED_POSTCODE_4")
	)
	(segment
		(start 57.9374 -138.557)
		(end 58.3819 -138.1125)
		(width 0.127)
		(layer "In5.Cu")
		(net "LED_POSTCODE_4")
	)
	(segment
		(start 61.6331 -136.5885)
		(end 65.168018 -136.5885)
		(width 0.127)
		(layer "In5.Cu")
		(net "LED_POSTCODE_4")
	)
	(segment
		(start 58.3819 -138.1125)
		(end 60.1091 -138.1125)
		(width 0.127)
		(layer "In5.Cu")
		(net "LED_POSTCODE_4")
	)
	(segment
		(start 77.120242 -137.318242)
		(end 77.6732 -137.8712)
		(width 0.127)
		(layer "In5.Cu")
		(net "LED_POSTCODE_4")
	)
	(segment
		(start 82.2452 -137.8712)
		(end 82.422746 -138.048746)
		(width 0.127)
		(layer "In5.Cu")
		(net "LED_POSTCODE_4")
	)
	(segment
		(start 65.168018 -136.5885)
		(end 66.425318 -137.8458)
		(width 0.127)
		(layer "In5.Cu")
		(net "LED_POSTCODE_4")
	)
	(segment
		(start 77.6732 -137.8712)
		(end 82.2452 -137.8712)
		(width 0.127)
		(layer "In5.Cu")
		(net "LED_POSTCODE_4")
	)
	(segment
		(start 75.353418 -137.318242)
		(end 77.120242 -137.318242)
		(width 0.127)
		(layer "In5.Cu")
		(net "LED_POSTCODE_4")
	)
	(segment
		(start 66.425318 -137.8458)
		(end 68.458588 -137.8458)
		(width 0.127)
		(layer "In5.Cu")
		(net "LED_POSTCODE_4")
	)
	(segment
		(start 73.70826 -138.9634)
		(end 75.353418 -137.318242)
		(width 0.127)
		(layer "In5.Cu")
		(net "LED_POSTCODE_4")
	)
	(segment
		(start 60.1091 -138.1125)
		(end 61.6331 -136.5885)
		(width 0.127)
		(layer "In5.Cu")
		(net "LED_POSTCODE_4")
	)
	(segment
		(start 82.422746 -138.048746)
		(end 83.160362 -138.048746)
		(width 0.127)
		(layer "In5.Cu")
		(net "LED_POSTCODE_4")
	)
	(segment
		(start 68.458588 -137.8458)
		(end 69.576188 -138.9634)
		(width 0.127)
		(layer "In5.Cu")
		(net "LED_POSTCODE_4")
	)
	(segment
		(start 93.2434 -148.7678)
		(end 93.2434 -146.777964)
		(width 0.127)
		(layer "F.Cu")
		(net "LED_POSTCODE_3")
	)
	(segment
		(start 93.001846 -142.328646)
		(end 90.357706 -142.328646)
		(width 0.127)
		(layer "F.Cu")
		(net "LED_POSTCODE_3")
	)
	(segment
		(start 93.2434 -146.777964)
		(end 94.043246 -145.978118)
		(width 0.127)
		(layer "F.Cu")
		(net "LED_POSTCODE_3")
	)
	(segment
		(start 94.043246 -145.978118)
		(end 94.043246 -143.370046)
		(width 0.127)
		(layer "F.Cu")
		(net "LED_POSTCODE_3")
	)
	(segment
		(start 54.500272 -140.599922)
		(end 54.899814 -140.20038)
		(width 0.127)
		(layer "F.Cu")
		(net "LED_POSTCODE_3")
	)
	(segment
		(start 94.043246 -143.370046)
		(end 93.001846 -142.328646)
		(width 0.127)
		(layer "F.Cu")
		(net "LED_POSTCODE_3")
	)
	(segment
		(start 54.500018 -140.599922)
		(end 54.500272 -140.599922)
		(width 0.127)
		(layer "F.Cu")
		(net "LED_POSTCODE_3")
	)
	(segment
		(start 93.091 -148.9202)
		(end 93.2434 -148.7678)
		(width 0.127)
		(layer "F.Cu")
		(net "LED_POSTCODE_3")
	)
	(via
		(at 54.899814 -140.20038)
		(size 0.4572)
		(drill 0.2032)
		(layers "F.Cu" "B.Cu")
		(net "LED_POSTCODE_3")
	)
	(via
		(at 59.0042 -152.4762)
		(size 0.508)
		(drill 0.254)
		(layers "F.Cu" "B.Cu")
		(net "LED_POSTCODE_3")
	)
	(via
		(at 93.091 -148.9202)
		(size 0.508)
		(drill 0.254)
		(layers "F.Cu" "B.Cu")
		(net "LED_POSTCODE_3")
	)
	(segment
		(start 56.8706 -150.3426)
		(end 59.0042 -152.4762)
		(width 0.127)
		(layer "In2.Cu")
		(net "LED_POSTCODE_3")
	)
	(segment
		(start 54.899814 -140.20038)
		(end 54.980078 -140.20038)
		(width 0.127)
		(layer "In2.Cu")
		(net "LED_POSTCODE_3")
	)
	(segment
		(start 56.8706 -142.090902)
		(end 56.8706 -150.3426)
		(width 0.127)
		(layer "In2.Cu")
		(net "LED_POSTCODE_3")
	)
	(segment
		(start 54.980078 -140.20038)
		(end 56.8706 -142.090902)
		(width 0.127)
		(layer "In2.Cu")
		(net "LED_POSTCODE_3")
	)
	(segment
		(start 80.798162 -151.892)
		(end 76.073254 -151.892)
		(width 0.127)
		(layer "In5.Cu")
		(net "LED_POSTCODE_3")
	)
	(segment
		(start 72.118728 -150.751286)
		(end 62.837568 -150.751286)
		(width 0.127)
		(layer "In5.Cu")
		(net "LED_POSTCODE_3")
	)
	(segment
		(start 82.548476 -150.141686)
		(end 80.798162 -151.892)
		(width 0.127)
		(layer "In5.Cu")
		(net "LED_POSTCODE_3")
	)
	(segment
		(start 62.837568 -150.751286)
		(end 61.112654 -152.4762)
		(width 0.127)
		(layer "In5.Cu")
		(net "LED_POSTCODE_3")
	)
	(segment
		(start 88.105234 -151.38019)
		(end 86.86673 -150.141686)
		(width 0.127)
		(layer "In5.Cu")
		(net "LED_POSTCODE_3")
	)
	(segment
		(start 93.091 -148.9202)
		(end 92.5322 -148.9202)
		(width 0.127)
		(layer "In5.Cu")
		(net "LED_POSTCODE_3")
	)
	(segment
		(start 91.698572 -149.753828)
		(end 91.411044 -149.753828)
		(width 0.127)
		(layer "In5.Cu")
		(net "LED_POSTCODE_3")
	)
	(segment
		(start 72.438768 -151.071326)
		(end 72.118728 -150.751286)
		(width 0.127)
		(layer "In5.Cu")
		(net "LED_POSTCODE_3")
	)
	(segment
		(start 89.784682 -151.38019)
		(end 88.105234 -151.38019)
		(width 0.127)
		(layer "In5.Cu")
		(net "LED_POSTCODE_3")
	)
	(segment
		(start 61.112654 -152.4762)
		(end 59.0042 -152.4762)
		(width 0.127)
		(layer "In5.Cu")
		(net "LED_POSTCODE_3")
	)
	(segment
		(start 92.5322 -148.9202)
		(end 91.698572 -149.753828)
		(width 0.127)
		(layer "In5.Cu")
		(net "LED_POSTCODE_3")
	)
	(segment
		(start 91.411044 -149.753828)
		(end 89.784682 -151.38019)
		(width 0.127)
		(layer "In5.Cu")
		(net "LED_POSTCODE_3")
	)
	(segment
		(start 75.25258 -151.071326)
		(end 72.438768 -151.071326)
		(width 0.127)
		(layer "In5.Cu")
		(net "LED_POSTCODE_3")
	)
	(segment
		(start 76.073254 -151.892)
		(end 75.25258 -151.071326)
		(width 0.127)
		(layer "In5.Cu")
		(net "LED_POSTCODE_3")
	)
	(segment
		(start 86.86673 -150.141686)
		(end 82.548476 -150.141686)
		(width 0.127)
		(layer "In5.Cu")
		(net "LED_POSTCODE_3")
	)
	(segment
		(start 92.9894 -149.6314)
		(end 92.3925 -149.0345)
		(width 0.127)
		(layer "F.Cu")
		(net "LED_POSTCODE_2")
	)
	(segment
		(start 92.84335 -144.04975)
		(end 92.61475 -144.04975)
		(width 0.127)
		(layer "F.Cu")
		(net "LED_POSTCODE_2")
	)
	(segment
		(start 92.61475 -144.04975)
		(end 91.543886 -142.978886)
		(width 0.127)
		(layer "F.Cu")
		(net "LED_POSTCODE_2")
	)
	(segment
		(start 93.43263 -146.049746)
		(end 93.43263 -144.63903)
		(width 0.127)
		(layer "F.Cu")
		(net "LED_POSTCODE_2")
	)
	(segment
		(start 92.3925 -149.0345)
		(end 92.3925 -148.362416)
		(width 0.127)
		(layer "F.Cu")
		(net "LED_POSTCODE_2")
	)
	(segment
		(start 53.700172 -140.599922)
		(end 54.099968 -140.200126)
		(width 0.127)
		(layer "F.Cu")
		(net "LED_POSTCODE_2")
	)
	(segment
		(start 53.699918 -140.599922)
		(end 53.700172 -140.599922)
		(width 0.127)
		(layer "F.Cu")
		(net "LED_POSTCODE_2")
	)
	(segment
		(start 93.43263 -144.63903)
		(end 92.84335 -144.04975)
		(width 0.127)
		(layer "F.Cu")
		(net "LED_POSTCODE_2")
	)
	(segment
		(start 92.3925 -148.362416)
		(end 92.6846 -148.070316)
		(width 0.127)
		(layer "F.Cu")
		(net "LED_POSTCODE_2")
	)
	(segment
		(start 91.543886 -142.978886)
		(end 90.357706 -142.978886)
		(width 0.127)
		(layer "F.Cu")
		(net "LED_POSTCODE_2")
	)
	(segment
		(start 92.6846 -148.070316)
		(end 92.6846 -147.701)
		(width 0.127)
		(layer "F.Cu")
		(net "LED_POSTCODE_2")
	)
	(segment
		(start 92.6846 -146.797776)
		(end 93.43263 -146.049746)
		(width 0.127)
		(layer "F.Cu")
		(net "LED_POSTCODE_2")
	)
	(segment
		(start 92.6846 -147.701)
		(end 92.6846 -146.797776)
		(width 0.127)
		(layer "F.Cu")
		(net "LED_POSTCODE_2")
	)
	(segment
		(start 92.9894 -149.86)
		(end 92.9894 -149.6314)
		(width 0.127)
		(layer "F.Cu")
		(net "LED_POSTCODE_2")
	)
	(via
		(at 54.099968 -140.200126)
		(size 0.4572)
		(drill 0.2032)
		(layers "F.Cu" "B.Cu")
		(net "LED_POSTCODE_2")
	)
	(via
		(at 59.295538 -153.351738)
		(size 0.508)
		(drill 0.254)
		(layers "F.Cu" "B.Cu")
		(net "LED_POSTCODE_2")
	)
	(via
		(at 92.6846 -147.701)
		(size 0.6604)
		(drill 0.3302)
		(layers "F.Cu" "B.Cu")
		(net "LED_POSTCODE_2")
	)
	(via
		(at 92.9894 -149.86)
		(size 0.508)
		(drill 0.254)
		(layers "F.Cu" "B.Cu")
		(net "LED_POSTCODE_2")
	)
	(segment
		(start 55.063136 -140.60678)
		(end 54.506622 -140.60678)
		(width 0.127)
		(layer "In2.Cu")
		(net "LED_POSTCODE_2")
	)
	(segment
		(start 56.4642 -142.007844)
		(end 55.063136 -140.60678)
		(width 0.127)
		(layer "In2.Cu")
		(net "LED_POSTCODE_2")
	)
	(segment
		(start 59.286902 -153.351738)
		(end 56.4642 -150.529036)
		(width 0.127)
		(layer "In2.Cu")
		(net "LED_POSTCODE_2")
	)
	(segment
		(start 59.295538 -153.351738)
		(end 59.286902 -153.351738)
		(width 0.127)
		(layer "In2.Cu")
		(net "LED_POSTCODE_2")
	)
	(segment
		(start 54.506622 -140.60678)
		(end 54.099968 -140.200126)
		(width 0.127)
		(layer "In2.Cu")
		(net "LED_POSTCODE_2")
	)
	(segment
		(start 56.4642 -150.529036)
		(end 56.4642 -142.007844)
		(width 0.127)
		(layer "In2.Cu")
		(net "LED_POSTCODE_2")
	)
	(segment
		(start 60.872116 -153.351738)
		(end 59.295538 -153.351738)
		(width 0.127)
		(layer "In5.Cu")
		(net "LED_POSTCODE_2")
	)
	(segment
		(start 75.915266 -152.273)
		(end 75.094592 -151.452326)
		(width 0.127)
		(layer "In5.Cu")
		(net "LED_POSTCODE_2")
	)
	(segment
		(start 91.481402 -150.395686)
		(end 90.115898 -151.76119)
		(width 0.127)
		(layer "In5.Cu")
		(net "LED_POSTCODE_2")
	)
	(segment
		(start 71.96074 -151.132286)
		(end 63.091568 -151.132286)
		(width 0.127)
		(layer "In5.Cu")
		(net "LED_POSTCODE_2")
	)
	(segment
		(start 92.9894 -149.86)
		(end 92.5068 -149.86)
		(width 0.127)
		(layer "In5.Cu")
		(net "LED_POSTCODE_2")
	)
	(segment
		(start 75.094592 -151.452326)
		(end 72.28078 -151.452326)
		(width 0.127)
		(layer "In5.Cu")
		(net "LED_POSTCODE_2")
	)
	(segment
		(start 90.115898 -151.76119)
		(end 87.947246 -151.76119)
		(width 0.127)
		(layer "In5.Cu")
		(net "LED_POSTCODE_2")
	)
	(segment
		(start 82.609944 -151.081486)
		(end 81.41843 -152.273)
		(width 0.127)
		(layer "In5.Cu")
		(net "LED_POSTCODE_2")
	)
	(segment
		(start 91.971114 -150.395686)
		(end 91.481402 -150.395686)
		(width 0.127)
		(layer "In5.Cu")
		(net "LED_POSTCODE_2")
	)
	(segment
		(start 72.28078 -151.452326)
		(end 71.96074 -151.132286)
		(width 0.127)
		(layer "In5.Cu")
		(net "LED_POSTCODE_2")
	)
	(segment
		(start 81.41843 -152.273)
		(end 75.915266 -152.273)
		(width 0.127)
		(layer "In5.Cu")
		(net "LED_POSTCODE_2")
	)
	(segment
		(start 63.091568 -151.132286)
		(end 60.872116 -153.351738)
		(width 0.127)
		(layer "In5.Cu")
		(net "LED_POSTCODE_2")
	)
	(segment
		(start 92.5068 -149.86)
		(end 91.971114 -150.395686)
		(width 0.127)
		(layer "In5.Cu")
		(net "LED_POSTCODE_2")
	)
	(segment
		(start 87.947246 -151.76119)
		(end 87.267542 -151.081486)
		(width 0.127)
		(layer "In5.Cu")
		(net "LED_POSTCODE_2")
	)
	(segment
		(start 87.267542 -151.081486)
		(end 82.609944 -151.081486)
		(width 0.127)
		(layer "In5.Cu")
		(net "LED_POSTCODE_2")
	)
	(segment
		(start 85.912706 -139.1666)
		(end 89.40292 -142.656814)
		(width 0.127)
		(layer "F.Cu")
		(net "LED_POSTCODE_1")
	)
	(segment
		(start 55.300118 -139.800076)
		(end 55.299864 -139.800076)
		(width 0.127)
		(layer "F.Cu")
		(net "LED_POSTCODE_1")
	)
	(segment
		(start 84.497418 -139.1539)
		(end 84.510118 -139.1666)
		(width 0.127)
		(layer "F.Cu")
		(net "LED_POSTCODE_1")
	)
	(segment
		(start 81.4578 -137.9855)
		(end 82.186018 -138.713718)
		(width 0.127)
		(layer "F.Cu")
		(net "LED_POSTCODE_1")
	)
	(segment
		(start 82.186018 -138.713718)
		(end 83.843876 -138.713718)
		(width 0.127)
		(layer "F.Cu")
		(net "LED_POSTCODE_1")
	)
	(segment
		(start 89.40292 -143.32966)
		(end 89.702386 -143.629126)
		(width 0.127)
		(layer "F.Cu")
		(net "LED_POSTCODE_1")
	)
	(segment
		(start 89.40292 -142.656814)
		(end 89.40292 -143.32966)
		(width 0.127)
		(layer "F.Cu")
		(net "LED_POSTCODE_1")
	)
	(segment
		(start 55.699914 -139.40028)
		(end 55.300118 -139.800076)
		(width 0.127)
		(layer "F.Cu")
		(net "LED_POSTCODE_1")
	)
	(segment
		(start 81.3435 -137.8712)
		(end 81.4578 -137.9855)
		(width 0.127)
		(layer "F.Cu")
		(net "LED_POSTCODE_1")
	)
	(segment
		(start 76.973938 -137.8712)
		(end 81.3435 -137.8712)
		(width 0.127)
		(layer "F.Cu")
		(net "LED_POSTCODE_1")
	)
	(segment
		(start 84.510118 -139.1666)
		(end 85.912706 -139.1666)
		(width 0.127)
		(layer "F.Cu")
		(net "LED_POSTCODE_1")
	)
	(segment
		(start 83.843876 -138.713718)
		(end 84.284058 -139.1539)
		(width 0.127)
		(layer "F.Cu")
		(net "LED_POSTCODE_1")
	)
	(segment
		(start 89.702386 -143.629126)
		(end 90.357706 -143.629126)
		(width 0.127)
		(layer "F.Cu")
		(net "LED_POSTCODE_1")
	)
	(segment
		(start 84.284058 -139.1539)
		(end 84.497418 -139.1539)
		(width 0.127)
		(layer "F.Cu")
		(net "LED_POSTCODE_1")
	)
	(segment
		(start 76.836524 -138.008614)
		(end 76.973938 -137.8712)
		(width 0.127)
		(layer "F.Cu")
		(net "LED_POSTCODE_1")
	)
	(via
		(at 55.699914 -139.40028)
		(size 0.4572)
		(drill 0.2032)
		(layers "F.Cu" "B.Cu")
		(net "LED_POSTCODE_1")
	)
	(via
		(at 81.4578 -137.9855)
		(size 0.6604)
		(drill 0.3302)
		(layers "F.Cu" "B.Cu")
		(net "LED_POSTCODE_1")
	)
	(via
		(at 76.836524 -138.008614)
		(size 0.508)
		(drill 0.254)
		(layers "F.Cu" "B.Cu")
		(net "LED_POSTCODE_1")
	)
	(segment
		(start 60.931044 -138.274552)
		(end 60.229496 -138.9761)
		(width 0.127)
		(layer "In5.Cu")
		(net "LED_POSTCODE_1")
	)
	(segment
		(start 74.814938 -140.0302)
		(end 70.104 -140.0302)
		(width 0.127)
		(layer "In5.Cu")
		(net "LED_POSTCODE_1")
	)
	(segment
		(start 60.229496 -138.9761)
		(end 56.124094 -138.9761)
		(width 0.127)
		(layer "In5.Cu")
		(net "LED_POSTCODE_1")
	)
	(segment
		(start 76.836524 -138.008614)
		(end 74.814938 -140.0302)
		(width 0.127)
		(layer "In5.Cu")
		(net "LED_POSTCODE_1")
	)
	(segment
		(start 56.124094 -138.9761)
		(end 55.699914 -139.40028)
		(width 0.127)
		(layer "In5.Cu")
		(net "LED_POSTCODE_1")
	)
	(segment
		(start 70.104 -140.0302)
		(end 68.348352 -138.274552)
		(width 0.127)
		(layer "In5.Cu")
		(net "LED_POSTCODE_1")
	)
	(segment
		(start 68.348352 -138.274552)
		(end 60.931044 -138.274552)
		(width 0.127)
		(layer "In5.Cu")
		(net "LED_POSTCODE_1")
	)
	(segment
		(start 88.985598 -143.620744)
		(end 88.985598 -142.77848)
		(width 0.127)
		(layer "F.Cu")
		(net "LED_POSTCODE_0")
	)
	(segment
		(start 83.75523 -139.799822)
		(end 82.268822 -139.799822)
		(width 0.127)
		(layer "F.Cu")
		(net "LED_POSTCODE_0")
	)
	(segment
		(start 77.361288 -138.3284)
		(end 76.87691 -138.812778)
		(width 0.127)
		(layer "F.Cu")
		(net "LED_POSTCODE_0")
	)
	(segment
		(start 81.4832 -139.5222)
		(end 80.2894 -138.3284)
		(width 0.127)
		(layer "F.Cu")
		(net "LED_POSTCODE_0")
	)
	(segment
		(start 80.2894 -138.3284)
		(end 77.361288 -138.3284)
		(width 0.127)
		(layer "F.Cu")
		(net "LED_POSTCODE_0")
	)
	(segment
		(start 90.357706 -144.279366)
		(end 89.64422 -144.279366)
		(width 0.127)
		(layer "F.Cu")
		(net "LED_POSTCODE_0")
	)
	(segment
		(start 88.985598 -142.77848)
		(end 86.764622 -140.557504)
		(width 0.127)
		(layer "F.Cu")
		(net "LED_POSTCODE_0")
	)
	(segment
		(start 76.87691 -138.812778)
		(end 76.87691 -138.939524)
		(width 0.127)
		(layer "F.Cu")
		(net "LED_POSTCODE_0")
	)
	(segment
		(start 56.500014 -139.40028)
		(end 56.100218 -139.800076)
		(width 0.127)
		(layer "F.Cu")
		(net "LED_POSTCODE_0")
	)
	(segment
		(start 89.64422 -144.279366)
		(end 88.985598 -143.620744)
		(width 0.127)
		(layer "F.Cu")
		(net "LED_POSTCODE_0")
	)
	(segment
		(start 56.100218 -139.800076)
		(end 56.099964 -139.800076)
		(width 0.127)
		(layer "F.Cu")
		(net "LED_POSTCODE_0")
	)
	(segment
		(start 86.764622 -140.557504)
		(end 84.512912 -140.557504)
		(width 0.127)
		(layer "F.Cu")
		(net "LED_POSTCODE_0")
	)
	(segment
		(start 84.512912 -140.557504)
		(end 83.75523 -139.799822)
		(width 0.127)
		(layer "F.Cu")
		(net "LED_POSTCODE_0")
	)
	(segment
		(start 81.9912 -139.5222)
		(end 81.4832 -139.5222)
		(width 0.127)
		(layer "F.Cu")
		(net "LED_POSTCODE_0")
	)
	(segment
		(start 82.268822 -139.799822)
		(end 81.9912 -139.5222)
		(width 0.127)
		(layer "F.Cu")
		(net "LED_POSTCODE_0")
	)
	(via
		(at 81.9912 -139.5222)
		(size 0.6604)
		(drill 0.3302)
		(layers "F.Cu" "B.Cu")
		(net "LED_POSTCODE_0")
	)
	(via
		(at 56.500014 -139.40028)
		(size 0.4572)
		(drill 0.2032)
		(layers "F.Cu" "B.Cu")
		(net "LED_POSTCODE_0")
	)
	(via
		(at 76.87691 -138.939524)
		(size 0.508)
		(drill 0.254)
		(layers "F.Cu" "B.Cu")
		(net "LED_POSTCODE_0")
	)
	(segment
		(start 68.707 -140.462)
		(end 67.107054 -138.862054)
		(width 0.127)
		(layer "In5.Cu")
		(net "LED_POSTCODE_0")
	)
	(segment
		(start 76.660248 -138.939524)
		(end 75.137772 -140.462)
		(width 0.127)
		(layer "In5.Cu")
		(net "LED_POSTCODE_0")
	)
	(segment
		(start 76.87691 -138.939524)
		(end 76.660248 -138.939524)
		(width 0.127)
		(layer "In5.Cu")
		(net "LED_POSTCODE_0")
	)
	(segment
		(start 67.107054 -138.862054)
		(end 60.88253 -138.862054)
		(width 0.127)
		(layer "In5.Cu")
		(net "LED_POSTCODE_0")
	)
	(segment
		(start 60.88253 -138.862054)
		(end 60.344304 -139.40028)
		(width 0.127)
		(layer "In5.Cu")
		(net "LED_POSTCODE_0")
	)
	(segment
		(start 60.344304 -139.40028)
		(end 56.500014 -139.40028)
		(width 0.127)
		(layer "In5.Cu")
		(net "LED_POSTCODE_0")
	)
	(segment
		(start 75.137772 -140.462)
		(end 68.707 -140.462)
		(width 0.127)
		(layer "In5.Cu")
		(net "LED_POSTCODE_0")
	)
	(segment
		(start 95.117412 -130.811016)
		(end 94.613476 -130.30708)
		(width 0.127)
		(layer "F.Cu")
		(net "DEBUG_UART_IOM_TX")
	)
	(segment
		(start 95.945706 -130.811016)
		(end 95.117412 -130.811016)
		(width 0.127)
		(layer "F.Cu")
		(net "DEBUG_UART_IOM_TX")
	)
	(via
		(at 94.613476 -130.30708)
		(size 0.508)
		(drill 0.254)
		(layers "F.Cu" "B.Cu")
		(net "DEBUG_UART_IOM_TX")
	)
	(via
		(at 95.008446 -131.415282)
		(size 0.6096)
		(drill 0.3048)
		(layers "F.Cu" "B.Cu")
		(net "DEBUG_UART_IOM_TX")
	)
	(segment
		(start 95.017844 -131.955794)
		(end 94.868238 -132.1054)
		(width 0.127)
		(layer "B.Cu")
		(net "DEBUG_UART_IOM_TX")
	)
	(segment
		(start 94.613476 -130.30708)
		(end 95.017844 -130.711448)
		(width 0.127)
		(layer "B.Cu")
		(net "DEBUG_UART_IOM_TX")
	)
	(segment
		(start 95.017844 -131.415282)
		(end 95.008446 -131.415282)
		(width 0.127)
		(layer "B.Cu")
		(net "DEBUG_UART_IOM_TX")
	)
	(segment
		(start 95.017844 -130.711448)
		(end 95.017844 -131.415282)
		(width 0.127)
		(layer "B.Cu")
		(net "DEBUG_UART_IOM_TX")
	)
	(segment
		(start 95.017844 -131.415282)
		(end 95.017844 -131.955794)
		(width 0.127)
		(layer "B.Cu")
		(net "DEBUG_UART_IOM_TX")
	)
	(segment
		(start 94.868238 -132.1054)
		(end 93.5355 -132.1054)
		(width 0.127)
		(layer "B.Cu")
		(net "DEBUG_UART_IOM_TX")
	)
	(segment
		(start 85.046058 -131.387342)
		(end 85.046058 -131.344162)
		(width 0.127)
		(layer "F.Cu")
		(net "DEBUG_UART_IOM_RX")
	)
	(segment
		(start 94.5388 -128.27)
		(end 95.080836 -128.812036)
		(width 0.127)
		(layer "F.Cu")
		(net "DEBUG_UART_IOM_RX")
	)
	(segment
		(start 84.074 -132.3594)
		(end 85.046058 -131.387342)
		(width 0.127)
		(layer "F.Cu")
		(net "DEBUG_UART_IOM_RX")
	)
	(segment
		(start 95.080836 -128.812036)
		(end 95.945706 -128.812036)
		(width 0.127)
		(layer "F.Cu")
		(net "DEBUG_UART_IOM_RX")
	)
	(segment
		(start 93.7006 -128.27)
		(end 94.5388 -128.27)
		(width 0.127)
		(layer "F.Cu")
		(net "DEBUG_UART_IOM_RX")
	)
	(segment
		(start 84.074 -132.6134)
		(end 84.074 -132.3594)
		(width 0.127)
		(layer "F.Cu")
		(net "DEBUG_UART_IOM_RX")
	)
	(via
		(at 93.7006 -128.27)
		(size 0.508)
		(drill 0.254)
		(layers "F.Cu" "B.Cu")
		(net "DEBUG_UART_IOM_RX")
	)
	(via
		(at 90.894662 -127.20955)
		(size 0.6096)
		(drill 0.3048)
		(layers "F.Cu" "B.Cu")
		(net "DEBUG_UART_IOM_RX")
	)
	(via
		(at 84.074 -132.6134)
		(size 0.508)
		(drill 0.254)
		(layers "F.Cu" "B.Cu")
		(net "DEBUG_UART_IOM_RX")
	)
	(segment
		(start 93.372178 -128.27)
		(end 93.7006 -128.27)
		(width 0.127)
		(layer "B.Cu")
		(net "DEBUG_UART_IOM_RX")
	)
	(segment
		(start 89.8525 -128.251712)
		(end 89.8525 -130.68427)
		(width 0.127)
		(layer "B.Cu")
		(net "DEBUG_UART_IOM_RX")
	)
	(segment
		(start 89.447624 -131.086098)
		(end 88.52916 -132.004562)
		(width 0.127)
		(layer "B.Cu")
		(net "DEBUG_UART_IOM_RX")
	)
	(segment
		(start 89.8525 -130.68427)
		(end 89.450672 -131.086098)
		(width 0.127)
		(layer "B.Cu")
		(net "DEBUG_UART_IOM_RX")
	)
	(segment
		(start 92.710254 -127.608076)
		(end 93.372178 -128.27)
		(width 0.127)
		(layer "B.Cu")
		(net "DEBUG_UART_IOM_RX")
	)
	(segment
		(start 90.894662 -127.20955)
		(end 89.8525 -128.251712)
		(width 0.127)
		(layer "B.Cu")
		(net "DEBUG_UART_IOM_RX")
	)
	(segment
		(start 89.450672 -131.086098)
		(end 89.447624 -131.086098)
		(width 0.127)
		(layer "B.Cu")
		(net "DEBUG_UART_IOM_RX")
	)
	(segment
		(start 92.710254 -126.962916)
		(end 92.710254 -127.608076)
		(width 0.127)
		(layer "B.Cu")
		(net "DEBUG_UART_IOM_RX")
	)
	(segment
		(start 91.581732 -126.52248)
		(end 92.269818 -126.52248)
		(width 0.127)
		(layer "B.Cu")
		(net "DEBUG_UART_IOM_RX")
	)
	(segment
		(start 88.52916 -132.95376)
		(end 90.15476 -134.57936)
		(width 0.127)
		(layer "B.Cu")
		(net "DEBUG_UART_IOM_RX")
	)
	(segment
		(start 88.52916 -132.004562)
		(end 88.52916 -132.95376)
		(width 0.127)
		(layer "B.Cu")
		(net "DEBUG_UART_IOM_RX")
	)
	(segment
		(start 90.15476 -134.57936)
		(end 91.11742 -134.57936)
		(width 0.127)
		(layer "B.Cu")
		(net "DEBUG_UART_IOM_RX")
	)
	(segment
		(start 92.269818 -126.52248)
		(end 92.710254 -126.962916)
		(width 0.127)
		(layer "B.Cu")
		(net "DEBUG_UART_IOM_RX")
	)
	(segment
		(start 90.894662 -127.20955)
		(end 91.581732 -126.52248)
		(width 0.127)
		(layer "B.Cu")
		(net "DEBUG_UART_IOM_RX")
	)
	(segment
		(start 85.598 -131.8768)
		(end 87.45728 -131.8768)
		(width 0.127)
		(layer "In5.Cu")
		(net "DEBUG_UART_IOM_RX")
	)
	(segment
		(start 87.45728 -131.8768)
		(end 88.27008 -131.064)
		(width 0.127)
		(layer "In5.Cu")
		(net "DEBUG_UART_IOM_RX")
	)
	(segment
		(start 88.27008 -131.064)
		(end 90.814144 -131.064)
		(width 0.127)
		(layer "In5.Cu")
		(net "DEBUG_UART_IOM_RX")
	)
	(segment
		(start 85.1154 -132.3594)
		(end 85.598 -131.8768)
		(width 0.127)
		(layer "In5.Cu")
		(net "DEBUG_UART_IOM_RX")
	)
	(segment
		(start 93.608144 -128.27)
		(end 93.7006 -128.27)
		(width 0.127)
		(layer "In5.Cu")
		(net "DEBUG_UART_IOM_RX")
	)
	(segment
		(start 84.328 -132.3594)
		(end 85.1154 -132.3594)
		(width 0.127)
		(layer "In5.Cu")
		(net "DEBUG_UART_IOM_RX")
	)
	(segment
		(start 84.074 -132.6134)
		(end 84.328 -132.3594)
		(width 0.127)
		(layer "In5.Cu")
		(net "DEBUG_UART_IOM_RX")
	)
	(segment
		(start 90.814144 -131.064)
		(end 93.608144 -128.27)
		(width 0.127)
		(layer "In5.Cu")
		(net "DEBUG_UART_IOM_RX")
	)
	(segment
		(start 90.551508 -120.4976)
		(end 90.551508 -125.187964)
		(width 0.127)
		(layer "F.Cu")
		(net "DEBUG_CARD_PRSNT")
	)
	(segment
		(start 91.8591 -119.5451)
		(end 90.8939 -119.5451)
		(width 0.127)
		(layer "F.Cu")
		(net "DEBUG_CARD_PRSNT")
	)
	(segment
		(start 92.075 -126.711456)
		(end 92.075 -126.99238)
		(width 0.127)
		(layer "F.Cu")
		(net "DEBUG_CARD_PRSNT")
	)
	(segment
		(start 90.551508 -125.187964)
		(end 92.075 -126.711456)
		(width 0.127)
		(layer "F.Cu")
		(net "DEBUG_CARD_PRSNT")
	)
	(segment
		(start 90.551508 -119.887492)
		(end 90.551508 -120.4976)
		(width 0.127)
		(layer "F.Cu")
		(net "DEBUG_CARD_PRSNT")
	)
	(segment
		(start 90.8939 -119.5451)
		(end 90.551508 -119.887492)
		(width 0.127)
		(layer "F.Cu")
		(net "DEBUG_CARD_PRSNT")
	)
	(segment
		(start 95.933514 -114.780314)
		(end 95.123 -115.590828)
		(width 0.127)
		(layer "F.Cu")
		(net "DEBUG_CARD_PRSNT")
	)
	(segment
		(start 95.123 -116.2812)
		(end 91.8591 -119.5451)
		(width 0.127)
		(layer "F.Cu")
		(net "DEBUG_CARD_PRSNT")
	)
	(segment
		(start 95.123 -115.590828)
		(end 95.123 -116.2812)
		(width 0.127)
		(layer "F.Cu")
		(net "DEBUG_CARD_PRSNT")
	)
	(via
		(at 92.075 -126.99238)
		(size 0.508)
		(drill 0.254)
		(layers "F.Cu" "B.Cu")
		(net "DEBUG_CARD_PRSNT")
	)
	(via
		(at 95.933514 -114.780314)
		(size 0.508)
		(drill 0.254)
		(layers "F.Cu" "B.Cu")
		(net "DEBUG_CARD_PRSNT")
	)
	(via
		(at 83.8708 -135.9408)
		(size 0.508)
		(drill 0.254)
		(layers "F.Cu" "B.Cu")
		(net "DEBUG_CARD_PRSNT")
	)
	(via
		(at 90.551508 -120.4976)
		(size 0.6604)
		(drill 0.3302)
		(layers "F.Cu" "B.Cu")
		(net "DEBUG_CARD_PRSNT")
	)
	(via
		(at 92.89542 -137.4267)
		(size 0.508)
		(drill 0.254)
		(layers "F.Cu" "B.Cu")
		(net "DEBUG_CARD_PRSNT")
	)
	(segment
		(start 92.3163 -141.5923)
		(end 92.3163 -142.14475)
		(width 0.127)
		(layer "B.Cu")
		(net "DEBUG_CARD_PRSNT")
	)
	(segment
		(start 78.763368 -146.138646)
		(end 78.763368 -145.639028)
		(width 0.127)
		(layer "B.Cu")
		(net "DEBUG_CARD_PRSNT")
	)
	(segment
		(start 92.89542 -137.05078)
		(end 92.76842 -136.92378)
		(width 0.127)
		(layer "B.Cu")
		(net "DEBUG_CARD_PRSNT")
	)
	(segment
		(start 91.467686 -132.12064)
		(end 92.441014 -132.12064)
		(width 0.127)
		(layer "B.Cu")
		(net "DEBUG_CARD_PRSNT")
	)
	(segment
		(start 78.88605 -144.345914)
		(end 80.456278 -142.775686)
		(width 0.127)
		(layer "B.Cu")
		(net "DEBUG_CARD_PRSNT")
	)
	(segment
		(start 92.76842 -136.92378)
		(end 92.76842 -135.87984)
		(width 0.127)
		(layer "B.Cu")
		(net "DEBUG_CARD_PRSNT")
	)
	(segment
		(start 92.441014 -132.12064)
		(end 93.076014 -132.75564)
		(width 0.127)
		(layer "B.Cu")
		(net "DEBUG_CARD_PRSNT")
	)
	(segment
		(start 95.00616 -134.516368)
		(end 93.642688 -135.87984)
		(width 0.127)
		(layer "B.Cu")
		(net "DEBUG_CARD_PRSNT")
	)
	(segment
		(start 93.5355 -132.75564)
		(end 94.87916 -132.75564)
		(width 0.127)
		(layer "B.Cu")
		(net "DEBUG_CARD_PRSNT")
	)
	(segment
		(start 92.89542 -138.2268)
		(end 92.89542 -140.05306)
		(width 0.127)
		(layer "B.Cu")
		(net "DEBUG_CARD_PRSNT")
	)
	(segment
		(start 83.3628 -135.9408)
		(end 83.8708 -135.9408)
		(width 0.127)
		(layer "B.Cu")
		(net "DEBUG_CARD_PRSNT")
	)
	(segment
		(start 82.296 -138.000232)
		(end 82.296 -137.0076)
		(width 0.127)
		(layer "B.Cu")
		(net "DEBUG_CARD_PRSNT")
	)
	(segment
		(start 78.763368 -145.639028)
		(end 78.88605 -145.516346)
		(width 0.127)
		(layer "B.Cu")
		(net "DEBUG_CARD_PRSNT")
	)
	(segment
		(start 92.075 -126.99238)
		(end 91.0844 -127.98298)
		(width 0.127)
		(layer "B.Cu")
		(net "DEBUG_CARD_PRSNT")
	)
	(segment
		(start 94.87916 -132.75564)
		(end 95.00616 -132.88264)
		(width 0.127)
		(layer "B.Cu")
		(net "DEBUG_CARD_PRSNT")
	)
	(segment
		(start 93.642688 -135.87984)
		(end 92.76842 -135.87984)
		(width 0.127)
		(layer "B.Cu")
		(net "DEBUG_CARD_PRSNT")
	)
	(segment
		(start 91.0844 -131.737354)
		(end 91.467686 -132.12064)
		(width 0.127)
		(layer "B.Cu")
		(net "DEBUG_CARD_PRSNT")
	)
	(segment
		(start 80.456278 -142.775686)
		(end 80.456278 -139.839954)
		(width 0.127)
		(layer "B.Cu")
		(net "DEBUG_CARD_PRSNT")
	)
	(segment
		(start 95.00616 -132.88264)
		(end 95.00616 -134.516368)
		(width 0.127)
		(layer "B.Cu")
		(net "DEBUG_CARD_PRSNT")
	)
	(segment
		(start 80.456278 -139.839954)
		(end 82.296 -138.000232)
		(width 0.127)
		(layer "B.Cu")
		(net "DEBUG_CARD_PRSNT")
	)
	(segment
		(start 91.0844 -127.98298)
		(end 91.0844 -131.737354)
		(width 0.127)
		(layer "B.Cu")
		(net "DEBUG_CARD_PRSNT")
	)
	(segment
		(start 82.296 -137.0076)
		(end 83.3628 -135.9408)
		(width 0.127)
		(layer "B.Cu")
		(net "DEBUG_CARD_PRSNT")
	)
	(segment
		(start 92.89542 -137.4267)
		(end 92.89542 -137.05078)
		(width 0.127)
		(layer "B.Cu")
		(net "DEBUG_CARD_PRSNT")
	)
	(segment
		(start 78.88605 -145.516346)
		(end 78.88605 -144.345914)
		(width 0.127)
		(layer "B.Cu")
		(net "DEBUG_CARD_PRSNT")
	)
	(segment
		(start 92.89542 -141.01318)
		(end 92.3163 -141.5923)
		(width 0.127)
		(layer "B.Cu")
		(net "DEBUG_CARD_PRSNT")
	)
	(segment
		(start 93.076014 -132.75564)
		(end 93.5355 -132.75564)
		(width 0.127)
		(layer "B.Cu")
		(net "DEBUG_CARD_PRSNT")
	)
	(segment
		(start 92.89542 -140.05306)
		(end 92.89542 -141.01318)
		(width 0.127)
		(layer "B.Cu")
		(net "DEBUG_CARD_PRSNT")
	)
	(segment
		(start 92.89542 -138.2268)
		(end 92.89542 -137.4267)
		(width 0.127)
		(layer "B.Cu")
		(net "DEBUG_CARD_PRSNT")
	)
	(segment
		(start 94.1832 -115.4938)
		(end 95.220028 -115.4938)
		(width 0.127)
		(layer "In5.Cu")
		(net "DEBUG_CARD_PRSNT")
	)
	(segment
		(start 95.220028 -115.4938)
		(end 95.933514 -114.780314)
		(width 0.127)
		(layer "In5.Cu")
		(net "DEBUG_CARD_PRSNT")
	)
	(segment
		(start 84.000594 -136.070594)
		(end 83.8708 -135.9408)
		(width 0.127)
		(layer "In5.Cu")
		(net "DEBUG_CARD_PRSNT")
	)
	(segment
		(start 80.5942 -56.99252)
		(end 81.026 -57.42432)
		(width 0.127)
		(layer "In5.Cu")
		(net "DEBUG_CARD_PRSNT")
	)
	(segment
		(start 84.662772 -40.320468)
		(end 80.5942 -44.38904)
		(width 0.127)
		(layer "In5.Cu")
		(net "DEBUG_CARD_PRSNT")
	)
	(segment
		(start 90.318082 -137.033508)
		(end 86.1695 -137.033508)
		(width 0.127)
		(layer "In5.Cu")
		(net "DEBUG_CARD_PRSNT")
	)
	(segment
		(start 87.907368 -98.2218)
		(end 93.726 -104.040432)
		(width 0.127)
		(layer "In5.Cu")
		(net "DEBUG_CARD_PRSNT")
	)
	(segment
		(start 86.1695 -137.033508)
		(end 85.206586 -136.070594)
		(width 0.127)
		(layer "In5.Cu")
		(net "DEBUG_CARD_PRSNT")
	)
	(segment
		(start 82.743802 -98.2218)
		(end 87.907368 -98.2218)
		(width 0.127)
		(layer "In5.Cu")
		(net "DEBUG_CARD_PRSNT")
	)
	(segment
		(start 80.8228 -96.300798)
		(end 82.743802 -98.2218)
		(width 0.127)
		(layer "In5.Cu")
		(net "DEBUG_CARD_PRSNT")
	)
	(segment
		(start 85.979 -20.2184)
		(end 84.662518 -21.534882)
		(width 0.127)
		(layer "In5.Cu")
		(net "DEBUG_CARD_PRSNT")
	)
	(segment
		(start 84.662518 -21.534882)
		(end 84.662518 -39.25697)
		(width 0.127)
		(layer "In5.Cu")
		(net "DEBUG_CARD_PRSNT")
	)
	(segment
		(start 88.138 -20.2184)
		(end 85.979 -20.2184)
		(width 0.127)
		(layer "In5.Cu")
		(net "DEBUG_CARD_PRSNT")
	)
	(segment
		(start 80.5942 -44.38904)
		(end 80.5942 -56.99252)
		(width 0.127)
		(layer "In5.Cu")
		(net "DEBUG_CARD_PRSNT")
	)
	(segment
		(start 81.026 -57.42432)
		(end 81.026 -93.017594)
		(width 0.127)
		(layer "In5.Cu")
		(net "DEBUG_CARD_PRSNT")
	)
	(segment
		(start 81.026 -93.017594)
		(end 80.8228 -93.220794)
		(width 0.127)
		(layer "In5.Cu")
		(net "DEBUG_CARD_PRSNT")
	)
	(segment
		(start 80.8228 -93.220794)
		(end 80.8228 -96.300798)
		(width 0.127)
		(layer "In5.Cu")
		(net "DEBUG_CARD_PRSNT")
	)
	(segment
		(start 84.662772 -39.257224)
		(end 84.662772 -40.320468)
		(width 0.127)
		(layer "In5.Cu")
		(net "DEBUG_CARD_PRSNT")
	)
	(segment
		(start 90.711274 -137.4267)
		(end 90.318082 -137.033508)
		(width 0.127)
		(layer "In5.Cu")
		(net "DEBUG_CARD_PRSNT")
	)
	(segment
		(start 85.206586 -136.070594)
		(end 84.000594 -136.070594)
		(width 0.127)
		(layer "In5.Cu")
		(net "DEBUG_CARD_PRSNT")
	)
	(segment
		(start 89.799922 -18.556478)
		(end 88.138 -20.2184)
		(width 0.127)
		(layer "In5.Cu")
		(net "DEBUG_CARD_PRSNT")
	)
	(segment
		(start 92.89542 -137.4267)
		(end 90.711274 -137.4267)
		(width 0.127)
		(layer "In5.Cu")
		(net "DEBUG_CARD_PRSNT")
	)
	(segment
		(start 84.662518 -39.25697)
		(end 84.662772 -39.257224)
		(width 0.127)
		(layer "In5.Cu")
		(net "DEBUG_CARD_PRSNT")
	)
	(segment
		(start 93.726 -104.040432)
		(end 93.726 -115.0366)
		(width 0.127)
		(layer "In5.Cu")
		(net "DEBUG_CARD_PRSNT")
	)
	(segment
		(start 89.799922 -17.979898)
		(end 89.799922 -18.556478)
		(width 0.127)
		(layer "In5.Cu")
		(net "DEBUG_CARD_PRSNT")
	)
	(segment
		(start 93.726 -115.0366)
		(end 94.1832 -115.4938)
		(width 0.127)
		(layer "In5.Cu")
		(net "DEBUG_CARD_PRSNT")
	)
	(segment
		(start 59.9186 -156.2354)
		(end 60.6298 -156.9466)
		(width 0.508)
		(layer "F.Cu")
		(net "VPLLAV33")
	)
	(segment
		(start 60.6298 -156.9466)
		(end 60.8584 -157.1752)
		(width 0.508)
		(layer "F.Cu")
		(net "VPLLAV33")
	)
	(segment
		(start 61.804296 -159.540956)
		(end 61.804296 -158.270956)
		(width 0.508)
		(layer "F.Cu")
		(net "VPLLAV33")
	)
	(segment
		(start 61.214 -157.1752)
		(end 61.804296 -157.765496)
		(width 0.508)
		(layer "F.Cu")
		(net "VPLLAV33")
	)
	(segment
		(start 49.812956 -148.71319)
		(end 49.699926 -148.60016)
		(width 0.3048)
		(layer "F.Cu")
		(net "VPLLAV33")
	)
	(segment
		(start 62.73165 -160.46831)
		(end 62.185296 -159.921956)
		(width 0.508)
		(layer "F.Cu")
		(net "VPLLAV33")
	)
	(segment
		(start 50.07991 -148.98116)
		(end 49.812956 -148.714206)
		(width 0.3048)
		(layer "F.Cu")
		(net "VPLLAV33")
	)
	(segment
		(start 49.699926 -148.60016)
		(end 49.699926 -148.599906)
		(width 0.3048)
		(layer "F.Cu")
		(net "VPLLAV33")
	)
	(segment
		(start 50.500026 -148.60016)
		(end 50.500026 -148.599906)
		(width 0.3048)
		(layer "F.Cu")
		(net "VPLLAV33")
	)
	(segment
		(start 60.8584 -157.1752)
		(end 61.214 -157.1752)
		(width 0.508)
		(layer "F.Cu")
		(net "VPLLAV33")
	)
	(segment
		(start 59.8932 -156.2354)
		(end 59.9186 -156.2354)
		(width 0.508)
		(layer "F.Cu")
		(net "VPLLAV33")
	)
	(segment
		(start 62.185296 -159.921956)
		(end 61.804296 -159.540956)
		(width 0.508)
		(layer "F.Cu")
		(net "VPLLAV33")
	)
	(segment
		(start 49.812956 -148.714206)
		(end 49.812956 -148.71319)
		(width 0.3048)
		(layer "F.Cu")
		(net "VPLLAV33")
	)
	(segment
		(start 50.899822 -148.999956)
		(end 50.500026 -148.60016)
		(width 0.3048)
		(layer "F.Cu")
		(net "VPLLAV33")
	)
	(segment
		(start 61.804296 -157.765496)
		(end 61.804296 -158.270956)
		(width 0.508)
		(layer "F.Cu")
		(net "VPLLAV33")
	)
	(segment
		(start 62.73165 -160.979104)
		(end 62.73165 -160.46831)
		(width 0.508)
		(layer "F.Cu")
		(net "VPLLAV33")
	)
	(via
		(at 50.07991 -148.98116)
		(size 0.4572)
		(drill 0.2032)
		(layers "F.Cu" "B.Cu")
		(net "VPLLAV33")
	)
	(via
		(at 60.6298 -156.9466)
		(size 0.6604)
		(drill 0.3302)
		(layers "F.Cu" "B.Cu")
		(net "VPLLAV33")
	)
	(via
		(at 59.8932 -156.2354)
		(size 0.508)
		(drill 0.254)
		(layers "F.Cu" "B.Cu")
		(net "VPLLAV33")
	)
	(via
		(at 50.899822 -148.999956)
		(size 0.4572)
		(drill 0.2032)
		(layers "F.Cu" "B.Cu")
		(net "VPLLAV33")
	)
	(segment
		(start 50.3936 -148.1582)
		(end 50.3936 -144.97304)
		(width 0.508)
		(layer "In2.Cu")
		(net "VPLLAV33")
	)
	(segment
		(start 51.89601 -144.415764)
		(end 52.615846 -145.1356)
		(width 0.508)
		(layer "In2.Cu")
		(net "VPLLAV33")
	)
	(segment
		(start 52.615846 -145.1356)
		(end 55.2196 -145.1356)
		(width 0.508)
		(layer "In2.Cu")
		(net "VPLLAV33")
	)
	(segment
		(start 50.3936 -144.97304)
		(end 50.950876 -144.415764)
		(width 0.508)
		(layer "In2.Cu")
		(net "VPLLAV33")
	)
	(segment
		(start 50.950876 -144.415764)
		(end 51.89601 -144.415764)
		(width 0.508)
		(layer "In2.Cu")
		(net "VPLLAV33")
	)
	(segment
		(start 55.2196 -145.1356)
		(end 55.6768 -145.5928)
		(width 0.508)
		(layer "In2.Cu")
		(net "VPLLAV33")
	)
	(segment
		(start 55.6768 -145.5928)
		(end 55.6768 -150.622)
		(width 0.508)
		(layer "In2.Cu")
		(net "VPLLAV33")
	)
	(segment
		(start 59.8932 -154.8384)
		(end 59.8932 -156.2354)
		(width 0.508)
		(layer "In2.Cu")
		(net "VPLLAV33")
	)
	(segment
		(start 55.6768 -150.622)
		(end 59.8932 -154.8384)
		(width 0.508)
		(layer "In2.Cu")
		(net "VPLLAV33")
	)
	(segment
		(start 48.499776 -150.599902)
		(end 48.499776 -150.599648)
		(width 0.3048)
		(layer "F.Cu")
		(net "V1PLLAV11")
	)
	(segment
		(start 48.499776 -149.800056)
		(end 48.499776 -149.799802)
		(width 0.3048)
		(layer "F.Cu")
		(net "V1PLLAV11")
	)
	(segment
		(start 48.499776 -150.599648)
		(end 48.09998 -150.199852)
		(width 0.3048)
		(layer "F.Cu")
		(net "V1PLLAV11")
	)
	(segment
		(start 48.499776 -149.799802)
		(end 48.09998 -149.400006)
		(width 0.3048)
		(layer "F.Cu")
		(net "V1PLLAV11")
	)
	(via
		(at 48.499776 -150.599902)
		(size 0.4572)
		(drill 0.2032)
		(layers "F.Cu" "B.Cu")
		(net "V1PLLAV11")
	)
	(via
		(at 35.2298 -161.71037)
		(size 0.508)
		(drill 0.254)
		(layers "F.Cu" "B.Cu")
		(net "V1PLLAV11")
	)
	(via
		(at 48.499776 -149.800056)
		(size 0.4572)
		(drill 0.2032)
		(layers "F.Cu" "B.Cu")
		(net "V1PLLAV11")
	)
	(segment
		(start 48.499776 -150.599902)
		(end 48.499776 -149.800056)
		(width 0.3048)
		(layer "B.Cu")
		(net "V1PLLAV11")
	)
	(segment
		(start 44.671996 -156.283152)
		(end 46.2534 -154.701748)
		(width 0.508)
		(layer "In2.Cu")
		(net "V1PLLAV11")
	)
	(segment
		(start 44.671996 -157.664404)
		(end 44.671996 -156.283152)
		(width 0.508)
		(layer "In2.Cu")
		(net "V1PLLAV11")
	)
	(segment
		(start 46.2534 -152.846278)
		(end 48.499776 -150.599902)
		(width 0.381)
		(layer "In2.Cu")
		(net "V1PLLAV11")
	)
	(segment
		(start 46.2534 -154.701748)
		(end 46.2534 -152.846278)
		(width 0.508)
		(layer "In2.Cu")
		(net "V1PLLAV11")
	)
	(segment
		(start 35.2298 -161.71037)
		(end 40.62603 -161.71037)
		(width 0.508)
		(layer "In2.Cu")
		(net "V1PLLAV11")
	)
	(segment
		(start 40.62603 -161.71037)
		(end 44.671996 -157.664404)
		(width 0.508)
		(layer "In2.Cu")
		(net "V1PLLAV11")
	)
	(via
		(at 79.196692 -171.001182)
		(size 0.6096)
		(drill 0.3048)
		(layers "F.Cu" "B.Cu")
		(net "UART_SDB_TX")
	)
	(via
		(at 80.01 -171.4246)
		(size 0.508)
		(drill 0.254)
		(layers "F.Cu" "B.Cu")
		(net "UART_SDB_TX")
	)
	(via
		(at 93.48724 -169.606722)
		(size 0.508)
		(drill 0.254)
		(layers "F.Cu" "B.Cu")
		(net "UART_SDB_TX")
	)
	(segment
		(start 79.248 -169.3545)
		(end 79.248 -169.950892)
		(width 0.127)
		(layer "B.Cu")
		(net "UART_SDB_TX")
	)
	(segment
		(start 79.248 -169.950892)
		(end 79.196692 -170.0022)
		(width 0.127)
		(layer "B.Cu")
		(net "UART_SDB_TX")
	)
	(segment
		(start 80.01 -171.4246)
		(end 79.62011 -171.4246)
		(width 0.127)
		(layer "B.Cu")
		(net "UART_SDB_TX")
	)
	(segment
		(start 79.62011 -171.4246)
		(end 79.196692 -171.001182)
		(width 0.127)
		(layer "B.Cu")
		(net "UART_SDB_TX")
	)
	(segment
		(start 79.196692 -170.0022)
		(end 79.196692 -171.001182)
		(width 0.127)
		(layer "B.Cu")
		(net "UART_SDB_TX")
	)
	(segment
		(start 90.7288 -144.705832)
		(end 91.762834 -143.671798)
		(width 0.127)
		(layer "In2.Cu")
		(net "UART_SDB_TX")
	)
	(segment
		(start 92.2528 -126.096522)
		(end 92.2528 -120.551956)
		(width 0.127)
		(layer "In2.Cu")
		(net "UART_SDB_TX")
	)
	(segment
		(start 93.48724 -169.606722)
		(end 93.675454 -169.418508)
		(width 0.127)
		(layer "In2.Cu")
		(net "UART_SDB_TX")
	)
	(segment
		(start 93.0656 -93.346524)
		(end 93.0656 -63.9064)
		(width 0.127)
		(layer "In2.Cu")
		(net "UART_SDB_TX")
	)
	(segment
		(start 91.762834 -143.671798)
		(end 91.762834 -142.196566)
		(width 0.127)
		(layer "In2.Cu")
		(net "UART_SDB_TX")
	)
	(segment
		(start 91.8464 -159.025844)
		(end 91.8464 -151.510746)
		(width 0.127)
		(layer "In2.Cu")
		(net "UART_SDB_TX")
	)
	(segment
		(start 129.57175 -31.265114)
		(end 129.57175 -31.265368)
		(width 0.127)
		(layer "In2.Cu")
		(net "UART_SDB_TX")
	)
	(segment
		(start 90.7288 -145.9484)
		(end 90.7288 -144.705832)
		(width 0.127)
		(layer "In2.Cu")
		(net "UART_SDB_TX")
	)
	(segment
		(start 93.4466 -94.049596)
		(end 93.4466 -93.727524)
		(width 0.127)
		(layer "In2.Cu")
		(net "UART_SDB_TX")
	)
	(segment
		(start 129.906776 -38.606984)
		(end 130.499866 -39.200074)
		(width 0.127)
		(layer "In2.Cu")
		(net "UART_SDB_TX")
	)
	(segment
		(start 93.4466 -93.727524)
		(end 93.0656 -93.346524)
		(width 0.127)
		(layer "In2.Cu")
		(net "UART_SDB_TX")
	)
	(segment
		(start 94.0562 -94.659196)
		(end 93.4466 -94.049596)
		(width 0.127)
		(layer "In2.Cu")
		(net "UART_SDB_TX")
	)
	(segment
		(start 93.675454 -167.531034)
		(end 95.716344 -165.490144)
		(width 0.127)
		(layer "In2.Cu")
		(net "UART_SDB_TX")
	)
	(segment
		(start 95.716344 -165.490144)
		(end 95.716344 -162.699192)
		(width 0.127)
		(layer "In2.Cu")
		(net "UART_SDB_TX")
	)
	(segment
		(start 93.599 -63.373)
		(end 93.599 -53.028088)
		(width 0.127)
		(layer "In2.Cu")
		(net "UART_SDB_TX")
	)
	(segment
		(start 93.599 -53.028088)
		(end 92.4306 -51.859688)
		(width 0.127)
		(layer "In2.Cu")
		(net "UART_SDB_TX")
	)
	(segment
		(start 92.621354 -141.338046)
		(end 92.621354 -139.02182)
		(width 0.127)
		(layer "In2.Cu")
		(net "UART_SDB_TX")
	)
	(segment
		(start 129.200148 -30.893512)
		(end 129.57175 -31.265114)
		(width 0.127)
		(layer "In2.Cu")
		(net "UART_SDB_TX")
	)
	(segment
		(start 92.256356 -160.682432)
		(end 92.256356 -159.4358)
		(width 0.127)
		(layer "In2.Cu")
		(net "UART_SDB_TX")
	)
	(segment
		(start 91.8464 -151.510746)
		(end 91.1733 -150.837646)
		(width 0.127)
		(layer "In2.Cu")
		(net "UART_SDB_TX")
	)
	(segment
		(start 95.716344 -162.699192)
		(end 95.173546 -162.156394)
		(width 0.127)
		(layer "In2.Cu")
		(net "UART_SDB_TX")
	)
	(segment
		(start 126.280672 -30.893512)
		(end 129.200148 -30.893512)
		(width 0.127)
		(layer "In2.Cu")
		(net "UART_SDB_TX")
	)
	(segment
		(start 92.4306 -48.978058)
		(end 93.513148 -47.89551)
		(width 0.127)
		(layer "In2.Cu")
		(net "UART_SDB_TX")
	)
	(segment
		(start 129.57175 -31.265368)
		(end 129.906776 -31.600394)
		(width 0.127)
		(layer "In2.Cu")
		(net "UART_SDB_TX")
	)
	(segment
		(start 91.1733 -146.3929)
		(end 90.7288 -145.9484)
		(width 0.127)
		(layer "In2.Cu")
		(net "UART_SDB_TX")
	)
	(segment
		(start 92.256356 -159.4358)
		(end 91.8464 -159.025844)
		(width 0.127)
		(layer "In2.Cu")
		(net "UART_SDB_TX")
	)
	(segment
		(start 91.9861 -131.323588)
		(end 91.6051 -130.942588)
		(width 0.127)
		(layer "In2.Cu")
		(net "UART_SDB_TX")
	)
	(segment
		(start 92.2528 -120.551956)
		(end 91.9734 -120.272556)
		(width 0.127)
		(layer "In2.Cu")
		(net "UART_SDB_TX")
	)
	(segment
		(start 129.906776 -31.600394)
		(end 129.906776 -38.606984)
		(width 0.127)
		(layer "In2.Cu")
		(net "UART_SDB_TX")
	)
	(segment
		(start 91.9734 -114.494056)
		(end 91.971368 -114.492024)
		(width 0.127)
		(layer "In2.Cu")
		(net "UART_SDB_TX")
	)
	(segment
		(start 93.513148 -35.974528)
		(end 95.935546 -33.55213)
		(width 0.127)
		(layer "In2.Cu")
		(net "UART_SDB_TX")
	)
	(segment
		(start 91.9861 -138.386566)
		(end 91.9861 -131.323588)
		(width 0.127)
		(layer "In2.Cu")
		(net "UART_SDB_TX")
	)
	(segment
		(start 93.675454 -169.418508)
		(end 93.675454 -167.531034)
		(width 0.127)
		(layer "In2.Cu")
		(net "UART_SDB_TX")
	)
	(segment
		(start 94.0562 -110.86338)
		(end 94.0562 -94.659196)
		(width 0.127)
		(layer "In2.Cu")
		(net "UART_SDB_TX")
	)
	(segment
		(start 115.094004 -21.565616)
		(end 116.642388 -23.114)
		(width 0.127)
		(layer "In2.Cu")
		(net "UART_SDB_TX")
	)
	(segment
		(start 91.9734 -120.272556)
		(end 91.9734 -114.494056)
		(width 0.127)
		(layer "In2.Cu")
		(net "UART_SDB_TX")
	)
	(segment
		(start 93.0656 -63.9064)
		(end 93.599 -63.373)
		(width 0.127)
		(layer "In2.Cu")
		(net "UART_SDB_TX")
	)
	(segment
		(start 91.971368 -112.948212)
		(end 94.0562 -110.86338)
		(width 0.127)
		(layer "In2.Cu")
		(net "UART_SDB_TX")
	)
	(segment
		(start 116.642388 -23.114)
		(end 118.50116 -23.114)
		(width 0.127)
		(layer "In2.Cu")
		(net "UART_SDB_TX")
	)
	(segment
		(start 95.173546 -162.156394)
		(end 93.730318 -162.156394)
		(width 0.127)
		(layer "In2.Cu")
		(net "UART_SDB_TX")
	)
	(segment
		(start 93.730318 -162.156394)
		(end 92.256356 -160.682432)
		(width 0.127)
		(layer "In2.Cu")
		(net "UART_SDB_TX")
	)
	(segment
		(start 95.935546 -33.55213)
		(end 95.935546 -28.982924)
		(width 0.127)
		(layer "In2.Cu")
		(net "UART_SDB_TX")
	)
	(segment
		(start 91.1733 -150.837646)
		(end 91.1733 -146.3929)
		(width 0.127)
		(layer "In2.Cu")
		(net "UART_SDB_TX")
	)
	(segment
		(start 92.4306 -51.859688)
		(end 92.4306 -48.978058)
		(width 0.127)
		(layer "In2.Cu")
		(net "UART_SDB_TX")
	)
	(segment
		(start 91.762834 -142.196566)
		(end 92.621354 -141.338046)
		(width 0.127)
		(layer "In2.Cu")
		(net "UART_SDB_TX")
	)
	(segment
		(start 91.971368 -114.492024)
		(end 91.971368 -112.948212)
		(width 0.127)
		(layer "In2.Cu")
		(net "UART_SDB_TX")
	)
	(segment
		(start 118.50116 -23.114)
		(end 126.280672 -30.893512)
		(width 0.127)
		(layer "In2.Cu")
		(net "UART_SDB_TX")
	)
	(segment
		(start 91.6051 -126.744222)
		(end 92.2528 -126.096522)
		(width 0.127)
		(layer "In2.Cu")
		(net "UART_SDB_TX")
	)
	(segment
		(start 95.935546 -28.982924)
		(end 103.352854 -21.565616)
		(width 0.127)
		(layer "In2.Cu")
		(net "UART_SDB_TX")
	)
	(segment
		(start 103.352854 -21.565616)
		(end 115.094004 -21.565616)
		(width 0.127)
		(layer "In2.Cu")
		(net "UART_SDB_TX")
	)
	(segment
		(start 91.6051 -130.942588)
		(end 91.6051 -126.744222)
		(width 0.127)
		(layer "In2.Cu")
		(net "UART_SDB_TX")
	)
	(segment
		(start 93.513148 -47.89551)
		(end 93.513148 -35.974528)
		(width 0.127)
		(layer "In2.Cu")
		(net "UART_SDB_TX")
	)
	(segment
		(start 92.621354 -139.02182)
		(end 91.9861 -138.386566)
		(width 0.127)
		(layer "In2.Cu")
		(net "UART_SDB_TX")
	)
	(segment
		(start 82.709004 -169.711878)
		(end 80.996282 -171.4246)
		(width 0.127)
		(layer "In5.Cu")
		(net "UART_SDB_TX")
	)
	(segment
		(start 93.356176 -169.711878)
		(end 82.709004 -169.711878)
		(width 0.127)
		(layer "In5.Cu")
		(net "UART_SDB_TX")
	)
	(segment
		(start 93.48724 -169.606722)
		(end 93.461332 -169.606722)
		(width 0.127)
		(layer "In5.Cu")
		(net "UART_SDB_TX")
	)
	(segment
		(start 80.996282 -171.4246)
		(end 80.01 -171.4246)
		(width 0.127)
		(layer "In5.Cu")
		(net "UART_SDB_TX")
	)
	(segment
		(start 93.461332 -169.606722)
		(end 93.356176 -169.711878)
		(width 0.127)
		(layer "In5.Cu")
		(net "UART_SDB_TX")
	)
	(via
		(at 80.649064 -170.589448)
		(size 0.508)
		(drill 0.254)
		(layers "F.Cu" "B.Cu")
		(net "UART_SDB_RX")
	)
	(via
		(at 94.350078 -169.568622)
		(size 0.508)
		(drill 0.254)
		(layers "F.Cu" "B.Cu")
		(net "UART_SDB_RX")
	)
	(via
		(at 80.558386 -169.624502)
		(size 0.6096)
		(drill 0.3048)
		(layers "F.Cu" "B.Cu")
		(net "UART_SDB_RX")
	)
	(segment
		(start 80.344264 -169.838624)
		(end 80.344264 -170.284648)
		(width 0.127)
		(layer "B.Cu")
		(net "UART_SDB_RX")
	)
	(segment
		(start 81.05394 -169.624502)
		(end 81.449164 -170.019726)
		(width 0.127)
		(layer "B.Cu")
		(net "UART_SDB_RX")
	)
	(segment
		(start 81.449164 -170.019726)
		(end 82.051906 -170.019726)
		(width 0.127)
		(layer "B.Cu")
		(net "UART_SDB_RX")
	)
	(segment
		(start 80.344264 -170.284648)
		(end 80.649064 -170.589448)
		(width 0.127)
		(layer "B.Cu")
		(net "UART_SDB_RX")
	)
	(segment
		(start 80.558386 -169.624502)
		(end 80.344264 -169.838624)
		(width 0.127)
		(layer "B.Cu")
		(net "UART_SDB_RX")
	)
	(segment
		(start 80.558386 -169.624502)
		(end 81.05394 -169.624502)
		(width 0.127)
		(layer "B.Cu")
		(net "UART_SDB_RX")
	)
	(segment
		(start 92.6592 -120.060212)
		(end 92.6592 -115.0874)
		(width 0.127)
		(layer "In2.Cu")
		(net "UART_SDB_RX")
	)
	(segment
		(start 93.6117 -134.205218)
		(end 93.8149 -134.002018)
		(width 0.127)
		(layer "In2.Cu")
		(net "UART_SDB_RX")
	)
	(segment
		(start 128.93675 -31.528512)
		(end 129.271522 -31.863284)
		(width 0.127)
		(layer "In2.Cu")
		(net "UART_SDB_RX")
	)
	(segment
		(start 94.350078 -167.754554)
		(end 96.364552 -165.74008)
		(width 0.127)
		(layer "In2.Cu")
		(net "UART_SDB_RX")
	)
	(segment
		(start 92.1766 -146.354546)
		(end 91.5416 -145.719546)
		(width 0.127)
		(layer "In2.Cu")
		(net "UART_SDB_RX")
	)
	(segment
		(start 93.8149 -134.002018)
		(end 93.8149 -132.254244)
		(width 0.127)
		(layer "In2.Cu")
		(net "UART_SDB_RX")
	)
	(segment
		(start 94.234 -52.764944)
		(end 93.425772 -51.956716)
		(width 0.127)
		(layer "In2.Cu")
		(net "UART_SDB_RX")
	)
	(segment
		(start 94.234 -63.7794)
		(end 94.234 -52.764944)
		(width 0.127)
		(layer "In2.Cu")
		(net "UART_SDB_RX")
	)
	(segment
		(start 92.587064 -131.026408)
		(end 92.587064 -126.866396)
		(width 0.127)
		(layer "In2.Cu")
		(net "UART_SDB_RX")
	)
	(segment
		(start 91.8083 -148.5519)
		(end 92.1766 -148.1836)
		(width 0.127)
		(layer "In2.Cu")
		(net "UART_SDB_RX")
	)
	(segment
		(start 92.9386 -112.879124)
		(end 94.6912 -111.126524)
		(width 0.127)
		(layer "In2.Cu")
		(net "UART_SDB_RX")
	)
	(segment
		(start 96.364552 -162.39744)
		(end 95.2119 -161.244788)
		(width 0.127)
		(layer "In2.Cu")
		(net "UART_SDB_RX")
	)
	(segment
		(start 129.271522 -39.371778)
		(end 130.499866 -40.600122)
		(width 0.127)
		(layer "In2.Cu")
		(net "UART_SDB_RX")
	)
	(segment
		(start 94.0816 -93.786452)
		(end 94.0816 -93.46438)
		(width 0.127)
		(layer "In2.Cu")
		(net "UART_SDB_RX")
	)
	(segment
		(start 96.364552 -165.74008)
		(end 96.364552 -162.39744)
		(width 0.127)
		(layer "In2.Cu")
		(net "UART_SDB_RX")
	)
	(segment
		(start 92.6592 -115.0874)
		(end 92.9386 -114.808)
		(width 0.127)
		(layer "In2.Cu")
		(net "UART_SDB_RX")
	)
	(segment
		(start 103.615998 -22.200616)
		(end 114.83086 -22.200616)
		(width 0.127)
		(layer "In2.Cu")
		(net "UART_SDB_RX")
	)
	(segment
		(start 91.5416 -145.719546)
		(end 91.5416 -144.791176)
		(width 0.127)
		(layer "In2.Cu")
		(net "UART_SDB_RX")
	)
	(segment
		(start 93.425772 -51.956716)
		(end 93.425772 -50.795428)
		(width 0.127)
		(layer "In2.Cu")
		(net "UART_SDB_RX")
	)
	(segment
		(start 92.8878 -126.56566)
		(end 92.8878 -120.288812)
		(width 0.127)
		(layer "In2.Cu")
		(net "UART_SDB_RX")
	)
	(segment
		(start 95.2119 -154.165046)
		(end 92.677996 -151.631142)
		(width 0.127)
		(layer "In2.Cu")
		(net "UART_SDB_RX")
	)
	(segment
		(start 94.6912 -94.396052)
		(end 94.0816 -93.786452)
		(width 0.127)
		(layer "In2.Cu")
		(net "UART_SDB_RX")
	)
	(segment
		(start 93.6117 -141.245844)
		(end 93.6117 -134.205218)
		(width 0.127)
		(layer "In2.Cu")
		(net "UART_SDB_RX")
	)
	(segment
		(start 96.570546 -29.246068)
		(end 103.615998 -22.200616)
		(width 0.127)
		(layer "In2.Cu")
		(net "UART_SDB_RX")
	)
	(segment
		(start 92.1766 -148.1836)
		(end 92.1766 -146.354546)
		(width 0.127)
		(layer "In2.Cu")
		(net "UART_SDB_RX")
	)
	(segment
		(start 94.0816 -93.46438)
		(end 93.7006 -93.08338)
		(width 0.127)
		(layer "In2.Cu")
		(net "UART_SDB_RX")
	)
	(segment
		(start 94.6912 -111.126524)
		(end 94.6912 -94.396052)
		(width 0.127)
		(layer "In2.Cu")
		(net "UART_SDB_RX")
	)
	(segment
		(start 126.017528 -31.528512)
		(end 128.93675 -31.528512)
		(width 0.127)
		(layer "In2.Cu")
		(net "UART_SDB_RX")
	)
	(segment
		(start 93.7006 -64.3128)
		(end 94.234 -63.7794)
		(width 0.127)
		(layer "In2.Cu")
		(net "UART_SDB_RX")
	)
	(segment
		(start 116.379244 -23.749)
		(end 118.238016 -23.749)
		(width 0.127)
		(layer "In2.Cu")
		(net "UART_SDB_RX")
	)
	(segment
		(start 114.83086 -22.200616)
		(end 116.379244 -23.749)
		(width 0.127)
		(layer "In2.Cu")
		(net "UART_SDB_RX")
	)
	(segment
		(start 92.397834 -143.934942)
		(end 92.397834 -142.45971)
		(width 0.127)
		(layer "In2.Cu")
		(net "UART_SDB_RX")
	)
	(segment
		(start 92.677996 -151.631142)
		(end 92.677996 -151.444198)
		(width 0.127)
		(layer "In2.Cu")
		(net "UART_SDB_RX")
	)
	(segment
		(start 92.8878 -120.288812)
		(end 92.6592 -120.060212)
		(width 0.127)
		(layer "In2.Cu")
		(net "UART_SDB_RX")
	)
	(segment
		(start 96.570546 -33.815274)
		(end 96.570546 -29.246068)
		(width 0.127)
		(layer "In2.Cu")
		(net "UART_SDB_RX")
	)
	(segment
		(start 92.677996 -151.444198)
		(end 91.8083 -150.574502)
		(width 0.127)
		(layer "In2.Cu")
		(net "UART_SDB_RX")
	)
	(segment
		(start 129.271522 -31.863284)
		(end 129.271522 -39.371778)
		(width 0.127)
		(layer "In2.Cu")
		(net "UART_SDB_RX")
	)
	(segment
		(start 118.238016 -23.749)
		(end 126.017528 -31.528512)
		(width 0.127)
		(layer "In2.Cu")
		(net "UART_SDB_RX")
	)
	(segment
		(start 94.148148 -36.237672)
		(end 96.570546 -33.815274)
		(width 0.127)
		(layer "In2.Cu")
		(net "UART_SDB_RX")
	)
	(segment
		(start 93.425772 -50.795428)
		(end 94.148148 -50.073052)
		(width 0.127)
		(layer "In2.Cu")
		(net "UART_SDB_RX")
	)
	(segment
		(start 94.350078 -169.568622)
		(end 94.350078 -167.754554)
		(width 0.127)
		(layer "In2.Cu")
		(net "UART_SDB_RX")
	)
	(segment
		(start 92.397834 -142.45971)
		(end 93.6117 -141.245844)
		(width 0.127)
		(layer "In2.Cu")
		(net "UART_SDB_RX")
	)
	(segment
		(start 95.2119 -161.244788)
		(end 95.2119 -154.165046)
		(width 0.127)
		(layer "In2.Cu")
		(net "UART_SDB_RX")
	)
	(segment
		(start 92.9386 -114.808)
		(end 92.9386 -112.879124)
		(width 0.127)
		(layer "In2.Cu")
		(net "UART_SDB_RX")
	)
	(segment
		(start 91.8083 -150.574502)
		(end 91.8083 -148.5519)
		(width 0.127)
		(layer "In2.Cu")
		(net "UART_SDB_RX")
	)
	(segment
		(start 93.7006 -93.08338)
		(end 93.7006 -64.3128)
		(width 0.127)
		(layer "In2.Cu")
		(net "UART_SDB_RX")
	)
	(segment
		(start 94.148148 -50.073052)
		(end 94.148148 -36.237672)
		(width 0.127)
		(layer "In2.Cu")
		(net "UART_SDB_RX")
	)
	(segment
		(start 91.5416 -144.791176)
		(end 92.397834 -143.934942)
		(width 0.127)
		(layer "In2.Cu")
		(net "UART_SDB_RX")
	)
	(segment
		(start 93.8149 -132.254244)
		(end 92.587064 -131.026408)
		(width 0.127)
		(layer "In2.Cu")
		(net "UART_SDB_RX")
	)
	(segment
		(start 92.587064 -126.866396)
		(end 92.8878 -126.56566)
		(width 0.127)
		(layer "In2.Cu")
		(net "UART_SDB_RX")
	)
	(segment
		(start 93.704156 -168.9227)
		(end 94.350078 -169.568622)
		(width 0.127)
		(layer "In5.Cu")
		(net "UART_SDB_RX")
	)
	(segment
		(start 88.936322 -169.076878)
		(end 89.0905 -168.9227)
		(width 0.127)
		(layer "In5.Cu")
		(net "UART_SDB_RX")
	)
	(segment
		(start 80.649064 -170.589448)
		(end 82.161634 -169.076878)
		(width 0.127)
		(layer "In5.Cu")
		(net "UART_SDB_RX")
	)
	(segment
		(start 89.0905 -168.9227)
		(end 93.704156 -168.9227)
		(width 0.127)
		(layer "In5.Cu")
		(net "UART_SDB_RX")
	)
	(segment
		(start 82.161634 -169.076878)
		(end 88.936322 -169.076878)
		(width 0.127)
		(layer "In5.Cu")
		(net "UART_SDB_RX")
	)
	(segment
		(start 39.875968 -155.268168)
		(end 41.699942 -153.444194)
		(width 0.127)
		(layer "F.Cu")
		(net "UART_COMP_OUT_TX_R")
	)
	(segment
		(start 39.875968 -155.923234)
		(end 39.875968 -155.268168)
		(width 0.127)
		(layer "F.Cu")
		(net "UART_COMP_OUT_TX_R")
	)
	(segment
		(start 41.699942 -153.444194)
		(end 41.699942 -153.399998)
		(width 0.127)
		(layer "F.Cu")
		(net "UART_COMP_OUT_TX_R")
	)
	(segment
		(start 39.466012 -157.000956)
		(end 39.624 -156.842968)
		(width 0.127)
		(layer "F.Cu")
		(net "UART_COMP_OUT_TX_R")
	)
	(segment
		(start 39.624 -156.842968)
		(end 39.624 -156.175202)
		(width 0.127)
		(layer "F.Cu")
		(net "UART_COMP_OUT_TX_R")
	)
	(segment
		(start 39.0398 -157.427168)
		(end 39.466012 -157.000956)
		(width 0.127)
		(layer "F.Cu")
		(net "UART_COMP_OUT_TX_R")
	)
	(segment
		(start 39.624 -156.175202)
		(end 39.875968 -155.923234)
		(width 0.127)
		(layer "F.Cu")
		(net "UART_COMP_OUT_TX_R")
	)
	(segment
		(start 39.0398 -158.1785)
		(end 39.0398 -157.427168)
		(width 0.127)
		(layer "F.Cu")
		(net "UART_COMP_OUT_TX_R")
	)
	(via
		(at 39.466012 -157.000956)
		(size 0.6604)
		(drill 0.3302)
		(layers "F.Cu" "B.Cu")
		(net "UART_COMP_OUT_TX_R")
	)
	(segment
		(start 72.616314 -179.057808)
		(end 71.478648 -179.057808)
		(width 0.254)
		(layer "F.Cu")
		(net "TPS74801_P2V5_STBY_SS")
	)
	(segment
		(start 71.478648 -179.057808)
		(end 71.09968 -178.67884)
		(width 0.254)
		(layer "F.Cu")
		(net "TPS74801_P2V5_STBY_SS")
	)
	(segment
		(start 70.26402 -178.67884)
		(end 70.041262 -178.901598)
		(width 0.254)
		(layer "F.Cu")
		(net "TPS74801_P2V5_STBY_SS")
	)
	(segment
		(start 71.09968 -178.67884)
		(end 70.26402 -178.67884)
		(width 0.254)
		(layer "F.Cu")
		(net "TPS74801_P2V5_STBY_SS")
	)
	(via
		(at 71.09968 -178.67884)
		(size 0.6604)
		(drill 0.3302)
		(layers "F.Cu" "B.Cu")
		(net "TPS74801_P2V5_STBY_SS")
	)
	(via
		(at 78.74 -175.387)
		(size 0.6604)
		(drill 0.3302)
		(layers "F.Cu" "B.Cu")
		(net "TPS74801_P2V5_STBY_OUT")
	)
	(via
		(at 72.645778 -175.838866)
		(size 0.6604)
		(drill 0.3302)
		(layers "F.Cu" "B.Cu")
		(net "TPS74801_P2V5_STBY_FB")
	)
	(segment
		(start 71.650352 -181.7116)
		(end 71.7042 -181.657752)
		(width 0.254)
		(layer "F.Cu")
		(net "TPS74801_P2V5_STBY_EN")
	)
	(segment
		(start 69.96176 -183.78678)
		(end 69.96176 -182.7403)
		(width 0.254)
		(layer "F.Cu")
		(net "TPS74801_P2V5_STBY_EN")
	)
	(segment
		(start 71.7042 -181.657752)
		(end 72.616314 -181.657752)
		(width 0.254)
		(layer "F.Cu")
		(net "TPS74801_P2V5_STBY_EN")
	)
	(segment
		(start 69.99478 -181.76748)
		(end 69.99478 -182.70728)
		(width 0.254)
		(layer "F.Cu")
		(net "TPS74801_P2V5_STBY_EN")
	)
	(segment
		(start 69.96176 -182.7403)
		(end 69.96938 -182.73268)
		(width 0.254)
		(layer "F.Cu")
		(net "TPS74801_P2V5_STBY_EN")
	)
	(segment
		(start 70.05066 -181.7116)
		(end 69.99478 -181.76748)
		(width 0.254)
		(layer "F.Cu")
		(net "TPS74801_P2V5_STBY_EN")
	)
	(segment
		(start 69.99478 -182.70728)
		(end 69.96938 -182.73268)
		(width 0.254)
		(layer "F.Cu")
		(net "TPS74801_P2V5_STBY_EN")
	)
	(segment
		(start 71.0946 -181.7116)
		(end 70.05066 -181.7116)
		(width 0.254)
		(layer "F.Cu")
		(net "TPS74801_P2V5_STBY_EN")
	)
	(segment
		(start 71.0946 -181.7116)
		(end 71.650352 -181.7116)
		(width 0.254)
		(layer "F.Cu")
		(net "TPS74801_P2V5_STBY_EN")
	)
	(via
		(at 71.0946 -181.7116)
		(size 0.6604)
		(drill 0.3302)
		(layers "F.Cu" "B.Cu")
		(net "TPS74801_P2V5_STBY_EN")
	)
	(segment
		(start 71.957692 -185.46318)
		(end 71.890128 -185.530744)
		(width 0.254)
		(layer "F.Cu")
		(net "TPS74801_P2V5_STBY_BIAS")
	)
	(segment
		(start 73.05548 -185.46318)
		(end 71.957692 -185.46318)
		(width 0.254)
		(layer "F.Cu")
		(net "TPS74801_P2V5_STBY_BIAS")
	)
	(segment
		(start 73.0504 -183.9976)
		(end 73.791064 -183.256936)
		(width 0.254)
		(layer "F.Cu")
		(net "TPS74801_P2V5_STBY_BIAS")
	)
	(segment
		(start 73.0504 -184.5056)
		(end 73.0504 -183.9976)
		(width 0.254)
		(layer "F.Cu")
		(net "TPS74801_P2V5_STBY_BIAS")
	)
	(segment
		(start 73.791064 -183.256936)
		(end 73.791064 -182.832502)
		(width 0.254)
		(layer "F.Cu")
		(net "TPS74801_P2V5_STBY_BIAS")
	)
	(segment
		(start 73.05548 -185.46318)
		(end 73.05548 -184.51068)
		(width 0.254)
		(layer "F.Cu")
		(net "TPS74801_P2V5_STBY_BIAS")
	)
	(segment
		(start 73.05548 -184.51068)
		(end 73.0504 -184.5056)
		(width 0.254)
		(layer "F.Cu")
		(net "TPS74801_P2V5_STBY_BIAS")
	)
	(via
		(at 73.0504 -184.5056)
		(size 0.6604)
		(drill 0.3302)
		(layers "F.Cu" "B.Cu")
		(net "TPS74801_P2V5_STBY_BIAS")
	)
	(segment
		(start 11.430508 -167.616886)
		(end 12.573 -167.616886)
		(width 0.254)
		(layer "F.Cu")
		(net "TPS74801_P1V2_STBY_SS")
	)
	(segment
		(start 13.39088 -167.616886)
		(end 13.599922 -167.825928)
		(width 0.254)
		(layer "F.Cu")
		(net "TPS74801_P1V2_STBY_SS")
	)
	(segment
		(start 13.599922 -167.825928)
		(end 14.216634 -167.825928)
		(width 0.254)
		(layer "F.Cu")
		(net "TPS74801_P1V2_STBY_SS")
	)
	(segment
		(start 12.573 -167.616886)
		(end 13.39088 -167.616886)
		(width 0.254)
		(layer "F.Cu")
		(net "TPS74801_P1V2_STBY_SS")
	)
	(via
		(at 12.573 -167.616886)
		(size 0.6604)
		(drill 0.3302)
		(layers "F.Cu" "B.Cu")
		(net "TPS74801_P1V2_STBY_SS")
	)
	(via
		(at 21.1963 -164.24148)
		(size 0.6604)
		(drill 0.3302)
		(layers "F.Cu" "B.Cu")
		(net "TPS74801_P1V2_STBY_OUT")
	)
	(via
		(at 18.60931 -164.42817)
		(size 0.6604)
		(drill 0.3302)
		(layers "F.Cu" "B.Cu")
		(net "TPS74801_P1V2_STBY_OUT")
	)
	(via
		(at 14.19733 -163.446714)
		(size 0.6604)
		(drill 0.3302)
		(layers "F.Cu" "B.Cu")
		(net "TPS74801_P1V2_STBY_FB")
	)
	(segment
		(start 12.462764 -170.425872)
		(end 14.216634 -170.425872)
		(width 0.254)
		(layer "F.Cu")
		(net "TPS74801_P1V2_STBY_EN")
	)
	(segment
		(start 12.251436 -170.6372)
		(end 12.462764 -170.425872)
		(width 0.254)
		(layer "F.Cu")
		(net "TPS74801_P1V2_STBY_EN")
	)
	(segment
		(start 12.234164 -171.577)
		(end 12.2428 -171.585636)
		(width 0.254)
		(layer "F.Cu")
		(net "TPS74801_P1V2_STBY_EN")
	)
	(segment
		(start 11.0998 -172.530516)
		(end 11.0998 -171.6786)
		(width 0.254)
		(layer "F.Cu")
		(net "TPS74801_P1V2_STBY_EN")
	)
	(segment
		(start 11.0998 -171.6786)
		(end 11.1252 -171.6532)
		(width 0.254)
		(layer "F.Cu")
		(net "TPS74801_P1V2_STBY_EN")
	)
	(segment
		(start 12.251436 -171.577)
		(end 12.2428 -171.585636)
		(width 0.254)
		(layer "F.Cu")
		(net "TPS74801_P1V2_STBY_EN")
	)
	(segment
		(start 11.1252 -171.6532)
		(end 11.2014 -171.577)
		(width 0.254)
		(layer "F.Cu")
		(net "TPS74801_P1V2_STBY_EN")
	)
	(segment
		(start 10.973816 -172.6565)
		(end 11.0998 -172.530516)
		(width 0.254)
		(layer "F.Cu")
		(net "TPS74801_P1V2_STBY_EN")
	)
	(segment
		(start 12.251436 -170.6372)
		(end 12.251436 -171.577)
		(width 0.254)
		(layer "F.Cu")
		(net "TPS74801_P1V2_STBY_EN")
	)
	(segment
		(start 11.2014 -171.577)
		(end 12.234164 -171.577)
		(width 0.254)
		(layer "F.Cu")
		(net "TPS74801_P1V2_STBY_EN")
	)
	(via
		(at 11.1252 -171.6532)
		(size 0.6604)
		(drill 0.3302)
		(layers "F.Cu" "B.Cu")
		(net "TPS74801_P1V2_STBY_EN")
	)
	(segment
		(start 18.011648 -174.56658)
		(end 16.9418 -174.56658)
		(width 0.254)
		(layer "F.Cu")
		(net "TPS74801_P1V2_STBY_BIAS")
	)
	(segment
		(start 16.9418 -174.56658)
		(end 15.391384 -173.016164)
		(width 0.254)
		(layer "F.Cu")
		(net "TPS74801_P1V2_STBY_BIAS")
	)
	(segment
		(start 20.809712 -175.206406)
		(end 19.788378 -175.206406)
		(width 0.254)
		(layer "F.Cu")
		(net "TPS74801_P1V2_STBY_BIAS")
	)
	(segment
		(start 19.787362 -175.20539)
		(end 18.650458 -175.20539)
		(width 0.254)
		(layer "F.Cu")
		(net "TPS74801_P1V2_STBY_BIAS")
	)
	(segment
		(start 19.788378 -175.206406)
		(end 19.787362 -175.20539)
		(width 0.254)
		(layer "F.Cu")
		(net "TPS74801_P1V2_STBY_BIAS")
	)
	(segment
		(start 15.391384 -173.016164)
		(end 15.391384 -171.600622)
		(width 0.254)
		(layer "F.Cu")
		(net "TPS74801_P1V2_STBY_BIAS")
	)
	(segment
		(start 18.650458 -175.20539)
		(end 18.011648 -174.56658)
		(width 0.254)
		(layer "F.Cu")
		(net "TPS74801_P1V2_STBY_BIAS")
	)
	(via
		(at 19.787362 -175.20539)
		(size 0.6604)
		(drill 0.3302)
		(layers "F.Cu" "B.Cu")
		(net "TPS74801_P1V2_STBY_BIAS")
	)
	(segment
		(start 73.347834 -161.826194)
		(end 74.2696 -160.904428)
		(width 0.254)
		(layer "F.Cu")
		(net "TPS74801_P1V15_STBY_SS")
	)
	(segment
		(start 73.347834 -161.982404)
		(end 73.347834 -161.826194)
		(width 0.254)
		(layer "F.Cu")
		(net "TPS74801_P1V15_STBY_SS")
	)
	(segment
		(start 72.490584 -161.982404)
		(end 72.36968 -161.8615)
		(width 0.254)
		(layer "F.Cu")
		(net "TPS74801_P1V15_STBY_SS")
	)
	(segment
		(start 73.347834 -161.982404)
		(end 72.490584 -161.982404)
		(width 0.254)
		(layer "F.Cu")
		(net "TPS74801_P1V15_STBY_SS")
	)
	(segment
		(start 74.2696 -160.904428)
		(end 75.325478 -160.904428)
		(width 0.254)
		(layer "F.Cu")
		(net "TPS74801_P1V15_STBY_SS")
	)
	(via
		(at 73.347834 -161.982404)
		(size 0.6604)
		(drill 0.3302)
		(layers "F.Cu" "B.Cu")
		(net "TPS74801_P1V15_STBY_SS")
	)
	(via
		(at 80.391 -157.099)
		(size 0.6604)
		(drill 0.3302)
		(layers "F.Cu" "B.Cu")
		(net "TPS74801_P1V15_STBY_OUT")
	)
	(via
		(at 75.819 -158.0388)
		(size 0.6604)
		(drill 0.3302)
		(layers "F.Cu" "B.Cu")
		(net "TPS74801_P1V15_STBY_FB")
	)
	(segment
		(start 75.325478 -163.504372)
		(end 74.569828 -163.504372)
		(width 0.254)
		(layer "F.Cu")
		(net "TPS74801_P1V15_STBY_EN")
	)
	(segment
		(start 72.67448 -164.586412)
		(end 72.67448 -165.619176)
		(width 0.254)
		(layer "F.Cu")
		(net "TPS74801_P1V15_STBY_EN")
	)
	(segment
		(start 73.787 -163.7538)
		(end 73.345548 -163.7538)
		(width 0.254)
		(layer "F.Cu")
		(net "TPS74801_P1V15_STBY_EN")
	)
	(segment
		(start 73.205848 -163.6141)
		(end 72.67448 -163.6141)
		(width 0.254)
		(layer "F.Cu")
		(net "TPS74801_P1V15_STBY_EN")
	)
	(segment
		(start 74.3204 -163.7538)
		(end 73.787 -163.7538)
		(width 0.254)
		(layer "F.Cu")
		(net "TPS74801_P1V15_STBY_EN")
	)
	(segment
		(start 72.67448 -163.6141)
		(end 72.67448 -164.586412)
		(width 0.254)
		(layer "F.Cu")
		(net "TPS74801_P1V15_STBY_EN")
	)
	(segment
		(start 74.569828 -163.504372)
		(end 74.3204 -163.7538)
		(width 0.254)
		(layer "F.Cu")
		(net "TPS74801_P1V15_STBY_EN")
	)
	(segment
		(start 73.345548 -163.7538)
		(end 73.205848 -163.6141)
		(width 0.254)
		(layer "F.Cu")
		(net "TPS74801_P1V15_STBY_EN")
	)
	(via
		(at 73.787 -163.7538)
		(size 0.6604)
		(drill 0.3302)
		(layers "F.Cu" "B.Cu")
		(net "TPS74801_P1V15_STBY_EN")
	)
	(segment
		(start 76.073 -165.8366)
		(end 76.500228 -165.409372)
		(width 0.254)
		(layer "F.Cu")
		(net "TPS74801_P1V15_STBY_BIAS")
	)
	(segment
		(start 76.500228 -165.409372)
		(end 76.500228 -164.679122)
		(width 0.254)
		(layer "F.Cu")
		(net "TPS74801_P1V15_STBY_BIAS")
	)
	(segment
		(start 74.680572 -166.37)
		(end 75.213972 -165.8366)
		(width 0.254)
		(layer "F.Cu")
		(net "TPS74801_P1V15_STBY_BIAS")
	)
	(segment
		(start 73.561448 -168.015666)
		(end 74.249534 -168.015666)
		(width 0.254)
		(layer "F.Cu")
		(net "TPS74801_P1V15_STBY_BIAS")
	)
	(segment
		(start 74.249534 -168.015666)
		(end 74.680572 -167.584628)
		(width 0.254)
		(layer "F.Cu")
		(net "TPS74801_P1V15_STBY_BIAS")
	)
	(segment
		(start 75.213972 -165.8366)
		(end 76.073 -165.8366)
		(width 0.254)
		(layer "F.Cu")
		(net "TPS74801_P1V15_STBY_BIAS")
	)
	(segment
		(start 74.680572 -167.584628)
		(end 74.680572 -166.37)
		(width 0.254)
		(layer "F.Cu")
		(net "TPS74801_P1V15_STBY_BIAS")
	)
	(via
		(at 74.680572 -166.37)
		(size 0.6604)
		(drill 0.3302)
		(layers "F.Cu" "B.Cu")
		(net "TPS74801_P1V15_STBY_BIAS")
	)
	(segment
		(start 185.74766 -130.316478)
		(end 183.900064 -128.468882)
		(width 0.127)
		(layer "F.Cu")
		(net "TP_M2_2_MFG_DAT")
	)
	(segment
		(start 183.900064 -128.468882)
		(end 183.900064 -127.324866)
		(width 0.127)
		(layer "F.Cu")
		(net "TP_M2_2_MFG_DAT")
	)
	(segment
		(start 187.6298 -140.0556)
		(end 187.6298 -138.926062)
		(width 0.127)
		(layer "F.Cu")
		(net "TP_M2_2_MFG_DAT")
	)
	(segment
		(start 187.6298 -138.926062)
		(end 185.74766 -137.043922)
		(width 0.127)
		(layer "F.Cu")
		(net "TP_M2_2_MFG_DAT")
	)
	(segment
		(start 185.74766 -137.043922)
		(end 185.74766 -130.316478)
		(width 0.127)
		(layer "F.Cu")
		(net "TP_M2_2_MFG_DAT")
	)
	(segment
		(start 188.1886 -140.6144)
		(end 187.6298 -140.0556)
		(width 0.127)
		(layer "F.Cu")
		(net "TP_M2_2_MFG_DAT")
	)
	(segment
		(start 186.20486 -136.29386)
		(end 186.20486 -130.189478)
		(width 0.127)
		(layer "F.Cu")
		(net "TP_M2_2_MFG_CLK")
	)
	(segment
		(start 184.399936 -128.384554)
		(end 184.399936 -127.324866)
		(width 0.127)
		(layer "F.Cu")
		(net "TP_M2_2_MFG_CLK")
	)
	(segment
		(start 188.214 -139.1158)
		(end 188.214 -138.303)
		(width 0.127)
		(layer "F.Cu")
		(net "TP_M2_2_MFG_CLK")
	)
	(segment
		(start 186.20486 -130.189478)
		(end 184.399936 -128.384554)
		(width 0.127)
		(layer "F.Cu")
		(net "TP_M2_2_MFG_CLK")
	)
	(segment
		(start 188.214 -138.303)
		(end 186.20486 -136.29386)
		(width 0.127)
		(layer "F.Cu")
		(net "TP_M2_2_MFG_CLK")
	)
	(segment
		(start 210.928204 -123.039632)
		(end 210.928204 -122.666506)
		(width 0.127)
		(layer "F.Cu")
		(net "TP_M2_1_MFG_DAT")
	)
	(segment
		(start 208.900014 -127.324866)
		(end 208.900014 -125.067822)
		(width 0.127)
		(layer "F.Cu")
		(net "TP_M2_1_MFG_DAT")
	)
	(segment
		(start 208.900014 -125.067822)
		(end 210.928204 -123.039632)
		(width 0.127)
		(layer "F.Cu")
		(net "TP_M2_1_MFG_DAT")
	)
	(segment
		(start 209.399886 -125.58522)
		(end 212.331046 -122.65406)
		(width 0.127)
		(layer "F.Cu")
		(net "TP_M2_1_MFG_CLK")
	)
	(segment
		(start 209.399886 -127.324866)
		(end 209.399886 -125.58522)
		(width 0.127)
		(layer "F.Cu")
		(net "TP_M2_1_MFG_CLK")
	)
	(segment
		(start 55.70093 -153.000964)
		(end 55.299864 -152.599898)
		(width 0.127)
		(layer "F.Cu")
		(net "TP_BMC_GPIOT6")
	)
	(segment
		(start 55.9054 -156.673296)
		(end 55.9054 -154.432)
		(width 0.127)
		(layer "F.Cu")
		(net "TP_BMC_GPIOT6")
	)
	(segment
		(start 55.9054 -154.432)
		(end 55.70093 -154.22753)
		(width 0.127)
		(layer "F.Cu")
		(net "TP_BMC_GPIOT6")
	)
	(segment
		(start 56.362092 -157.129988)
		(end 55.9054 -156.673296)
		(width 0.127)
		(layer "F.Cu")
		(net "TP_BMC_GPIOT6")
	)
	(segment
		(start 55.70093 -154.22753)
		(end 55.70093 -153.000964)
		(width 0.127)
		(layer "F.Cu")
		(net "TP_BMC_GPIOT6")
	)
	(segment
		(start 58.3946 -153.483056)
		(end 59.845956 -154.934412)
		(width 0.127)
		(layer "F.Cu")
		(net "TP_BMC_GPIOT0")
	)
	(segment
		(start 56.127904 -150.542752)
		(end 58.3946 -152.809448)
		(width 0.127)
		(layer "F.Cu")
		(net "TP_BMC_GPIOT0")
	)
	(segment
		(start 55.614824 -150.199852)
		(end 55.957724 -150.542752)
		(width 0.127)
		(layer "F.Cu")
		(net "TP_BMC_GPIOT0")
	)
	(segment
		(start 55.957724 -150.542752)
		(end 56.127904 -150.542752)
		(width 0.127)
		(layer "F.Cu")
		(net "TP_BMC_GPIOT0")
	)
	(segment
		(start 55.299864 -150.199852)
		(end 55.614824 -150.199852)
		(width 0.127)
		(layer "F.Cu")
		(net "TP_BMC_GPIOT0")
	)
	(segment
		(start 58.3946 -152.809448)
		(end 58.3946 -153.483056)
		(width 0.127)
		(layer "F.Cu")
		(net "TP_BMC_GPIOT0")
	)
	(segment
		(start 43.700192 -151.399748)
		(end 44.099988 -150.999952)
		(width 0.127)
		(layer "F.Cu")
		(net "TP_BMC_GPION7")
	)
	(segment
		(start 43.700192 -151.400002)
		(end 43.700192 -151.399748)
		(width 0.127)
		(layer "F.Cu")
		(net "TP_BMC_GPION7")
	)
	(via
		(at 43.700192 -151.400002)
		(size 0.4572)
		(drill 0.2032)
		(layers "F.Cu" "B.Cu")
		(net "TP_BMC_GPION7")
	)
	(segment
		(start 42.931334 -154.997912)
		(end 42.956734 -154.972512)
		(width 0.127)
		(layer "B.Cu")
		(net "TP_BMC_GPION7")
	)
	(segment
		(start 43.306492 -152.3873)
		(end 43.306492 -151.793702)
		(width 0.127)
		(layer "B.Cu")
		(net "TP_BMC_GPION7")
	)
	(segment
		(start 43.624754 -152.705562)
		(end 43.306492 -152.3873)
		(width 0.127)
		(layer "B.Cu")
		(net "TP_BMC_GPION7")
	)
	(segment
		(start 42.956734 -154.020266)
		(end 43.624754 -153.352246)
		(width 0.127)
		(layer "B.Cu")
		(net "TP_BMC_GPION7")
	)
	(segment
		(start 43.624754 -153.352246)
		(end 43.624754 -152.705562)
		(width 0.127)
		(layer "B.Cu")
		(net "TP_BMC_GPION7")
	)
	(segment
		(start 43.306492 -151.793702)
		(end 43.700192 -151.400002)
		(width 0.127)
		(layer "B.Cu")
		(net "TP_BMC_GPION7")
	)
	(segment
		(start 42.956734 -154.972512)
		(end 42.956734 -154.020266)
		(width 0.127)
		(layer "B.Cu")
		(net "TP_BMC_GPION7")
	)
	(segment
		(start 40.899842 -151.800052)
		(end 40.499792 -152.200102)
		(width 0.127)
		(layer "F.Cu")
		(net "TP_BMC_GPION6")
	)
	(via
		(at 40.499792 -152.200102)
		(size 0.4572)
		(drill 0.2032)
		(layers "F.Cu" "B.Cu")
		(net "TP_BMC_GPION6")
	)
	(segment
		(start 40.499792 -152.718008)
		(end 40.499792 -152.200102)
		(width 0.127)
		(layer "B.Cu")
		(net "TP_BMC_GPION6")
	)
	(segment
		(start 40.0812 -153.1366)
		(end 40.499792 -152.718008)
		(width 0.127)
		(layer "B.Cu")
		(net "TP_BMC_GPION6")
	)
	(segment
		(start 37.65423 -155.28417)
		(end 37.65423 -153.72461)
		(width 0.127)
		(layer "F.Cu")
		(net "TP_BMC_GPION5")
	)
	(segment
		(start 39.66845 -152.231598)
		(end 40.099996 -151.800052)
		(width 0.127)
		(layer "F.Cu")
		(net "TP_BMC_GPION5")
	)
	(segment
		(start 39.147242 -152.231598)
		(end 39.66845 -152.231598)
		(width 0.127)
		(layer "F.Cu")
		(net "TP_BMC_GPION5")
	)
	(segment
		(start 36.322 -157.001718)
		(end 36.322 -156.6164)
		(width 0.127)
		(layer "F.Cu")
		(net "TP_BMC_GPION5")
	)
	(segment
		(start 35.58286 -157.740858)
		(end 36.322 -157.001718)
		(width 0.127)
		(layer "F.Cu")
		(net "TP_BMC_GPION5")
	)
	(segment
		(start 37.65423 -153.72461)
		(end 39.147242 -152.231598)
		(width 0.127)
		(layer "F.Cu")
		(net "TP_BMC_GPION5")
	)
	(segment
		(start 36.322 -156.6164)
		(end 37.65423 -155.28417)
		(width 0.127)
		(layer "F.Cu")
		(net "TP_BMC_GPION5")
	)
	(segment
		(start 41.699942 -151.800052)
		(end 41.299892 -152.200102)
		(width 0.127)
		(layer "F.Cu")
		(net "TP_BMC_GPION4")
	)
	(via
		(at 41.299892 -152.200102)
		(size 0.4572)
		(drill 0.2032)
		(layers "F.Cu" "B.Cu")
		(net "TP_BMC_GPION4")
	)
	(segment
		(start 39.345362 -154.548332)
		(end 39.462456 -154.548332)
		(width 0.127)
		(layer "B.Cu")
		(net "TP_BMC_GPION4")
	)
	(segment
		(start 41.299892 -152.710896)
		(end 41.299892 -152.200102)
		(width 0.127)
		(layer "B.Cu")
		(net "TP_BMC_GPION4")
	)
	(segment
		(start 39.462456 -154.548332)
		(end 41.299892 -152.710896)
		(width 0.127)
		(layer "B.Cu")
		(net "TP_BMC_GPION4")
	)
	(segment
		(start 42.900092 -152.199848)
		(end 43.299888 -151.800052)
		(width 0.127)
		(layer "F.Cu")
		(net "TP_BMC_GPION3")
	)
	(segment
		(start 42.900092 -152.200102)
		(end 42.900092 -152.199848)
		(width 0.127)
		(layer "F.Cu")
		(net "TP_BMC_GPION3")
	)
	(via
		(at 42.900092 -152.200102)
		(size 0.4572)
		(drill 0.2032)
		(layers "F.Cu" "B.Cu")
		(net "TP_BMC_GPION3")
	)
	(segment
		(start 42.900092 -152.529032)
		(end 42.900092 -152.200102)
		(width 0.127)
		(layer "B.Cu")
		(net "TP_BMC_GPION3")
	)
	(segment
		(start 42.987468 -152.616408)
		(end 42.900092 -152.529032)
		(width 0.127)
		(layer "B.Cu")
		(net "TP_BMC_GPION3")
	)
	(segment
		(start 42.987468 -153.189178)
		(end 42.987468 -152.616408)
		(width 0.127)
		(layer "B.Cu")
		(net "TP_BMC_GPION3")
	)
	(segment
		(start 42.500042 -151.800052)
		(end 42.099992 -152.200102)
		(width 0.127)
		(layer "F.Cu")
		(net "TP_BMC_GPION2")
	)
	(via
		(at 42.099992 -152.200102)
		(size 0.4572)
		(drill 0.2032)
		(layers "F.Cu" "B.Cu")
		(net "TP_BMC_GPION2")
	)
	(segment
		(start 41.653714 -153.965148)
		(end 42.099992 -153.51887)
		(width 0.127)
		(layer "B.Cu")
		(net "TP_BMC_GPION2")
	)
	(segment
		(start 42.099992 -153.51887)
		(end 42.099992 -152.200102)
		(width 0.127)
		(layer "B.Cu")
		(net "TP_BMC_GPION2")
	)
	(segment
		(start 45.699934 -151.800306)
		(end 45.300138 -152.200102)
		(width 0.127)
		(layer "F.Cu")
		(net "TP_BMC_GPIOL5")
	)
	(segment
		(start 45.699934 -151.800052)
		(end 45.699934 -151.800306)
		(width 0.127)
		(layer "F.Cu")
		(net "TP_BMC_GPIOL5")
	)
	(via
		(at 45.300138 -152.200102)
		(size 0.4572)
		(drill 0.2032)
		(layers "F.Cu" "B.Cu")
		(net "TP_BMC_GPIOL5")
	)
	(segment
		(start 45.300138 -152.200102)
		(end 45.300138 -152.818338)
		(width 0.127)
		(layer "B.Cu")
		(net "TP_BMC_GPIOL5")
	)
	(segment
		(start 45.300138 -152.818338)
		(end 45.593 -153.1112)
		(width 0.127)
		(layer "B.Cu")
		(net "TP_BMC_GPIOL5")
	)
	(segment
		(start 45.699934 -150.999952)
		(end 45.699934 -151.000206)
		(width 0.127)
		(layer "F.Cu")
		(net "TP_BMC_GPIOL4")
	)
	(segment
		(start 45.699934 -151.000206)
		(end 45.299884 -151.400256)
		(width 0.127)
		(layer "F.Cu")
		(net "TP_BMC_GPIOL4")
	)
	(via
		(at 45.299884 -151.400256)
		(size 0.4572)
		(drill 0.2032)
		(layers "F.Cu" "B.Cu")
		(net "TP_BMC_GPIOL4")
	)
	(segment
		(start 45.74413 -150.95601)
		(end 46.61281 -150.95601)
		(width 0.127)
		(layer "B.Cu")
		(net "TP_BMC_GPIOL4")
	)
	(segment
		(start 45.299884 -151.400256)
		(end 45.74413 -150.95601)
		(width 0.127)
		(layer "B.Cu")
		(net "TP_BMC_GPIOL4")
	)
	(segment
		(start 46.9392 -151.2824)
		(end 47.4472 -151.2824)
		(width 0.127)
		(layer "B.Cu")
		(net "TP_BMC_GPIOL4")
	)
	(segment
		(start 46.61281 -150.95601)
		(end 46.9392 -151.2824)
		(width 0.127)
		(layer "B.Cu")
		(net "TP_BMC_GPIOL4")
	)
	(segment
		(start 42.852848 -153.046938)
		(end 43.299888 -152.599898)
		(width 0.127)
		(layer "F.Cu")
		(net "TP_BMC_GPIOL3")
	)
	(segment
		(start 40.9194 -157.8102)
		(end 40.9194 -154.94)
		(width 0.127)
		(layer "F.Cu")
		(net "TP_BMC_GPIOL3")
	)
	(segment
		(start 41.7576 -154.1018)
		(end 42.28338 -154.1018)
		(width 0.127)
		(layer "F.Cu")
		(net "TP_BMC_GPIOL3")
	)
	(segment
		(start 42.28338 -154.1018)
		(end 42.852848 -153.532332)
		(width 0.127)
		(layer "F.Cu")
		(net "TP_BMC_GPIOL3")
	)
	(segment
		(start 40.9194 -154.94)
		(end 41.7576 -154.1018)
		(width 0.127)
		(layer "F.Cu")
		(net "TP_BMC_GPIOL3")
	)
	(segment
		(start 42.852848 -153.532332)
		(end 42.852848 -153.046938)
		(width 0.127)
		(layer "F.Cu")
		(net "TP_BMC_GPIOL3")
	)
	(segment
		(start 40.6654 -158.0642)
		(end 40.9194 -157.8102)
		(width 0.127)
		(layer "F.Cu")
		(net "TP_BMC_GPIOL3")
	)
	(segment
		(start 41.1226 -159.4612)
		(end 41.3258 -159.258)
		(width 0.127)
		(layer "F.Cu")
		(net "TP_BMC_GPIOL2")
	)
	(segment
		(start 41.9862 -156.112718)
		(end 41.9862 -155.374848)
		(width 0.127)
		(layer "F.Cu")
		(net "TP_BMC_GPIOL2")
	)
	(segment
		(start 41.3258 -159.258)
		(end 41.3258 -156.773118)
		(width 0.127)
		(layer "F.Cu")
		(net "TP_BMC_GPIOL2")
	)
	(segment
		(start 43.299888 -154.06116)
		(end 43.299888 -153.399998)
		(width 0.127)
		(layer "F.Cu")
		(net "TP_BMC_GPIOL2")
	)
	(segment
		(start 41.3258 -156.773118)
		(end 41.9862 -156.112718)
		(width 0.127)
		(layer "F.Cu")
		(net "TP_BMC_GPIOL2")
	)
	(segment
		(start 41.9862 -155.374848)
		(end 43.299888 -154.06116)
		(width 0.127)
		(layer "F.Cu")
		(net "TP_BMC_GPIOL2")
	)
	(segment
		(start 42.7609 -156.8069)
		(end 42.7609 -155.393136)
		(width 0.127)
		(layer "F.Cu")
		(net "TP_BMC_GPIOL1")
	)
	(segment
		(start 42.7609 -155.393136)
		(end 44.099988 -154.054048)
		(width 0.127)
		(layer "F.Cu")
		(net "TP_BMC_GPIOL1")
	)
	(segment
		(start 42.5196 -157.0482)
		(end 42.7609 -156.8069)
		(width 0.127)
		(layer "F.Cu")
		(net "TP_BMC_GPIOL1")
	)
	(segment
		(start 44.099988 -154.054048)
		(end 44.099988 -153.399998)
		(width 0.127)
		(layer "F.Cu")
		(net "TP_BMC_GPIOL1")
	)
	(segment
		(start 43.688 -153.011886)
		(end 44.099988 -152.599898)
		(width 0.127)
		(layer "F.Cu")
		(net "TP_BMC_GPIOL0")
	)
	(segment
		(start 42.346626 -156.29128)
		(end 42.346626 -155.337764)
		(width 0.127)
		(layer "F.Cu")
		(net "TP_BMC_GPIOL0")
	)
	(segment
		(start 43.688 -153.99639)
		(end 43.688 -153.011886)
		(width 0.127)
		(layer "F.Cu")
		(net "TP_BMC_GPIOL0")
	)
	(segment
		(start 42.346626 -155.337764)
		(end 43.688 -153.99639)
		(width 0.127)
		(layer "F.Cu")
		(net "TP_BMC_GPIOL0")
	)
	(segment
		(start 41.7068 -158.0134)
		(end 41.7068 -156.931106)
		(width 0.127)
		(layer "F.Cu")
		(net "TP_BMC_GPIOL0")
	)
	(segment
		(start 41.7068 -156.931106)
		(end 42.346626 -156.29128)
		(width 0.127)
		(layer "F.Cu")
		(net "TP_BMC_GPIOL0")
	)
	(segment
		(start 42.1132 -158.4198)
		(end 41.7068 -158.0134)
		(width 0.127)
		(layer "F.Cu")
		(net "TP_BMC_GPIOL0")
	)
	(segment
		(start 61.2394 -138.2014)
		(end 60.5917 -138.8491)
		(width 0.127)
		(layer "F.Cu")
		(net "TP_BMC_GPIOI7")
	)
	(segment
		(start 60.5917 -138.8491)
		(end 59.6519 -138.8491)
		(width 0.127)
		(layer "F.Cu")
		(net "TP_BMC_GPIOI7")
	)
	(segment
		(start 56.958738 -142.199868)
		(end 56.099964 -142.199868)
		(width 0.127)
		(layer "F.Cu")
		(net "TP_BMC_GPIOI7")
	)
	(segment
		(start 58.639456 -140.51915)
		(end 56.958738 -142.199868)
		(width 0.127)
		(layer "F.Cu")
		(net "TP_BMC_GPIOI7")
	)
	(segment
		(start 59.6519 -138.8491)
		(end 58.639456 -139.861544)
		(width 0.127)
		(layer "F.Cu")
		(net "TP_BMC_GPIOI7")
	)
	(segment
		(start 58.639456 -139.861544)
		(end 58.639456 -140.51915)
		(width 0.127)
		(layer "F.Cu")
		(net "TP_BMC_GPIOI7")
	)
	(segment
		(start 56.847232 -142.999968)
		(end 59.118246 -140.728954)
		(width 0.127)
		(layer "F.Cu")
		(net "TP_BMC_GPIOI6")
	)
	(segment
		(start 59.651646 -140.728954)
		(end 60.4774 -139.9032)
		(width 0.127)
		(layer "F.Cu")
		(net "TP_BMC_GPIOI6")
	)
	(segment
		(start 59.118246 -140.728954)
		(end 59.651646 -140.728954)
		(width 0.127)
		(layer "F.Cu")
		(net "TP_BMC_GPIOI6")
	)
	(segment
		(start 56.099964 -142.999968)
		(end 56.847232 -142.999968)
		(width 0.127)
		(layer "F.Cu")
		(net "TP_BMC_GPIOI6")
	)
	(segment
		(start 54.899814 -141.800326)
		(end 54.89956 -141.800326)
		(width 0.127)
		(layer "F.Cu")
		(net "TP_BMC_GPIOI5")
	)
	(segment
		(start 54.89956 -141.800326)
		(end 54.500018 -142.199868)
		(width 0.127)
		(layer "F.Cu")
		(net "TP_BMC_GPIOI5")
	)
	(via
		(at 54.899814 -141.800326)
		(size 0.4572)
		(drill 0.2032)
		(layers "F.Cu" "B.Cu")
		(net "TP_BMC_GPIOI5")
	)
	(segment
		(start 55.887874 -141.800326)
		(end 54.899814 -141.800326)
		(width 0.127)
		(layer "B.Cu")
		(net "TP_BMC_GPIOI5")
	)
	(segment
		(start 56.007 -141.6812)
		(end 55.887874 -141.800326)
		(width 0.127)
		(layer "B.Cu")
		(net "TP_BMC_GPIOI5")
	)
	(segment
		(start 59.5884 -138.303)
		(end 58.410602 -139.480798)
		(width 0.127)
		(layer "F.Cu")
		(net "TP_BMC_GPIOI4")
	)
	(segment
		(start 57.4802 -141.097)
		(end 56.731662 -141.845538)
		(width 0.127)
		(layer "F.Cu")
		(net "TP_BMC_GPIOI4")
	)
	(segment
		(start 58.410602 -140.424662)
		(end 57.738264 -141.097)
		(width 0.127)
		(layer "F.Cu")
		(net "TP_BMC_GPIOI4")
	)
	(segment
		(start 56.731662 -141.845538)
		(end 55.654194 -141.845538)
		(width 0.127)
		(layer "F.Cu")
		(net "TP_BMC_GPIOI4")
	)
	(segment
		(start 55.654194 -141.845538)
		(end 55.299864 -142.199868)
		(width 0.127)
		(layer "F.Cu")
		(net "TP_BMC_GPIOI4")
	)
	(segment
		(start 59.8678 -138.303)
		(end 59.5884 -138.303)
		(width 0.127)
		(layer "F.Cu")
		(net "TP_BMC_GPIOI4")
	)
	(segment
		(start 58.410602 -139.480798)
		(end 58.410602 -140.424662)
		(width 0.127)
		(layer "F.Cu")
		(net "TP_BMC_GPIOI4")
	)
	(segment
		(start 57.738264 -141.097)
		(end 57.4802 -141.097)
		(width 0.127)
		(layer "F.Cu")
		(net "TP_BMC_GPIOI4")
	)
	(segment
		(start 54.899814 -141.00048)
		(end 54.89956 -141.00048)
		(width 0.127)
		(layer "F.Cu")
		(net "TP_BMC_GPIOI3")
	)
	(segment
		(start 54.89956 -141.00048)
		(end 54.500018 -141.400022)
		(width 0.127)
		(layer "F.Cu")
		(net "TP_BMC_GPIOI3")
	)
	(via
		(at 54.899814 -141.00048)
		(size 0.4572)
		(drill 0.2032)
		(layers "F.Cu" "B.Cu")
		(net "TP_BMC_GPIOI3")
	)
	(segment
		(start 55.591964 -141.00048)
		(end 55.685944 -140.9065)
		(width 0.127)
		(layer "B.Cu")
		(net "TP_BMC_GPIOI3")
	)
	(segment
		(start 54.899814 -141.00048)
		(end 55.591964 -141.00048)
		(width 0.127)
		(layer "B.Cu")
		(net "TP_BMC_GPIOI3")
	)
	(segment
		(start 56.4007 -140.9065)
		(end 56.9722 -140.335)
		(width 0.127)
		(layer "B.Cu")
		(net "TP_BMC_GPIOI3")
	)
	(segment
		(start 55.685944 -140.9065)
		(end 56.4007 -140.9065)
		(width 0.127)
		(layer "B.Cu")
		(net "TP_BMC_GPIOI3")
	)
	(segment
		(start 57.73928 -139.908534)
		(end 57.73928 -139.494514)
		(width 0.127)
		(layer "F.Cu")
		(net "TP_BMC_GPIOI2")
	)
	(segment
		(start 61.997082 -137.668)
		(end 62.3062 -137.668)
		(width 0.127)
		(layer "F.Cu")
		(net "TP_BMC_GPIOI2")
	)
	(segment
		(start 59.406028 -137.694162)
		(end 60.061602 -137.694162)
		(width 0.127)
		(layer "F.Cu")
		(net "TP_BMC_GPIOI2")
	)
	(segment
		(start 56.677814 -140.97)
		(end 57.73928 -139.908534)
		(width 0.127)
		(layer "F.Cu")
		(net "TP_BMC_GPIOI2")
	)
	(segment
		(start 55.299864 -141.400022)
		(end 55.729886 -140.97)
		(width 0.127)
		(layer "F.Cu")
		(net "TP_BMC_GPIOI2")
	)
	(segment
		(start 62.3062 -137.668)
		(end 62.8142 -138.176)
		(width 0.127)
		(layer "F.Cu")
		(net "TP_BMC_GPIOI2")
	)
	(segment
		(start 60.061602 -137.694162)
		(end 60.163964 -137.5918)
		(width 0.127)
		(layer "F.Cu")
		(net "TP_BMC_GPIOI2")
	)
	(segment
		(start 60.163964 -137.5918)
		(end 61.920882 -137.5918)
		(width 0.127)
		(layer "F.Cu")
		(net "TP_BMC_GPIOI2")
	)
	(segment
		(start 58.803794 -138.296396)
		(end 59.406028 -137.694162)
		(width 0.127)
		(layer "F.Cu")
		(net "TP_BMC_GPIOI2")
	)
	(segment
		(start 58.803794 -138.43)
		(end 58.803794 -138.296396)
		(width 0.127)
		(layer "F.Cu")
		(net "TP_BMC_GPIOI2")
	)
	(segment
		(start 61.920882 -137.5918)
		(end 61.997082 -137.668)
		(width 0.127)
		(layer "F.Cu")
		(net "TP_BMC_GPIOI2")
	)
	(segment
		(start 55.729886 -140.97)
		(end 56.677814 -140.97)
		(width 0.127)
		(layer "F.Cu")
		(net "TP_BMC_GPIOI2")
	)
	(segment
		(start 57.73928 -139.494514)
		(end 58.803794 -138.43)
		(width 0.127)
		(layer "F.Cu")
		(net "TP_BMC_GPIOI2")
	)
	(segment
		(start 53.299614 -141.800072)
		(end 52.899818 -142.199868)
		(width 0.127)
		(layer "F.Cu")
		(net "TP_BMC_GPIOI1")
	)
	(segment
		(start 53.299868 -141.800072)
		(end 53.299614 -141.800072)
		(width 0.127)
		(layer "F.Cu")
		(net "TP_BMC_GPIOI1")
	)
	(via
		(at 53.299868 -141.800072)
		(size 0.4572)
		(drill 0.2032)
		(layers "F.Cu" "B.Cu")
		(net "TP_BMC_GPIOI1")
	)
	(segment
		(start 52.893468 -140.837158)
		(end 52.66309 -140.60678)
		(width 0.127)
		(layer "B.Cu")
		(net "TP_BMC_GPIOI1")
	)
	(segment
		(start 50.749454 -139.80668)
		(end 50.388774 -139.446)
		(width 0.127)
		(layer "B.Cu")
		(net "TP_BMC_GPIOI1")
	)
	(segment
		(start 52.093368 -140.363702)
		(end 52.093368 -140.037058)
		(width 0.127)
		(layer "B.Cu")
		(net "TP_BMC_GPIOI1")
	)
	(segment
		(start 51.86299 -139.80668)
		(end 50.749454 -139.80668)
		(width 0.127)
		(layer "B.Cu")
		(net "TP_BMC_GPIOI1")
	)
	(segment
		(start 50.388774 -139.446)
		(end 50.1396 -139.446)
		(width 0.127)
		(layer "B.Cu")
		(net "TP_BMC_GPIOI1")
	)
	(segment
		(start 52.893468 -141.393672)
		(end 52.893468 -140.837158)
		(width 0.127)
		(layer "B.Cu")
		(net "TP_BMC_GPIOI1")
	)
	(segment
		(start 52.66309 -140.60678)
		(end 52.336446 -140.60678)
		(width 0.127)
		(layer "B.Cu")
		(net "TP_BMC_GPIOI1")
	)
	(segment
		(start 52.093368 -140.037058)
		(end 51.86299 -139.80668)
		(width 0.127)
		(layer "B.Cu")
		(net "TP_BMC_GPIOI1")
	)
	(segment
		(start 52.336446 -140.60678)
		(end 52.093368 -140.363702)
		(width 0.127)
		(layer "B.Cu")
		(net "TP_BMC_GPIOI1")
	)
	(segment
		(start 53.299868 -141.800072)
		(end 52.893468 -141.393672)
		(width 0.127)
		(layer "B.Cu")
		(net "TP_BMC_GPIOI1")
	)
	(segment
		(start 54.900068 -139.40028)
		(end 54.500272 -139.800076)
		(width 0.127)
		(layer "F.Cu")
		(net "TP_BMC_GPIOI0")
	)
	(segment
		(start 54.500272 -139.800076)
		(end 54.500018 -139.800076)
		(width 0.127)
		(layer "F.Cu")
		(net "TP_BMC_GPIOI0")
	)
	(via
		(at 54.900068 -139.40028)
		(size 0.4572)
		(drill 0.2032)
		(layers "F.Cu" "B.Cu")
		(net "TP_BMC_GPIOI0")
	)
	(segment
		(start 55.5244 -139.0142)
		(end 55.13832 -139.40028)
		(width 0.127)
		(layer "B.Cu")
		(net "TP_BMC_GPIOI0")
	)
	(segment
		(start 55.528972 -139.0142)
		(end 55.5244 -139.0142)
		(width 0.127)
		(layer "B.Cu")
		(net "TP_BMC_GPIOI0")
	)
	(segment
		(start 56.3118 -138.557)
		(end 55.986172 -138.557)
		(width 0.127)
		(layer "B.Cu")
		(net "TP_BMC_GPIOI0")
	)
	(segment
		(start 55.986172 -138.557)
		(end 55.528972 -139.0142)
		(width 0.127)
		(layer "B.Cu")
		(net "TP_BMC_GPIOI0")
	)
	(segment
		(start 55.13832 -139.40028)
		(end 54.900068 -139.40028)
		(width 0.127)
		(layer "B.Cu")
		(net "TP_BMC_GPIOI0")
	)
	(segment
		(start 39.642796 -150.657052)
		(end 40.099996 -150.199852)
		(width 0.127)
		(layer "F.Cu")
		(net "THROTTLE_N")
	)
	(segment
		(start 36.195 -152.161748)
		(end 37.915088 -152.161748)
		(width 0.127)
		(layer "F.Cu")
		(net "THROTTLE_N")
	)
	(segment
		(start 38.468554 -151.608282)
		(end 38.468554 -151.346154)
		(width 0.127)
		(layer "F.Cu")
		(net "THROTTLE_N")
	)
	(segment
		(start 34.975546 -152.161748)
		(end 36.195 -152.161748)
		(width 0.127)
		(layer "F.Cu")
		(net "THROTTLE_N")
	)
	(segment
		(start 39.157656 -150.657052)
		(end 39.642796 -150.657052)
		(width 0.127)
		(layer "F.Cu")
		(net "THROTTLE_N")
	)
	(segment
		(start 38.468554 -151.346154)
		(end 39.157656 -150.657052)
		(width 0.127)
		(layer "F.Cu")
		(net "THROTTLE_N")
	)
	(segment
		(start 37.915088 -152.161748)
		(end 38.468554 -151.608282)
		(width 0.127)
		(layer "F.Cu")
		(net "THROTTLE_N")
	)
	(via
		(at 36.195 -152.161748)
		(size 0.6604)
		(drill 0.3302)
		(layers "F.Cu" "B.Cu")
		(net "THROTTLE_N")
	)
	(via
		(at 44.760896 -118.991888)
		(size 0.6096)
		(drill 0.3048)
		(layers "F.Cu" "B.Cu")
		(net "TEMP_3_SDA")
	)
	(segment
		(start 44.31792 -118.991888)
		(end 44.141136 -119.168672)
		(width 0.127)
		(layer "B.Cu")
		(net "TEMP_3_SDA")
	)
	(segment
		(start 45.521626 -119.11584)
		(end 46.66234 -119.11584)
		(width 0.127)
		(layer "B.Cu")
		(net "TEMP_3_SDA")
	)
	(segment
		(start 44.760896 -118.991888)
		(end 45.397674 -118.991888)
		(width 0.127)
		(layer "B.Cu")
		(net "TEMP_3_SDA")
	)
	(segment
		(start 44.141136 -119.168672)
		(end 43.573954 -119.168672)
		(width 0.127)
		(layer "B.Cu")
		(net "TEMP_3_SDA")
	)
	(segment
		(start 45.397674 -118.991888)
		(end 45.521626 -119.11584)
		(width 0.127)
		(layer "B.Cu")
		(net "TEMP_3_SDA")
	)
	(segment
		(start 44.760896 -118.991888)
		(end 44.31792 -118.991888)
		(width 0.127)
		(layer "B.Cu")
		(net "TEMP_3_SDA")
	)
	(via
		(at 44.768008 -120.287034)
		(size 0.6096)
		(drill 0.3048)
		(layers "F.Cu" "B.Cu")
		(net "TEMP_3_SCL")
	)
	(segment
		(start 45.76572 -119.76608)
		(end 46.66234 -119.76608)
		(width 0.127)
		(layer "B.Cu")
		(net "TEMP_3_SCL")
	)
	(segment
		(start 43.650916 -120.287034)
		(end 43.573954 -120.210072)
		(width 0.127)
		(layer "B.Cu")
		(net "TEMP_3_SCL")
	)
	(segment
		(start 45.244766 -120.287034)
		(end 45.76572 -119.76608)
		(width 0.127)
		(layer "B.Cu")
		(net "TEMP_3_SCL")
	)
	(segment
		(start 44.768008 -120.287034)
		(end 45.244766 -120.287034)
		(width 0.127)
		(layer "B.Cu")
		(net "TEMP_3_SCL")
	)
	(segment
		(start 44.768008 -120.287034)
		(end 43.650916 -120.287034)
		(width 0.127)
		(layer "B.Cu")
		(net "TEMP_3_SCL")
	)
	(segment
		(start 45.95368 -120.41632)
		(end 46.66234 -120.41632)
		(width 0.127)
		(layer "B.Cu")
		(net "TEMP_3_ALERT")
	)
	(segment
		(start 45.3644 -122.8852)
		(end 45.3644 -121.0056)
		(width 0.127)
		(layer "B.Cu")
		(net "TEMP_3_ALERT")
	)
	(segment
		(start 45.3644 -121.0056)
		(end 45.95368 -120.41632)
		(width 0.127)
		(layer "B.Cu")
		(net "TEMP_3_ALERT")
	)
	(via
		(at 52.705 -122.682)
		(size 0.6096)
		(drill 0.3048)
		(layers "F.Cu" "B.Cu")
		(net "TEMP_3_A2")
	)
	(segment
		(start 50.77206 -121.06656)
		(end 50.77206 -121.66346)
		(width 0.127)
		(layer "B.Cu")
		(net "TEMP_3_A2")
	)
	(segment
		(start 50.77206 -121.66346)
		(end 51.5239 -122.4153)
		(width 0.127)
		(layer "B.Cu")
		(net "TEMP_3_A2")
	)
	(segment
		(start 52.705 -122.682)
		(end 51.5239 -122.682)
		(width 0.127)
		(layer "B.Cu")
		(net "TEMP_3_A2")
	)
	(segment
		(start 53.879242 -122.682)
		(end 53.88991 -122.671332)
		(width 0.127)
		(layer "B.Cu")
		(net "TEMP_3_A2")
	)
	(segment
		(start 51.5239 -122.4153)
		(end 51.5239 -122.682)
		(width 0.127)
		(layer "B.Cu")
		(net "TEMP_3_A2")
	)
	(segment
		(start 52.705 -122.682)
		(end 53.879242 -122.682)
		(width 0.127)
		(layer "B.Cu")
		(net "TEMP_3_A2")
	)
	(via
		(at 52.9336 -121.1326)
		(size 0.6096)
		(drill 0.3048)
		(layers "F.Cu" "B.Cu")
		(net "TEMP_3_A1")
	)
	(segment
		(start 52.9336 -121.1326)
		(end 52.21732 -120.41632)
		(width 0.127)
		(layer "B.Cu")
		(net "TEMP_3_A1")
	)
	(segment
		(start 55.348632 -121.81459)
		(end 56.17591 -121.81459)
		(width 0.127)
		(layer "B.Cu")
		(net "TEMP_3_A1")
	)
	(segment
		(start 52.21732 -120.41632)
		(end 50.77206 -120.41632)
		(width 0.127)
		(layer "B.Cu")
		(net "TEMP_3_A1")
	)
	(segment
		(start 56.17591 -121.81459)
		(end 56.4134 -121.5771)
		(width 0.127)
		(layer "B.Cu")
		(net "TEMP_3_A1")
	)
	(segment
		(start 53.61559 -121.81459)
		(end 52.9336 -121.1326)
		(width 0.127)
		(layer "B.Cu")
		(net "TEMP_3_A1")
	)
	(segment
		(start 55.348632 -121.81459)
		(end 53.61559 -121.81459)
		(width 0.127)
		(layer "B.Cu")
		(net "TEMP_3_A1")
	)
	(via
		(at 52.6542 -119.76608)
		(size 0.6096)
		(drill 0.3048)
		(layers "F.Cu" "B.Cu")
		(net "TEMP_3_A0")
	)
	(segment
		(start 53.218842 -119.76608)
		(end 53.34 -119.644922)
		(width 0.127)
		(layer "B.Cu")
		(net "TEMP_3_A0")
	)
	(segment
		(start 50.77206 -119.76608)
		(end 52.6542 -119.76608)
		(width 0.127)
		(layer "B.Cu")
		(net "TEMP_3_A0")
	)
	(segment
		(start 54.9275 -119.6594)
		(end 54.887622 -119.644922)
		(width 0.127)
		(layer "B.Cu")
		(net "TEMP_3_A0")
	)
	(segment
		(start 52.6542 -119.76608)
		(end 53.218842 -119.76608)
		(width 0.127)
		(layer "B.Cu")
		(net "TEMP_3_A0")
	)
	(segment
		(start 54.887622 -119.644922)
		(end 53.877972 -119.644922)
		(width 0.127)
		(layer "B.Cu")
		(net "TEMP_3_A0")
	)
	(segment
		(start 53.34 -119.644922)
		(end 53.877972 -119.644922)
		(width 0.127)
		(layer "B.Cu")
		(net "TEMP_3_A0")
	)
	(segment
		(start 117.294152 -25.250648)
		(end 116.646198 -25.898602)
		(width 0.127)
		(layer "F.Cu")
		(net "SYS_RESET_N")
	)
	(segment
		(start 113.182908 -42.11701)
		(end 112.499902 -42.800016)
		(width 0.127)
		(layer "F.Cu")
		(net "SYS_RESET_N")
	)
	(segment
		(start 117.723666 -25.250648)
		(end 117.294152 -25.250648)
		(width 0.127)
		(layer "F.Cu")
		(net "SYS_RESET_N")
	)
	(segment
		(start 113.629948 -28.889452)
		(end 113.182908 -29.336492)
		(width 0.127)
		(layer "F.Cu")
		(net "SYS_RESET_N")
	)
	(segment
		(start 113.629948 -27.91714)
		(end 113.629948 -28.889452)
		(width 0.127)
		(layer "F.Cu")
		(net "SYS_RESET_N")
	)
	(segment
		(start 113.182908 -29.336492)
		(end 113.182908 -42.11701)
		(width 0.127)
		(layer "F.Cu")
		(net "SYS_RESET_N")
	)
	(segment
		(start 115.648486 -25.898602)
		(end 113.629948 -27.91714)
		(width 0.127)
		(layer "F.Cu")
		(net "SYS_RESET_N")
	)
	(segment
		(start 116.646198 -25.898602)
		(end 115.648486 -25.898602)
		(width 0.127)
		(layer "F.Cu")
		(net "SYS_RESET_N")
	)
	(via
		(at 117.723666 -25.250648)
		(size 0.508)
		(drill 0.254)
		(layers "F.Cu" "B.Cu")
		(net "SYS_RESET_N")
	)
	(via
		(at 33.219898 -121.701052)
		(size 0.508)
		(drill 0.254)
		(layers "F.Cu" "B.Cu")
		(net "SYS_RESET_N")
	)
	(via
		(at 32.08782 -113.054892)
		(size 0.6096)
		(drill 0.3048)
		(layers "F.Cu" "B.Cu")
		(net "SYS_RESET_N")
	)
	(via
		(at 58.794904 -114.214148)
		(size 0.508)
		(drill 0.254)
		(layers "F.Cu" "B.Cu")
		(net "SYS_RESET_N")
	)
	(via
		(at 28.7782 -113.935256)
		(size 0.508)
		(drill 0.254)
		(layers "F.Cu" "B.Cu")
		(net "SYS_RESET_N")
	)
	(segment
		(start 54.805834 -111.5568)
		(end 38.808914 -111.5568)
		(width 0.127)
		(layer "B.Cu")
		(net "SYS_RESET_N")
	)
	(segment
		(start 29.658564 -113.054892)
		(end 28.7782 -113.935256)
		(width 0.127)
		(layer "B.Cu")
		(net "SYS_RESET_N")
	)
	(segment
		(start 58.794904 -114.214148)
		(end 57.991756 -113.411)
		(width 0.127)
		(layer "B.Cu")
		(net "SYS_RESET_N")
	)
	(segment
		(start 37.310822 -113.054892)
		(end 32.08782 -113.054892)
		(width 0.127)
		(layer "B.Cu")
		(net "SYS_RESET_N")
	)
	(segment
		(start 34.0487 -126.62916)
		(end 34.0487 -122.529854)
		(width 0.127)
		(layer "B.Cu")
		(net "SYS_RESET_N")
	)
	(segment
		(start 56.660034 -113.411)
		(end 54.805834 -111.5568)
		(width 0.127)
		(layer "B.Cu")
		(net "SYS_RESET_N")
	)
	(segment
		(start 57.991756 -113.411)
		(end 56.660034 -113.411)
		(width 0.127)
		(layer "B.Cu")
		(net "SYS_RESET_N")
	)
	(segment
		(start 34.0487 -122.529854)
		(end 33.219898 -121.701052)
		(width 0.127)
		(layer "B.Cu")
		(net "SYS_RESET_N")
	)
	(segment
		(start 38.808914 -111.5568)
		(end 37.310822 -113.054892)
		(width 0.127)
		(layer "B.Cu")
		(net "SYS_RESET_N")
	)
	(segment
		(start 32.08782 -113.054892)
		(end 29.658564 -113.054892)
		(width 0.127)
		(layer "B.Cu")
		(net "SYS_RESET_N")
	)
	(segment
		(start 30.48127 -115.638326)
		(end 28.7782 -113.935256)
		(width 0.127)
		(layer "In2.Cu")
		(net "SYS_RESET_N")
	)
	(segment
		(start 30.48127 -118.962424)
		(end 30.48127 -115.638326)
		(width 0.127)
		(layer "In2.Cu")
		(net "SYS_RESET_N")
	)
	(segment
		(start 33.219898 -121.701052)
		(end 30.48127 -118.962424)
		(width 0.127)
		(layer "In2.Cu")
		(net "SYS_RESET_N")
	)
	(segment
		(start 92.855796 -8.775192)
		(end 84.575396 -8.775192)
		(width 0.127)
		(layer "In5.Cu")
		(net "SYS_RESET_N")
	)
	(segment
		(start 76.2127 -49.9745)
		(end 76.2127 -99.012756)
		(width 0.127)
		(layer "In5.Cu")
		(net "SYS_RESET_N")
	)
	(segment
		(start 84.575396 -8.775192)
		(end 82.200242 -11.150346)
		(width 0.127)
		(layer "In5.Cu")
		(net "SYS_RESET_N")
	)
	(segment
		(start 79.0702 -47.609506)
		(end 77.80401 -48.875696)
		(width 0.127)
		(layer "In5.Cu")
		(net "SYS_RESET_N")
	)
	(segment
		(start 79.0702 -43.757342)
		(end 79.0702 -47.609506)
		(width 0.127)
		(layer "In5.Cu")
		(net "SYS_RESET_N")
	)
	(segment
		(start 113.0681 -22.1869)
		(end 105.146856 -22.1869)
		(width 0.127)
		(layer "In5.Cu")
		(net "SYS_RESET_N")
	)
	(segment
		(start 59.075066 -114.49431)
		(end 58.794904 -114.214148)
		(width 0.127)
		(layer "In5.Cu")
		(net "SYS_RESET_N")
	)
	(segment
		(start 117.723666 -25.250648)
		(end 116.131848 -25.250648)
		(width 0.127)
		(layer "In5.Cu")
		(net "SYS_RESET_N")
	)
	(segment
		(start 83.665314 -105.875328)
		(end 79.961994 -109.578648)
		(width 0.127)
		(layer "In5.Cu")
		(net "SYS_RESET_N")
	)
	(segment
		(start 60.351416 -114.49431)
		(end 59.075066 -114.49431)
		(width 0.127)
		(layer "In5.Cu")
		(net "SYS_RESET_N")
	)
	(segment
		(start 78.723744 -101.5238)
		(end 81.294478 -101.5238)
		(width 0.127)
		(layer "In5.Cu")
		(net "SYS_RESET_N")
	)
	(segment
		(start 72.508618 -114.7191)
		(end 60.576206 -114.7191)
		(width 0.127)
		(layer "In5.Cu")
		(net "SYS_RESET_N")
	)
	(segment
		(start 77.31125 -48.875696)
		(end 76.2127 -49.9745)
		(width 0.127)
		(layer "In5.Cu")
		(net "SYS_RESET_N")
	)
	(segment
		(start 77.80401 -48.875696)
		(end 77.31125 -48.875696)
		(width 0.127)
		(layer "In5.Cu")
		(net "SYS_RESET_N")
	)
	(segment
		(start 77.64907 -109.578648)
		(end 72.508618 -114.7191)
		(width 0.127)
		(layer "In5.Cu")
		(net "SYS_RESET_N")
	)
	(segment
		(start 82.200242 -40.6273)
		(end 79.0702 -43.757342)
		(width 0.127)
		(layer "In5.Cu")
		(net "SYS_RESET_N")
	)
	(segment
		(start 96.1771 -12.096496)
		(end 92.855796 -8.775192)
		(width 0.127)
		(layer "In5.Cu")
		(net "SYS_RESET_N")
	)
	(segment
		(start 105.146856 -22.1869)
		(end 96.1771 -13.217144)
		(width 0.127)
		(layer "In5.Cu")
		(net "SYS_RESET_N")
	)
	(segment
		(start 96.1771 -13.217144)
		(end 96.1771 -12.096496)
		(width 0.127)
		(layer "In5.Cu")
		(net "SYS_RESET_N")
	)
	(segment
		(start 83.665314 -103.894636)
		(end 83.665314 -105.875328)
		(width 0.127)
		(layer "In5.Cu")
		(net "SYS_RESET_N")
	)
	(segment
		(start 76.2127 -99.012756)
		(end 78.723744 -101.5238)
		(width 0.127)
		(layer "In5.Cu")
		(net "SYS_RESET_N")
	)
	(segment
		(start 79.961994 -109.578648)
		(end 77.64907 -109.578648)
		(width 0.127)
		(layer "In5.Cu")
		(net "SYS_RESET_N")
	)
	(segment
		(start 82.200242 -11.150346)
		(end 82.200242 -40.6273)
		(width 0.127)
		(layer "In5.Cu")
		(net "SYS_RESET_N")
	)
	(segment
		(start 60.576206 -114.7191)
		(end 60.351416 -114.49431)
		(width 0.127)
		(layer "In5.Cu")
		(net "SYS_RESET_N")
	)
	(segment
		(start 116.131848 -25.250648)
		(end 113.0681 -22.1869)
		(width 0.127)
		(layer "In5.Cu")
		(net "SYS_RESET_N")
	)
	(segment
		(start 81.294478 -101.5238)
		(end 83.665314 -103.894636)
		(width 0.127)
		(layer "In5.Cu")
		(net "SYS_RESET_N")
	)
	(segment
		(start 52.899818 -143.800068)
		(end 53.299868 -143.400018)
		(width 0.127)
		(layer "F.Cu")
		(net "SYS_PWR_LED")
	)
	(via
		(at 84.505292 -138.109452)
		(size 0.508)
		(drill 0.254)
		(layers "F.Cu" "B.Cu")
		(net "SYS_PWR_LED")
	)
	(via
		(at 57.277 -141.478)
		(size 0.6096)
		(drill 0.3048)
		(layers "F.Cu" "B.Cu")
		(net "SYS_PWR_LED")
	)
	(via
		(at 53.299868 -143.400018)
		(size 0.4572)
		(drill 0.2032)
		(layers "F.Cu" "B.Cu")
		(net "SYS_PWR_LED")
	)
	(segment
		(start 53.6956 -143.004286)
		(end 53.6956 -142.447264)
		(width 0.127)
		(layer "B.Cu")
		(net "SYS_PWR_LED")
	)
	(segment
		(start 56.511698 -142.24)
		(end 57.277 -141.474698)
		(width 0.127)
		(layer "B.Cu")
		(net "SYS_PWR_LED")
	)
	(segment
		(start 54.26329 -142.206218)
		(end 54.263798 -142.206726)
		(width 0.127)
		(layer "B.Cu")
		(net "SYS_PWR_LED")
	)
	(segment
		(start 55.063136 -142.206726)
		(end 55.09641 -142.24)
		(width 0.127)
		(layer "B.Cu")
		(net "SYS_PWR_LED")
	)
	(segment
		(start 58.853832 -139.953238)
		(end 59.2582 -139.54887)
		(width 0.127)
		(layer "B.Cu")
		(net "SYS_PWR_LED")
	)
	(segment
		(start 60.2742 -138.9761)
		(end 59.2582 -138.9761)
		(width 0.127)
		(layer "B.Cu")
		(net "SYS_PWR_LED")
	)
	(segment
		(start 53.6956 -142.447264)
		(end 53.936646 -142.206218)
		(width 0.127)
		(layer "B.Cu")
		(net "SYS_PWR_LED")
	)
	(segment
		(start 57.277 -141.474698)
		(end 57.375298 -141.3764)
		(width 0.127)
		(layer "B.Cu")
		(net "SYS_PWR_LED")
	)
	(segment
		(start 55.09641 -142.24)
		(end 56.511698 -142.24)
		(width 0.127)
		(layer "B.Cu")
		(net "SYS_PWR_LED")
	)
	(segment
		(start 57.277 -141.478)
		(end 57.277 -141.474698)
		(width 0.127)
		(layer "B.Cu")
		(net "SYS_PWR_LED")
	)
	(segment
		(start 53.936646 -142.206218)
		(end 54.26329 -142.206218)
		(width 0.127)
		(layer "B.Cu")
		(net "SYS_PWR_LED")
	)
	(segment
		(start 53.299868 -143.400018)
		(end 53.6956 -143.004286)
		(width 0.127)
		(layer "B.Cu")
		(net "SYS_PWR_LED")
	)
	(segment
		(start 54.263798 -142.206726)
		(end 55.063136 -142.206726)
		(width 0.127)
		(layer "B.Cu")
		(net "SYS_PWR_LED")
	)
	(segment
		(start 57.375298 -141.3764)
		(end 58.039 -141.3764)
		(width 0.127)
		(layer "B.Cu")
		(net "SYS_PWR_LED")
	)
	(segment
		(start 58.853832 -140.561568)
		(end 58.853832 -139.953238)
		(width 0.127)
		(layer "B.Cu")
		(net "SYS_PWR_LED")
	)
	(segment
		(start 58.039 -141.3764)
		(end 58.853832 -140.561568)
		(width 0.127)
		(layer "B.Cu")
		(net "SYS_PWR_LED")
	)
	(segment
		(start 59.2582 -139.54887)
		(end 59.2582 -138.9761)
		(width 0.127)
		(layer "B.Cu")
		(net "SYS_PWR_LED")
	)
	(segment
		(start 136.852406 -40.847518)
		(end 136.852406 -31.227268)
		(width 0.127)
		(layer "In2.Cu")
		(net "SYS_PWR_LED")
	)
	(segment
		(start 130.847592 -25.222454)
		(end 125.998986 -25.222454)
		(width 0.127)
		(layer "In2.Cu")
		(net "SYS_PWR_LED")
	)
	(segment
		(start 82.918554 -134.220966)
		(end 82.918554 -136.271508)
		(width 0.127)
		(layer "In2.Cu")
		(net "SYS_PWR_LED")
	)
	(segment
		(start 86.0044 -99.468432)
		(end 88.1253 -101.589332)
		(width 0.127)
		(layer "In2.Cu")
		(net "SYS_PWR_LED")
	)
	(segment
		(start 95.935038 -14.089634)
		(end 95.935038 -10.851896)
		(width 0.127)
		(layer "In2.Cu")
		(net "SYS_PWR_LED")
	)
	(segment
		(start 94.009718 -8.926576)
		(end 84.503768 -8.926576)
		(width 0.127)
		(layer "In2.Cu")
		(net "SYS_PWR_LED")
	)
	(segment
		(start 85.725 -35.00501)
		(end 85.725 -53.686202)
		(width 0.127)
		(layer "In2.Cu")
		(net "SYS_PWR_LED")
	)
	(segment
		(start 86.1695 -122.762772)
		(end 81.4705 -127.461772)
		(width 0.127)
		(layer "In2.Cu")
		(net "SYS_PWR_LED")
	)
	(segment
		(start 88.1253 -108.405168)
		(end 85.8647 -110.665768)
		(width 0.127)
		(layer "In2.Cu")
		(net "SYS_PWR_LED")
	)
	(segment
		(start 115.624864 -16.707104)
		(end 98.552508 -16.707104)
		(width 0.127)
		(layer "In2.Cu")
		(net "SYS_PWR_LED")
	)
	(segment
		(start 135.899906 -41.800018)
		(end 136.852406 -40.847518)
		(width 0.127)
		(layer "In2.Cu")
		(net "SYS_PWR_LED")
	)
	(segment
		(start 95.935038 -10.851896)
		(end 94.009718 -8.926576)
		(width 0.127)
		(layer "In2.Cu")
		(net "SYS_PWR_LED")
	)
	(segment
		(start 86.8172 -93.84157)
		(end 86.25332 -94.40545)
		(width 0.127)
		(layer "In2.Cu")
		(net "SYS_PWR_LED")
	)
	(segment
		(start 85.725 -53.686202)
		(end 86.8172 -54.778402)
		(width 0.127)
		(layer "In2.Cu")
		(net "SYS_PWR_LED")
	)
	(segment
		(start 136.852406 -31.227268)
		(end 130.847592 -25.222454)
		(width 0.127)
		(layer "In2.Cu")
		(net "SYS_PWR_LED")
	)
	(segment
		(start 85.3694 -115.600988)
		(end 86.1695 -116.401088)
		(width 0.127)
		(layer "In2.Cu")
		(net "SYS_PWR_LED")
	)
	(segment
		(start 81.4705 -127.461772)
		(end 81.4705 -129.039112)
		(width 0.127)
		(layer "In2.Cu")
		(net "SYS_PWR_LED")
	)
	(segment
		(start 82.944208 -32.224218)
		(end 85.725 -35.00501)
		(width 0.127)
		(layer "In2.Cu")
		(net "SYS_PWR_LED")
	)
	(segment
		(start 85.8647 -113.334546)
		(end 85.3694 -113.829846)
		(width 0.127)
		(layer "In2.Cu")
		(net "SYS_PWR_LED")
	)
	(segment
		(start 85.3694 -113.829846)
		(end 85.3694 -115.600988)
		(width 0.127)
		(layer "In2.Cu")
		(net "SYS_PWR_LED")
	)
	(segment
		(start 98.552508 -16.707104)
		(end 95.935038 -14.089634)
		(width 0.127)
		(layer "In2.Cu")
		(net "SYS_PWR_LED")
	)
	(segment
		(start 86.0044 -98.328988)
		(end 86.0044 -99.468432)
		(width 0.127)
		(layer "In2.Cu")
		(net "SYS_PWR_LED")
	)
	(segment
		(start 86.1695 -116.401088)
		(end 86.1695 -122.762772)
		(width 0.127)
		(layer "In2.Cu")
		(net "SYS_PWR_LED")
	)
	(segment
		(start 125.998986 -25.222454)
		(end 120.080532 -19.304)
		(width 0.127)
		(layer "In2.Cu")
		(net "SYS_PWR_LED")
	)
	(segment
		(start 88.1253 -101.589332)
		(end 88.1253 -108.405168)
		(width 0.127)
		(layer "In2.Cu")
		(net "SYS_PWR_LED")
	)
	(segment
		(start 83.71586 -137.068814)
		(end 83.71586 -137.331704)
		(width 0.127)
		(layer "In2.Cu")
		(net "SYS_PWR_LED")
	)
	(segment
		(start 83.71586 -137.331704)
		(end 84.213954 -137.829798)
		(width 0.127)
		(layer "In2.Cu")
		(net "SYS_PWR_LED")
	)
	(segment
		(start 81.4705 -129.039112)
		(end 82.5754 -130.144012)
		(width 0.127)
		(layer "In2.Cu")
		(net "SYS_PWR_LED")
	)
	(segment
		(start 82.944208 -10.486136)
		(end 82.944208 -32.224218)
		(width 0.127)
		(layer "In2.Cu")
		(net "SYS_PWR_LED")
	)
	(segment
		(start 86.25332 -94.40545)
		(end 86.25332 -98.080068)
		(width 0.127)
		(layer "In2.Cu")
		(net "SYS_PWR_LED")
	)
	(segment
		(start 118.22176 -19.304)
		(end 115.624864 -16.707104)
		(width 0.127)
		(layer "In2.Cu")
		(net "SYS_PWR_LED")
	)
	(segment
		(start 86.25332 -98.080068)
		(end 86.0044 -98.328988)
		(width 0.127)
		(layer "In2.Cu")
		(net "SYS_PWR_LED")
	)
	(segment
		(start 120.080532 -19.304)
		(end 118.22176 -19.304)
		(width 0.127)
		(layer "In2.Cu")
		(net "SYS_PWR_LED")
	)
	(segment
		(start 82.5754 -133.877812)
		(end 82.918554 -134.220966)
		(width 0.127)
		(layer "In2.Cu")
		(net "SYS_PWR_LED")
	)
	(segment
		(start 84.503768 -8.926576)
		(end 82.944208 -10.486136)
		(width 0.127)
		(layer "In2.Cu")
		(net "SYS_PWR_LED")
	)
	(segment
		(start 85.8647 -110.665768)
		(end 85.8647 -113.334546)
		(width 0.127)
		(layer "In2.Cu")
		(net "SYS_PWR_LED")
	)
	(segment
		(start 82.5754 -130.144012)
		(end 82.5754 -133.877812)
		(width 0.127)
		(layer "In2.Cu")
		(net "SYS_PWR_LED")
	)
	(segment
		(start 82.918554 -136.271508)
		(end 83.71586 -137.068814)
		(width 0.127)
		(layer "In2.Cu")
		(net "SYS_PWR_LED")
	)
	(segment
		(start 84.225638 -137.829798)
		(end 84.505292 -138.109452)
		(width 0.127)
		(layer "In2.Cu")
		(net "SYS_PWR_LED")
	)
	(segment
		(start 84.213954 -137.829798)
		(end 84.225638 -137.829798)
		(width 0.127)
		(layer "In2.Cu")
		(net "SYS_PWR_LED")
	)
	(segment
		(start 86.8172 -54.778402)
		(end 86.8172 -93.84157)
		(width 0.127)
		(layer "In2.Cu")
		(net "SYS_PWR_LED")
	)
	(segment
		(start 66.6369 -140.2207)
		(end 67.3354 -140.9192)
		(width 0.127)
		(layer "In5.Cu")
		(net "SYS_PWR_LED")
	)
	(segment
		(start 54.493414 -142.449804)
		(end 54.749192 -142.194026)
		(width 0.127)
		(layer "In5.Cu")
		(net "SYS_PWR_LED")
	)
	(segment
		(start 77.5208 -139.1158)
		(end 77.5208 -138.481054)
		(width 0.127)
		(layer "In5.Cu")
		(net "SYS_PWR_LED")
	)
	(segment
		(start 62.84087 -140.8176)
		(end 63.43777 -140.2207)
		(width 0.127)
		(layer "In5.Cu")
		(net "SYS_PWR_LED")
	)
	(segment
		(start 66.478912 -140.182346)
		(end 66.517266 -140.2207)
		(width 0.127)
		(layer "In5.Cu")
		(net "SYS_PWR_LED")
	)
	(segment
		(start 67.3354 -140.9192)
		(end 75.21956 -140.9192)
		(width 0.127)
		(layer "In5.Cu")
		(net "SYS_PWR_LED")
	)
	(segment
		(start 56.45912 -142.194026)
		(end 57.474612 -141.178534)
		(width 0.127)
		(layer "In5.Cu")
		(net "SYS_PWR_LED")
	)
	(segment
		(start 84.057744 -138.557)
		(end 84.505292 -138.109452)
		(width 0.127)
		(layer "In5.Cu")
		(net "SYS_PWR_LED")
	)
	(segment
		(start 76.6318 -139.50696)
		(end 77.12964 -139.50696)
		(width 0.127)
		(layer "In5.Cu")
		(net "SYS_PWR_LED")
	)
	(segment
		(start 66.058288 -140.182346)
		(end 66.478912 -140.182346)
		(width 0.127)
		(layer "In5.Cu")
		(net "SYS_PWR_LED")
	)
	(segment
		(start 63.43777 -140.2207)
		(end 66.019934 -140.2207)
		(width 0.127)
		(layer "In5.Cu")
		(net "SYS_PWR_LED")
	)
	(segment
		(start 53.299868 -143.400018)
		(end 53.706268 -142.993618)
		(width 0.127)
		(layer "In5.Cu")
		(net "SYS_PWR_LED")
	)
	(segment
		(start 77.5208 -138.481054)
		(end 77.724254 -138.2776)
		(width 0.127)
		(layer "In5.Cu")
		(net "SYS_PWR_LED")
	)
	(segment
		(start 77.12964 -139.50696)
		(end 77.5208 -139.1158)
		(width 0.127)
		(layer "In5.Cu")
		(net "SYS_PWR_LED")
	)
	(segment
		(start 75.21956 -140.9192)
		(end 76.6318 -139.50696)
		(width 0.127)
		(layer "In5.Cu")
		(net "SYS_PWR_LED")
	)
	(segment
		(start 53.936392 -142.994126)
		(end 54.263036 -142.994126)
		(width 0.127)
		(layer "In5.Cu")
		(net "SYS_PWR_LED")
	)
	(segment
		(start 54.493414 -142.763748)
		(end 54.493414 -142.449804)
		(width 0.127)
		(layer "In5.Cu")
		(net "SYS_PWR_LED")
	)
	(segment
		(start 78.867 -138.2776)
		(end 79.1464 -138.557)
		(width 0.127)
		(layer "In5.Cu")
		(net "SYS_PWR_LED")
	)
	(segment
		(start 59.405266 -141.178534)
		(end 59.7662 -140.8176)
		(width 0.127)
		(layer "In5.Cu")
		(net "SYS_PWR_LED")
	)
	(segment
		(start 54.749192 -142.194026)
		(end 56.45912 -142.194026)
		(width 0.127)
		(layer "In5.Cu")
		(net "SYS_PWR_LED")
	)
	(segment
		(start 66.517266 -140.2207)
		(end 66.6369 -140.2207)
		(width 0.127)
		(layer "In5.Cu")
		(net "SYS_PWR_LED")
	)
	(segment
		(start 66.019934 -140.2207)
		(end 66.058288 -140.182346)
		(width 0.127)
		(layer "In5.Cu")
		(net "SYS_PWR_LED")
	)
	(segment
		(start 53.706268 -142.993618)
		(end 53.935884 -142.993618)
		(width 0.127)
		(layer "In5.Cu")
		(net "SYS_PWR_LED")
	)
	(segment
		(start 77.724254 -138.2776)
		(end 78.867 -138.2776)
		(width 0.127)
		(layer "In5.Cu")
		(net "SYS_PWR_LED")
	)
	(segment
		(start 54.263036 -142.994126)
		(end 54.493414 -142.763748)
		(width 0.127)
		(layer "In5.Cu")
		(net "SYS_PWR_LED")
	)
	(segment
		(start 59.7662 -140.8176)
		(end 62.84087 -140.8176)
		(width 0.127)
		(layer "In5.Cu")
		(net "SYS_PWR_LED")
	)
	(segment
		(start 53.935884 -142.993618)
		(end 53.936392 -142.994126)
		(width 0.127)
		(layer "In5.Cu")
		(net "SYS_PWR_LED")
	)
	(segment
		(start 57.474612 -141.178534)
		(end 59.405266 -141.178534)
		(width 0.127)
		(layer "In5.Cu")
		(net "SYS_PWR_LED")
	)
	(segment
		(start 79.1464 -138.557)
		(end 84.057744 -138.557)
		(width 0.127)
		(layer "In5.Cu")
		(net "SYS_PWR_LED")
	)
	(segment
		(start 52.899818 -138.999976)
		(end 53.299868 -138.599926)
		(width 0.127)
		(layer "F.Cu")
		(net "SLOTID_1")
	)
	(via
		(at 96.0628 -121.0564)
		(size 0.508)
		(drill 0.254)
		(layers "F.Cu" "B.Cu")
		(net "SLOTID_1")
	)
	(via
		(at 54.5846 -124.46)
		(size 0.508)
		(drill 0.254)
		(layers "F.Cu" "B.Cu")
		(net "SLOTID_1")
	)
	(via
		(at 53.299868 -138.599926)
		(size 0.4572)
		(drill 0.2032)
		(layers "F.Cu" "B.Cu")
		(net "SLOTID_1")
	)
	(segment
		(start 53.690012 -136.106154)
		(end 53.690012 -136.6774)
		(width 0.127)
		(layer "B.Cu")
		(net "SLOTID_1")
	)
	(segment
		(start 53.740812 -136.055354)
		(end 53.690012 -136.106154)
		(width 0.127)
		(layer "B.Cu")
		(net "SLOTID_1")
	)
	(segment
		(start 53.7718 -136.759188)
		(end 53.7718 -137.4902)
		(width 0.127)
		(layer "B.Cu")
		(net "SLOTID_1")
	)
	(segment
		(start 53.7718 -137.4902)
		(end 53.299868 -137.962132)
		(width 0.127)
		(layer "B.Cu")
		(net "SLOTID_1")
	)
	(segment
		(start 53.299868 -137.962132)
		(end 53.299868 -138.599926)
		(width 0.127)
		(layer "B.Cu")
		(net "SLOTID_1")
	)
	(segment
		(start 54.723792 -136.055354)
		(end 53.740812 -136.055354)
		(width 0.127)
		(layer "B.Cu")
		(net "SLOTID_1")
	)
	(segment
		(start 53.690012 -136.6774)
		(end 53.7718 -136.759188)
		(width 0.127)
		(layer "B.Cu")
		(net "SLOTID_1")
	)
	(segment
		(start 96.266 -64.9986)
		(end 96.266 -37.144198)
		(width 0.127)
		(layer "In2.Cu")
		(net "SLOTID_1")
	)
	(segment
		(start 118.852442 -44.44746)
		(end 117.899942 -45.39996)
		(width 0.127)
		(layer "In2.Cu")
		(net "SLOTID_1")
	)
	(segment
		(start 96.8502 -114.685826)
		(end 96.8502 -89.880694)
		(width 0.127)
		(layer "In2.Cu")
		(net "SLOTID_1")
	)
	(segment
		(start 95.7326 -65.532)
		(end 96.266 -64.9986)
		(width 0.127)
		(layer "In2.Cu")
		(net "SLOTID_1")
	)
	(segment
		(start 95.7326 -88.763094)
		(end 95.7326 -84.9884)
		(width 0.127)
		(layer "In2.Cu")
		(net "SLOTID_1")
	)
	(segment
		(start 98.6028 -34.807398)
		(end 98.6028 -30.088078)
		(width 0.127)
		(layer "In2.Cu")
		(net "SLOTID_1")
	)
	(segment
		(start 95.7326 -82.251804)
		(end 95.7326 -65.532)
		(width 0.127)
		(layer "In2.Cu")
		(net "SLOTID_1")
	)
	(segment
		(start 96.341692 -84.379308)
		(end 96.341692 -82.860896)
		(width 0.127)
		(layer "In2.Cu")
		(net "SLOTID_1")
	)
	(segment
		(start 54.5846 -124.46)
		(end 54.2417 -124.8029)
		(width 0.127)
		(layer "In2.Cu")
		(net "SLOTID_1")
	)
	(segment
		(start 104.458262 -24.232616)
		(end 113.959132 -24.232616)
		(width 0.127)
		(layer "In2.Cu")
		(net "SLOTID_1")
	)
	(segment
		(start 54.2417 -124.8029)
		(end 54.2417 -131.171442)
		(width 0.127)
		(layer "In2.Cu")
		(net "SLOTID_1")
	)
	(segment
		(start 53.299868 -135.771128)
		(end 53.299868 -138.599926)
		(width 0.127)
		(layer "In2.Cu")
		(net "SLOTID_1")
	)
	(segment
		(start 53.467 -135.603996)
		(end 53.299868 -135.771128)
		(width 0.127)
		(layer "In2.Cu")
		(net "SLOTID_1")
	)
	(segment
		(start 113.959132 -24.232616)
		(end 118.852442 -29.125926)
		(width 0.127)
		(layer "In2.Cu")
		(net "SLOTID_1")
	)
	(segment
		(start 96.266 -37.144198)
		(end 98.6028 -34.807398)
		(width 0.127)
		(layer "In2.Cu")
		(net "SLOTID_1")
	)
	(segment
		(start 53.467 -131.946142)
		(end 53.467 -135.603996)
		(width 0.127)
		(layer "In2.Cu")
		(net "SLOTID_1")
	)
	(segment
		(start 95.866204 -120.859804)
		(end 95.866204 -115.669822)
		(width 0.127)
		(layer "In2.Cu")
		(net "SLOTID_1")
	)
	(segment
		(start 96.0628 -121.0564)
		(end 95.866204 -120.859804)
		(width 0.127)
		(layer "In2.Cu")
		(net "SLOTID_1")
	)
	(segment
		(start 95.866204 -115.669822)
		(end 96.8502 -114.685826)
		(width 0.127)
		(layer "In2.Cu")
		(net "SLOTID_1")
	)
	(segment
		(start 98.6028 -30.088078)
		(end 104.458262 -24.232616)
		(width 0.127)
		(layer "In2.Cu")
		(net "SLOTID_1")
	)
	(segment
		(start 96.341692 -82.860896)
		(end 95.7326 -82.251804)
		(width 0.127)
		(layer "In2.Cu")
		(net "SLOTID_1")
	)
	(segment
		(start 118.852442 -29.125926)
		(end 118.852442 -44.44746)
		(width 0.127)
		(layer "In2.Cu")
		(net "SLOTID_1")
	)
	(segment
		(start 95.7326 -84.9884)
		(end 96.341692 -84.379308)
		(width 0.127)
		(layer "In2.Cu")
		(net "SLOTID_1")
	)
	(segment
		(start 54.2417 -131.171442)
		(end 53.467 -131.946142)
		(width 0.127)
		(layer "In2.Cu")
		(net "SLOTID_1")
	)
	(segment
		(start 96.8502 -89.880694)
		(end 95.7326 -88.763094)
		(width 0.127)
		(layer "In2.Cu")
		(net "SLOTID_1")
	)
	(segment
		(start 67.175888 -123.5583)
		(end 58.937144 -123.5583)
		(width 0.127)
		(layer "In5.Cu")
		(net "SLOTID_1")
	)
	(segment
		(start 84.748624 -124.2568)
		(end 82.615024 -126.3904)
		(width 0.127)
		(layer "In5.Cu")
		(net "SLOTID_1")
	)
	(segment
		(start 85.611716 -124.2568)
		(end 84.748624 -124.2568)
		(width 0.127)
		(layer "In5.Cu")
		(net "SLOTID_1")
	)
	(segment
		(start 67.848988 -122.8852)
		(end 67.175888 -123.5583)
		(width 0.127)
		(layer "In5.Cu")
		(net "SLOTID_1")
	)
	(segment
		(start 69.4944 -122.8852)
		(end 67.848988 -122.8852)
		(width 0.127)
		(layer "In5.Cu")
		(net "SLOTID_1")
	)
	(segment
		(start 95.966788 -121.152412)
		(end 88.716104 -121.152412)
		(width 0.127)
		(layer "In5.Cu")
		(net "SLOTID_1")
	)
	(segment
		(start 82.615024 -126.3904)
		(end 77.316838 -126.3904)
		(width 0.127)
		(layer "In5.Cu")
		(net "SLOTID_1")
	)
	(segment
		(start 70.1675 -123.5583)
		(end 69.4944 -122.8852)
		(width 0.127)
		(layer "In5.Cu")
		(net "SLOTID_1")
	)
	(segment
		(start 54.9783 -124.0663)
		(end 54.5846 -124.46)
		(width 0.127)
		(layer "In5.Cu")
		(net "SLOTID_1")
	)
	(segment
		(start 77.316838 -126.3904)
		(end 74.484738 -123.5583)
		(width 0.127)
		(layer "In5.Cu")
		(net "SLOTID_1")
	)
	(segment
		(start 58.937144 -123.5583)
		(end 58.429144 -124.0663)
		(width 0.127)
		(layer "In5.Cu")
		(net "SLOTID_1")
	)
	(segment
		(start 74.484738 -123.5583)
		(end 70.1675 -123.5583)
		(width 0.127)
		(layer "In5.Cu")
		(net "SLOTID_1")
	)
	(segment
		(start 88.716104 -121.152412)
		(end 85.611716 -124.2568)
		(width 0.127)
		(layer "In5.Cu")
		(net "SLOTID_1")
	)
	(segment
		(start 96.0628 -121.0564)
		(end 95.966788 -121.152412)
		(width 0.127)
		(layer "In5.Cu")
		(net "SLOTID_1")
	)
	(segment
		(start 58.429144 -124.0663)
		(end 54.9783 -124.0663)
		(width 0.127)
		(layer "In5.Cu")
		(net "SLOTID_1")
	)
	(segment
		(start 58.529474 -137.228326)
		(end 57.91581 -137.228326)
		(width 0.127)
		(layer "F.Cu")
		(net "SLOTID_0")
	)
	(segment
		(start 56.14416 -138.999976)
		(end 56.099964 -138.999976)
		(width 0.127)
		(layer "F.Cu")
		(net "SLOTID_0")
	)
	(segment
		(start 59.448192 -136.309608)
		(end 58.8772 -136.8806)
		(width 0.127)
		(layer "F.Cu")
		(net "SLOTID_0")
	)
	(segment
		(start 57.91581 -137.228326)
		(end 56.14416 -138.999976)
		(width 0.127)
		(layer "F.Cu")
		(net "SLOTID_0")
	)
	(segment
		(start 62.326012 -136.31164)
		(end 62.326012 -135.623554)
		(width 0.127)
		(layer "F.Cu")
		(net "SLOTID_0")
	)
	(segment
		(start 58.8772 -136.8806)
		(end 58.529474 -137.228326)
		(width 0.127)
		(layer "F.Cu")
		(net "SLOTID_0")
	)
	(segment
		(start 60.661042 -136.309608)
		(end 59.448192 -136.309608)
		(width 0.127)
		(layer "F.Cu")
		(net "SLOTID_0")
	)
	(segment
		(start 61.293502 -136.942068)
		(end 60.661042 -136.309608)
		(width 0.127)
		(layer "F.Cu")
		(net "SLOTID_0")
	)
	(segment
		(start 62.326012 -135.623554)
		(end 62.613032 -135.336534)
		(width 0.127)
		(layer "F.Cu")
		(net "SLOTID_0")
	)
	(segment
		(start 61.695584 -136.942068)
		(end 62.326012 -136.31164)
		(width 0.127)
		(layer "F.Cu")
		(net "SLOTID_0")
	)
	(segment
		(start 61.293502 -136.942068)
		(end 61.695584 -136.942068)
		(width 0.127)
		(layer "F.Cu")
		(net "SLOTID_0")
	)
	(via
		(at 58.8772 -136.8806)
		(size 0.6604)
		(drill 0.3302)
		(layers "F.Cu" "B.Cu")
		(net "SLOTID_0")
	)
	(via
		(at 62.613032 -135.336534)
		(size 0.508)
		(drill 0.254)
		(layers "F.Cu" "B.Cu")
		(net "SLOTID_0")
	)
	(via
		(at 98.4758 -131.4958)
		(size 0.508)
		(drill 0.254)
		(layers "F.Cu" "B.Cu")
		(net "SLOTID_0")
	)
	(segment
		(start 118.471442 -43.428666)
		(end 118.471442 -29.283914)
		(width 0.127)
		(layer "In2.Cu")
		(net "SLOTID_0")
	)
	(segment
		(start 96.154494 -85.105494)
		(end 96.154494 -88.646)
		(width 0.127)
		(layer "In2.Cu")
		(net "SLOTID_0")
	)
	(segment
		(start 99.11207 -30.117796)
		(end 99.11207 -34.837116)
		(width 0.127)
		(layer "In2.Cu")
		(net "SLOTID_0")
	)
	(segment
		(start 96.722692 -82.702908)
		(end 96.722692 -84.537296)
		(width 0.127)
		(layer "In2.Cu")
		(net "SLOTID_0")
	)
	(segment
		(start 98.365818 -131.227322)
		(end 98.4758 -131.337304)
		(width 0.127)
		(layer "In2.Cu")
		(net "SLOTID_0")
	)
	(segment
		(start 97.282 -89.773506)
		(end 97.282 -116.923566)
		(width 0.127)
		(layer "In2.Cu")
		(net "SLOTID_0")
	)
	(segment
		(start 96.647 -37.302186)
		(end 96.647 -65.4812)
		(width 0.127)
		(layer "In2.Cu")
		(net "SLOTID_0")
	)
	(segment
		(start 98.4758 -131.337304)
		(end 98.4758 -131.4958)
		(width 0.127)
		(layer "In2.Cu")
		(net "SLOTID_0")
	)
	(segment
		(start 104.61625 -24.613616)
		(end 99.11207 -30.117796)
		(width 0.127)
		(layer "In2.Cu")
		(net "SLOTID_0")
	)
	(segment
		(start 98.365818 -125.557788)
		(end 98.365818 -131.227322)
		(width 0.127)
		(layer "In2.Cu")
		(net "SLOTID_0")
	)
	(segment
		(start 97.8662 -117.507766)
		(end 97.8662 -125.05817)
		(width 0.127)
		(layer "In2.Cu")
		(net "SLOTID_0")
	)
	(segment
		(start 96.722692 -84.537296)
		(end 96.154494 -85.105494)
		(width 0.127)
		(layer "In2.Cu")
		(net "SLOTID_0")
	)
	(segment
		(start 97.282 -116.923566)
		(end 97.8662 -117.507766)
		(width 0.127)
		(layer "In2.Cu")
		(net "SLOTID_0")
	)
	(segment
		(start 118.471442 -29.283914)
		(end 113.801144 -24.613616)
		(width 0.127)
		(layer "In2.Cu")
		(net "SLOTID_0")
	)
	(segment
		(start 117.899942 -44.000166)
		(end 118.471442 -43.428666)
		(width 0.127)
		(layer "In2.Cu")
		(net "SLOTID_0")
	)
	(segment
		(start 96.154494 -82.13471)
		(end 96.722692 -82.702908)
		(width 0.127)
		(layer "In2.Cu")
		(net "SLOTID_0")
	)
	(segment
		(start 113.801144 -24.613616)
		(end 104.61625 -24.613616)
		(width 0.127)
		(layer "In2.Cu")
		(net "SLOTID_0")
	)
	(segment
		(start 96.154494 -88.646)
		(end 97.282 -89.773506)
		(width 0.127)
		(layer "In2.Cu")
		(net "SLOTID_0")
	)
	(segment
		(start 97.8662 -125.05817)
		(end 98.365818 -125.557788)
		(width 0.127)
		(layer "In2.Cu")
		(net "SLOTID_0")
	)
	(segment
		(start 96.647 -65.4812)
		(end 96.154494 -65.973706)
		(width 0.127)
		(layer "In2.Cu")
		(net "SLOTID_0")
	)
	(segment
		(start 96.154494 -65.973706)
		(end 96.154494 -82.13471)
		(width 0.127)
		(layer "In2.Cu")
		(net "SLOTID_0")
	)
	(segment
		(start 99.11207 -34.837116)
		(end 96.647 -37.302186)
		(width 0.127)
		(layer "In2.Cu")
		(net "SLOTID_0")
	)
	(segment
		(start 86.312756 -134.598156)
		(end 95.487744 -134.598156)
		(width 0.127)
		(layer "In5.Cu")
		(net "SLOTID_0")
	)
	(segment
		(start 82.591656 -135.4074)
		(end 83.40471 -134.594346)
		(width 0.127)
		(layer "In5.Cu")
		(net "SLOTID_0")
	)
	(segment
		(start 83.76031 -134.239)
		(end 85.9536 -134.239)
		(width 0.127)
		(layer "In5.Cu")
		(net "SLOTID_0")
	)
	(segment
		(start 71.111618 -135.4963)
		(end 71.200518 -135.4074)
		(width 0.127)
		(layer "In5.Cu")
		(net "SLOTID_0")
	)
	(segment
		(start 65.374266 -135.336534)
		(end 66.1797 -134.5311)
		(width 0.127)
		(layer "In5.Cu")
		(net "SLOTID_0")
	)
	(segment
		(start 85.9536 -134.239)
		(end 86.312756 -134.598156)
		(width 0.127)
		(layer "In5.Cu")
		(net "SLOTID_0")
	)
	(segment
		(start 98.4758 -131.6101)
		(end 98.4758 -131.4958)
		(width 0.127)
		(layer "In5.Cu")
		(net "SLOTID_0")
	)
	(segment
		(start 62.613032 -135.336534)
		(end 65.374266 -135.336534)
		(width 0.127)
		(layer "In5.Cu")
		(net "SLOTID_0")
	)
	(segment
		(start 71.200518 -135.4074)
		(end 82.591656 -135.4074)
		(width 0.127)
		(layer "In5.Cu")
		(net "SLOTID_0")
	)
	(segment
		(start 69.4563 -134.5311)
		(end 70.4215 -135.4963)
		(width 0.127)
		(layer "In5.Cu")
		(net "SLOTID_0")
	)
	(segment
		(start 70.4215 -135.4963)
		(end 71.111618 -135.4963)
		(width 0.127)
		(layer "In5.Cu")
		(net "SLOTID_0")
	)
	(segment
		(start 66.1797 -134.5311)
		(end 69.4563 -134.5311)
		(width 0.127)
		(layer "In5.Cu")
		(net "SLOTID_0")
	)
	(segment
		(start 95.487744 -134.598156)
		(end 98.4758 -131.6101)
		(width 0.127)
		(layer "In5.Cu")
		(net "SLOTID_0")
	)
	(segment
		(start 83.40471 -134.594346)
		(end 83.404964 -134.594346)
		(width 0.127)
		(layer "In5.Cu")
		(net "SLOTID_0")
	)
	(segment
		(start 83.404964 -134.594346)
		(end 83.76031 -134.239)
		(width 0.127)
		(layer "In5.Cu")
		(net "SLOTID_0")
	)
	(segment
		(start 61.6966 -133.2738)
		(end 61.9633 -133.0071)
		(width 0.127)
		(layer "F.Cu")
		(net "SCC_STBY_PWR_EN")
	)
	(segment
		(start 61.9633 -131.014978)
		(end 61.087 -130.138678)
		(width 0.127)
		(layer "F.Cu")
		(net "SCC_STBY_PWR_EN")
	)
	(segment
		(start 61.9633 -133.0071)
		(end 61.9633 -132.8166)
		(width 0.127)
		(layer "F.Cu")
		(net "SCC_STBY_PWR_EN")
	)
	(segment
		(start 60.0456 -128.0668)
		(end 60.0456 -127.5461)
		(width 0.127)
		(layer "F.Cu")
		(net "SCC_STBY_PWR_EN")
	)
	(segment
		(start 61.087 -129.1082)
		(end 60.0456 -128.0668)
		(width 0.127)
		(layer "F.Cu")
		(net "SCC_STBY_PWR_EN")
	)
	(segment
		(start 60.746386 -133.2738)
		(end 61.6966 -133.2738)
		(width 0.127)
		(layer "F.Cu")
		(net "SCC_STBY_PWR_EN")
	)
	(segment
		(start 61.9633 -132.8166)
		(end 61.9633 -131.014978)
		(width 0.127)
		(layer "F.Cu")
		(net "SCC_STBY_PWR_EN")
	)
	(segment
		(start 61.087 -130.138678)
		(end 61.087 -129.1082)
		(width 0.127)
		(layer "F.Cu")
		(net "SCC_STBY_PWR_EN")
	)
	(via
		(at 61.9633 -132.8166)
		(size 0.6604)
		(drill 0.3302)
		(layers "F.Cu" "B.Cu")
		(net "SCC_STBY_PWR_EN")
	)
	(via
		(at 85.09 -126.238)
		(size 0.508)
		(drill 0.254)
		(layers "F.Cu" "B.Cu")
		(net "SCC_STBY_PWR_EN")
	)
	(via
		(at 60.0456 -127.5461)
		(size 0.508)
		(drill 0.254)
		(layers "F.Cu" "B.Cu")
		(net "SCC_STBY_PWR_EN")
	)
	(segment
		(start 60.0456 -128.143)
		(end 59.8424 -128.3462)
		(width 0.127)
		(layer "B.Cu")
		(net "SCC_STBY_PWR_EN")
	)
	(segment
		(start 60.0456 -127.5461)
		(end 60.0456 -128.143)
		(width 0.127)
		(layer "B.Cu")
		(net "SCC_STBY_PWR_EN")
	)
	(segment
		(start 59.8424 -128.3462)
		(end 59.2201 -128.3462)
		(width 0.127)
		(layer "B.Cu")
		(net "SCC_STBY_PWR_EN")
	)
	(segment
		(start 84.661756 -9.307576)
		(end 83.325208 -10.644124)
		(width 0.127)
		(layer "In2.Cu")
		(net "SCC_STBY_PWR_EN")
	)
	(segment
		(start 86.106 -53.528214)
		(end 87.1982 -54.620414)
		(width 0.127)
		(layer "In2.Cu")
		(net "SCC_STBY_PWR_EN")
	)
	(segment
		(start 86.63432 -94.563438)
		(end 86.63432 -97.906332)
		(width 0.127)
		(layer "In2.Cu")
		(net "SCC_STBY_PWR_EN")
	)
	(segment
		(start 87.1474 -98.419412)
		(end 87.1474 -100.072444)
		(width 0.127)
		(layer "In2.Cu")
		(net "SCC_STBY_PWR_EN")
	)
	(segment
		(start 93.85173 -9.307576)
		(end 84.661756 -9.307576)
		(width 0.127)
		(layer "In2.Cu")
		(net "SCC_STBY_PWR_EN")
	)
	(segment
		(start 125.841252 -25.603708)
		(end 119.922544 -19.685)
		(width 0.127)
		(layer "In2.Cu")
		(net "SCC_STBY_PWR_EN")
	)
	(segment
		(start 83.325208 -10.644124)
		(end 83.325208 -32.06623)
		(width 0.127)
		(layer "In2.Cu")
		(net "SCC_STBY_PWR_EN")
	)
	(segment
		(start 88.5063 -108.563156)
		(end 86.2457 -110.823756)
		(width 0.127)
		(layer "In2.Cu")
		(net "SCC_STBY_PWR_EN")
	)
	(segment
		(start 87.1982 -93.999558)
		(end 86.63432 -94.563438)
		(width 0.127)
		(layer "In2.Cu")
		(net "SCC_STBY_PWR_EN")
	)
	(segment
		(start 86.63432 -97.906332)
		(end 87.1474 -98.419412)
		(width 0.127)
		(layer "In2.Cu")
		(net "SCC_STBY_PWR_EN")
	)
	(segment
		(start 87.1982 -54.620414)
		(end 87.1982 -93.999558)
		(width 0.127)
		(layer "In2.Cu")
		(net "SCC_STBY_PWR_EN")
	)
	(segment
		(start 85.7504 -115.443)
		(end 86.5505 -116.2431)
		(width 0.127)
		(layer "In2.Cu")
		(net "SCC_STBY_PWR_EN")
	)
	(segment
		(start 136.471406 -39.82847)
		(end 136.471406 -31.385256)
		(width 0.127)
		(layer "In2.Cu")
		(net "SCC_STBY_PWR_EN")
	)
	(segment
		(start 86.5505 -122.937524)
		(end 85.0392 -124.448824)
		(width 0.127)
		(layer "In2.Cu")
		(net "SCC_STBY_PWR_EN")
	)
	(segment
		(start 95.554038 -14.247622)
		(end 95.554038 -11.009884)
		(width 0.127)
		(layer "In2.Cu")
		(net "SCC_STBY_PWR_EN")
	)
	(segment
		(start 85.0392 -126.1872)
		(end 85.09 -126.238)
		(width 0.127)
		(layer "In2.Cu")
		(net "SCC_STBY_PWR_EN")
	)
	(segment
		(start 88.5063 -101.431344)
		(end 88.5063 -108.563156)
		(width 0.127)
		(layer "In2.Cu")
		(net "SCC_STBY_PWR_EN")
	)
	(segment
		(start 119.922544 -19.685)
		(end 118.063772 -19.685)
		(width 0.127)
		(layer "In2.Cu")
		(net "SCC_STBY_PWR_EN")
	)
	(segment
		(start 95.554038 -11.009884)
		(end 93.85173 -9.307576)
		(width 0.127)
		(layer "In2.Cu")
		(net "SCC_STBY_PWR_EN")
	)
	(segment
		(start 87.1474 -100.072444)
		(end 88.5063 -101.431344)
		(width 0.127)
		(layer "In2.Cu")
		(net "SCC_STBY_PWR_EN")
	)
	(segment
		(start 86.2457 -110.823756)
		(end 86.2457 -113.492534)
		(width 0.127)
		(layer "In2.Cu")
		(net "SCC_STBY_PWR_EN")
	)
	(segment
		(start 126.156974 -25.603454)
		(end 126.15672 -25.603708)
		(width 0.127)
		(layer "In2.Cu")
		(net "SCC_STBY_PWR_EN")
	)
	(segment
		(start 135.899906 -40.39997)
		(end 136.471406 -39.82847)
		(width 0.127)
		(layer "In2.Cu")
		(net "SCC_STBY_PWR_EN")
	)
	(segment
		(start 136.471406 -31.385256)
		(end 130.689604 -25.603454)
		(width 0.127)
		(layer "In2.Cu")
		(net "SCC_STBY_PWR_EN")
	)
	(segment
		(start 85.0392 -124.448824)
		(end 85.0392 -126.1872)
		(width 0.127)
		(layer "In2.Cu")
		(net "SCC_STBY_PWR_EN")
	)
	(segment
		(start 130.689604 -25.603454)
		(end 126.156974 -25.603454)
		(width 0.127)
		(layer "In2.Cu")
		(net "SCC_STBY_PWR_EN")
	)
	(segment
		(start 118.063772 -19.685)
		(end 115.466876 -17.088104)
		(width 0.127)
		(layer "In2.Cu")
		(net "SCC_STBY_PWR_EN")
	)
	(segment
		(start 98.39452 -17.088104)
		(end 95.554038 -14.247622)
		(width 0.127)
		(layer "In2.Cu")
		(net "SCC_STBY_PWR_EN")
	)
	(segment
		(start 85.7504 -113.987834)
		(end 85.7504 -115.443)
		(width 0.127)
		(layer "In2.Cu")
		(net "SCC_STBY_PWR_EN")
	)
	(segment
		(start 86.5505 -116.2431)
		(end 86.5505 -122.937524)
		(width 0.127)
		(layer "In2.Cu")
		(net "SCC_STBY_PWR_EN")
	)
	(segment
		(start 83.325208 -32.06623)
		(end 86.106 -34.847022)
		(width 0.127)
		(layer "In2.Cu")
		(net "SCC_STBY_PWR_EN")
	)
	(segment
		(start 126.15672 -25.603708)
		(end 125.841252 -25.603708)
		(width 0.127)
		(layer "In2.Cu")
		(net "SCC_STBY_PWR_EN")
	)
	(segment
		(start 86.106 -34.847022)
		(end 86.106 -53.528214)
		(width 0.127)
		(layer "In2.Cu")
		(net "SCC_STBY_PWR_EN")
	)
	(segment
		(start 86.2457 -113.492534)
		(end 85.7504 -113.987834)
		(width 0.127)
		(layer "In2.Cu")
		(net "SCC_STBY_PWR_EN")
	)
	(segment
		(start 115.466876 -17.088104)
		(end 98.39452 -17.088104)
		(width 0.127)
		(layer "In2.Cu")
		(net "SCC_STBY_PWR_EN")
	)
	(segment
		(start 70.409308 -127.6858)
		(end 65.278 -127.6858)
		(width 0.127)
		(layer "In5.Cu")
		(net "SCC_STBY_PWR_EN")
	)
	(segment
		(start 85.09 -126.238)
		(end 83.4136 -127.9144)
		(width 0.127)
		(layer "In5.Cu")
		(net "SCC_STBY_PWR_EN")
	)
	(segment
		(start 75.5396 -127.9144)
		(end 74.676 -127.0508)
		(width 0.127)
		(layer "In5.Cu")
		(net "SCC_STBY_PWR_EN")
	)
	(segment
		(start 65.278 -127.6858)
		(end 65.1383 -127.5461)
		(width 0.127)
		(layer "In5.Cu")
		(net "SCC_STBY_PWR_EN")
	)
	(segment
		(start 65.1383 -127.5461)
		(end 60.0456 -127.5461)
		(width 0.127)
		(layer "In5.Cu")
		(net "SCC_STBY_PWR_EN")
	)
	(segment
		(start 83.4136 -127.9144)
		(end 75.5396 -127.9144)
		(width 0.127)
		(layer "In5.Cu")
		(net "SCC_STBY_PWR_EN")
	)
	(segment
		(start 71.044308 -127.0508)
		(end 70.409308 -127.6858)
		(width 0.127)
		(layer "In5.Cu")
		(net "SCC_STBY_PWR_EN")
	)
	(segment
		(start 74.676 -127.0508)
		(end 71.044308 -127.0508)
		(width 0.127)
		(layer "In5.Cu")
		(net "SCC_STBY_PWR_EN")
	)
	(segment
		(start 50.899822 -139.400026)
		(end 50.500026 -139.799822)
		(width 0.127)
		(layer "F.Cu")
		(net "SCC_RMT_TYPE_0_R")
	)
	(segment
		(start 50.500026 -139.799822)
		(end 50.500026 -139.800076)
		(width 0.127)
		(layer "F.Cu")
		(net "SCC_RMT_TYPE_0_R")
	)
	(via
		(at 56.896 -136.93902)
		(size 0.6096)
		(drill 0.3048)
		(layers "F.Cu" "B.Cu")
		(net "SCC_RMT_TYPE_0_R")
	)
	(via
		(at 50.899822 -139.400026)
		(size 0.4572)
		(drill 0.2032)
		(layers "F.Cu" "B.Cu")
		(net "SCC_RMT_TYPE_0_R")
	)
	(segment
		(start 53.693568 -138.763248)
		(end 53.462682 -138.994134)
		(width 0.127)
		(layer "B.Cu")
		(net "SCC_RMT_TYPE_0_R")
	)
	(segment
		(start 54.263036 -138.193526)
		(end 53.949346 -138.193526)
		(width 0.127)
		(layer "B.Cu")
		(net "SCC_RMT_TYPE_0_R")
	)
	(segment
		(start 51.305714 -138.994134)
		(end 50.899822 -139.400026)
		(width 0.127)
		(layer "B.Cu")
		(net "SCC_RMT_TYPE_0_R")
	)
	(segment
		(start 56.67502 -137.16)
		(end 54.982618 -137.16)
		(width 0.127)
		(layer "B.Cu")
		(net "SCC_RMT_TYPE_0_R")
	)
	(segment
		(start 53.949346 -138.193526)
		(end 53.693568 -138.449304)
		(width 0.127)
		(layer "B.Cu")
		(net "SCC_RMT_TYPE_0_R")
	)
	(segment
		(start 57.481978 -135.777224)
		(end 57.481978 -136.353042)
		(width 0.127)
		(layer "B.Cu")
		(net "SCC_RMT_TYPE_0_R")
	)
	(segment
		(start 54.493414 -137.963148)
		(end 54.263036 -138.193526)
		(width 0.127)
		(layer "B.Cu")
		(net "SCC_RMT_TYPE_0_R")
	)
	(segment
		(start 57.481978 -136.353042)
		(end 56.896 -136.93902)
		(width 0.127)
		(layer "B.Cu")
		(net "SCC_RMT_TYPE_0_R")
	)
	(segment
		(start 54.982618 -137.16)
		(end 54.493414 -137.649204)
		(width 0.127)
		(layer "B.Cu")
		(net "SCC_RMT_TYPE_0_R")
	)
	(segment
		(start 56.896 -136.93902)
		(end 56.67502 -137.16)
		(width 0.127)
		(layer "B.Cu")
		(net "SCC_RMT_TYPE_0_R")
	)
	(segment
		(start 53.693568 -138.449304)
		(end 53.693568 -138.763248)
		(width 0.127)
		(layer "B.Cu")
		(net "SCC_RMT_TYPE_0_R")
	)
	(segment
		(start 54.493414 -137.649204)
		(end 54.493414 -137.963148)
		(width 0.127)
		(layer "B.Cu")
		(net "SCC_RMT_TYPE_0_R")
	)
	(segment
		(start 53.462682 -138.994134)
		(end 51.305714 -138.994134)
		(width 0.127)
		(layer "B.Cu")
		(net "SCC_RMT_TYPE_0_R")
	)
	(segment
		(start 113.6142 -39.71417)
		(end 114.3 -40.39997)
		(width 0.127)
		(layer "F.Cu")
		(net "SCC_RMT_TYPE_0")
	)
	(segment
		(start 114.044984 -29.887164)
		(end 113.6142 -30.317948)
		(width 0.127)
		(layer "F.Cu")
		(net "SCC_RMT_TYPE_0")
	)
	(segment
		(start 113.6142 -30.317948)
		(end 113.6142 -39.71417)
		(width 0.127)
		(layer "F.Cu")
		(net "SCC_RMT_TYPE_0")
	)
	(via
		(at 103.2256 -38.1762)
		(size 0.508)
		(drill 0.254)
		(layers "F.Cu" "B.Cu")
		(net "SCC_RMT_TYPE_0")
	)
	(via
		(at 56.8452 -135.0264)
		(size 0.508)
		(drill 0.254)
		(layers "F.Cu" "B.Cu")
		(net "SCC_RMT_TYPE_0")
	)
	(via
		(at 114.044984 -29.887164)
		(size 0.508)
		(drill 0.254)
		(layers "F.Cu" "B.Cu")
		(net "SCC_RMT_TYPE_0")
	)
	(via
		(at 58.370978 -134.6708)
		(size 0.6096)
		(drill 0.3048)
		(layers "F.Cu" "B.Cu")
		(net "SCC_RMT_TYPE_0")
	)
	(segment
		(start 57.2008 -134.6708)
		(end 56.8452 -135.0264)
		(width 0.127)
		(layer "B.Cu")
		(net "SCC_RMT_TYPE_0")
	)
	(segment
		(start 58.370978 -135.777224)
		(end 58.370978 -134.6708)
		(width 0.127)
		(layer "B.Cu")
		(net "SCC_RMT_TYPE_0")
	)
	(segment
		(start 58.370978 -134.6708)
		(end 57.2008 -134.6708)
		(width 0.127)
		(layer "B.Cu")
		(net "SCC_RMT_TYPE_0")
	)
	(segment
		(start 112.962436 -28.804616)
		(end 114.044984 -29.887164)
		(width 0.127)
		(layer "In2.Cu")
		(net "SCC_RMT_TYPE_0")
	)
	(segment
		(start 103.899462 -37.502338)
		(end 103.899462 -31.258256)
		(width 0.127)
		(layer "In2.Cu")
		(net "SCC_RMT_TYPE_0")
	)
	(segment
		(start 103.899462 -31.258256)
		(end 106.353102 -28.804616)
		(width 0.127)
		(layer "In2.Cu")
		(net "SCC_RMT_TYPE_0")
	)
	(segment
		(start 106.353102 -28.804616)
		(end 112.962436 -28.804616)
		(width 0.127)
		(layer "In2.Cu")
		(net "SCC_RMT_TYPE_0")
	)
	(segment
		(start 103.2256 -38.1762)
		(end 103.899462 -37.502338)
		(width 0.127)
		(layer "In2.Cu")
		(net "SCC_RMT_TYPE_0")
	)
	(segment
		(start 59.203844 -134.05993)
		(end 58.237374 -135.0264)
		(width 0.127)
		(layer "In5.Cu")
		(net "SCC_RMT_TYPE_0")
	)
	(segment
		(start 87.992712 -132.7785)
		(end 87.294212 -133.477)
		(width 0.127)
		(layer "In5.Cu")
		(net "SCC_RMT_TYPE_0")
	)
	(segment
		(start 101.23678 -43.51782)
		(end 101.23678 -56.887364)
		(width 0.127)
		(layer "In5.Cu")
		(net "SCC_RMT_TYPE_0")
	)
	(segment
		(start 64.96812 -133.919468)
		(end 59.450732 -133.919468)
		(width 0.127)
		(layer "In5.Cu")
		(net "SCC_RMT_TYPE_0")
	)
	(segment
		(start 97.866454 -116.722652)
		(end 98.161602 -117.0178)
		(width 0.127)
		(layer "In5.Cu")
		(net "SCC_RMT_TYPE_0")
	)
	(segment
		(start 59.31027 -134.05993)
		(end 59.203844 -134.05993)
		(width 0.127)
		(layer "In5.Cu")
		(net "SCC_RMT_TYPE_0")
	)
	(segment
		(start 83.444334 -133.477)
		(end 83.088988 -133.832346)
		(width 0.127)
		(layer "In5.Cu")
		(net "SCC_RMT_TYPE_0")
	)
	(segment
		(start 100.838 -125.878082)
		(end 95.067882 -131.6482)
		(width 0.127)
		(layer "In5.Cu")
		(net "SCC_RMT_TYPE_0")
	)
	(segment
		(start 59.450732 -133.919468)
		(end 59.31027 -134.05993)
		(width 0.127)
		(layer "In5.Cu")
		(net "SCC_RMT_TYPE_0")
	)
	(segment
		(start 103.4542 -41.3004)
		(end 101.23678 -43.51782)
		(width 0.127)
		(layer "In5.Cu")
		(net "SCC_RMT_TYPE_0")
	)
	(segment
		(start 103.4542 -38.4048)
		(end 103.4542 -41.3004)
		(width 0.127)
		(layer "In5.Cu")
		(net "SCC_RMT_TYPE_0")
	)
	(segment
		(start 72.471788 -134.2644)
		(end 71.404988 -133.1976)
		(width 0.127)
		(layer "In5.Cu")
		(net "SCC_RMT_TYPE_0")
	)
	(segment
		(start 97.866454 -114.9096)
		(end 97.866454 -116.722652)
		(width 0.127)
		(layer "In5.Cu")
		(net "SCC_RMT_TYPE_0")
	)
	(segment
		(start 99.568 -110.3122)
		(end 98.8949 -110.9853)
		(width 0.127)
		(layer "In5.Cu")
		(net "SCC_RMT_TYPE_0")
	)
	(segment
		(start 99.0346 -117.0178)
		(end 100.838 -118.8212)
		(width 0.127)
		(layer "In5.Cu")
		(net "SCC_RMT_TYPE_0")
	)
	(segment
		(start 91.66733 -131.6482)
		(end 90.53703 -132.7785)
		(width 0.127)
		(layer "In5.Cu")
		(net "SCC_RMT_TYPE_0")
	)
	(segment
		(start 98.8949 -110.9853)
		(end 98.8949 -113.881154)
		(width 0.127)
		(layer "In5.Cu")
		(net "SCC_RMT_TYPE_0")
	)
	(segment
		(start 101.23678 -56.887364)
		(end 99.568 -58.556144)
		(width 0.127)
		(layer "In5.Cu")
		(net "SCC_RMT_TYPE_0")
	)
	(segment
		(start 58.237374 -135.0264)
		(end 56.8452 -135.0264)
		(width 0.127)
		(layer "In5.Cu")
		(net "SCC_RMT_TYPE_0")
	)
	(segment
		(start 87.294212 -133.477)
		(end 83.444334 -133.477)
		(width 0.127)
		(layer "In5.Cu")
		(net "SCC_RMT_TYPE_0")
	)
	(segment
		(start 98.161602 -117.0178)
		(end 99.0346 -117.0178)
		(width 0.127)
		(layer "In5.Cu")
		(net "SCC_RMT_TYPE_0")
	)
	(segment
		(start 103.2256 -38.1762)
		(end 103.4542 -38.4048)
		(width 0.127)
		(layer "In5.Cu")
		(net "SCC_RMT_TYPE_0")
	)
	(segment
		(start 65.689988 -133.1976)
		(end 64.96812 -133.919468)
		(width 0.127)
		(layer "In5.Cu")
		(net "SCC_RMT_TYPE_0")
	)
	(segment
		(start 99.568 -58.556144)
		(end 99.568 -110.3122)
		(width 0.127)
		(layer "In5.Cu")
		(net "SCC_RMT_TYPE_0")
	)
	(segment
		(start 81.223612 -134.2644)
		(end 72.471788 -134.2644)
		(width 0.127)
		(layer "In5.Cu")
		(net "SCC_RMT_TYPE_0")
	)
	(segment
		(start 83.088988 -133.832346)
		(end 81.655666 -133.832346)
		(width 0.127)
		(layer "In5.Cu")
		(net "SCC_RMT_TYPE_0")
	)
	(segment
		(start 98.8949 -113.881154)
		(end 97.866454 -114.9096)
		(width 0.127)
		(layer "In5.Cu")
		(net "SCC_RMT_TYPE_0")
	)
	(segment
		(start 90.53703 -132.7785)
		(end 87.992712 -132.7785)
		(width 0.127)
		(layer "In5.Cu")
		(net "SCC_RMT_TYPE_0")
	)
	(segment
		(start 100.838 -118.8212)
		(end 100.838 -125.878082)
		(width 0.127)
		(layer "In5.Cu")
		(net "SCC_RMT_TYPE_0")
	)
	(segment
		(start 81.655666 -133.832346)
		(end 81.223612 -134.2644)
		(width 0.127)
		(layer "In5.Cu")
		(net "SCC_RMT_TYPE_0")
	)
	(segment
		(start 71.404988 -133.1976)
		(end 65.689988 -133.1976)
		(width 0.127)
		(layer "In5.Cu")
		(net "SCC_RMT_TYPE_0")
	)
	(segment
		(start 95.067882 -131.6482)
		(end 91.66733 -131.6482)
		(width 0.127)
		(layer "In5.Cu")
		(net "SCC_RMT_TYPE_0")
	)
	(via
		(at 37.6936 -154.178)
		(size 0.6096)
		(drill 0.3048)
		(layers "F.Cu" "B.Cu")
		(net "SCC_RMT_HEARTBEAT")
	)
	(via
		(at 85.442298 -164.842698)
		(size 0.508)
		(drill 0.254)
		(layers "F.Cu" "B.Cu")
		(net "SCC_RMT_HEARTBEAT")
	)
	(via
		(at 36.642802 -154.691842)
		(size 0.508)
		(drill 0.254)
		(layers "F.Cu" "B.Cu")
		(net "SCC_RMT_HEARTBEAT")
	)
	(segment
		(start 36.642802 -154.691842)
		(end 36.826444 -154.5082)
		(width 0.127)
		(layer "B.Cu")
		(net "SCC_RMT_HEARTBEAT")
	)
	(segment
		(start 37.974778 -153.050748)
		(end 37.974778 -153.896822)
		(width 0.127)
		(layer "B.Cu")
		(net "SCC_RMT_HEARTBEAT")
	)
	(segment
		(start 37.974778 -153.896822)
		(end 37.6936 -154.178)
		(width 0.127)
		(layer "B.Cu")
		(net "SCC_RMT_HEARTBEAT")
	)
	(segment
		(start 36.826444 -154.5082)
		(end 37.3634 -154.5082)
		(width 0.127)
		(layer "B.Cu")
		(net "SCC_RMT_HEARTBEAT")
	)
	(segment
		(start 37.3634 -154.5082)
		(end 37.6936 -154.178)
		(width 0.127)
		(layer "B.Cu")
		(net "SCC_RMT_HEARTBEAT")
	)
	(segment
		(start 138.652504 -30.5054)
		(end 132.607304 -24.4602)
		(width 0.127)
		(layer "In2.Cu")
		(net "SCC_RMT_HEARTBEAT")
	)
	(segment
		(start 81.5086 -136.525)
		(end 82.156554 -137.172954)
		(width 0.127)
		(layer "In2.Cu")
		(net "SCC_RMT_HEARTBEAT")
	)
	(segment
		(start 137.700004 -40.600122)
		(end 138.652504 -39.647622)
		(width 0.127)
		(layer "In2.Cu")
		(net "SCC_RMT_HEARTBEAT")
	)
	(segment
		(start 82.747866 -158.859474)
		(end 84.5312 -160.642808)
		(width 0.127)
		(layer "In2.Cu")
		(net "SCC_RMT_HEARTBEAT")
	)
	(segment
		(start 80.7085 -129.4003)
		(end 81.8134 -130.5052)
		(width 0.127)
		(layer "In2.Cu")
		(net "SCC_RMT_HEARTBEAT")
	)
	(segment
		(start 80.7085 -126.977394)
		(end 80.7085 -129.4003)
		(width 0.127)
		(layer "In2.Cu")
		(net "SCC_RMT_HEARTBEAT")
	)
	(segment
		(start 132.607304 -24.4602)
		(end 126.314708 -24.4602)
		(width 0.127)
		(layer "In2.Cu")
		(net "SCC_RMT_HEARTBEAT")
	)
	(segment
		(start 84.6074 -113.51387)
		(end 84.6074 -115.916964)
		(width 0.127)
		(layer "In2.Cu")
		(net "SCC_RMT_HEARTBEAT")
	)
	(segment
		(start 84.6074 -115.916964)
		(end 85.4075 -116.717064)
		(width 0.127)
		(layer "In2.Cu")
		(net "SCC_RMT_HEARTBEAT")
	)
	(segment
		(start 85.4075 -122.278394)
		(end 80.7085 -126.977394)
		(width 0.127)
		(layer "In2.Cu")
		(net "SCC_RMT_HEARTBEAT")
	)
	(segment
		(start 87.3633 -108.089192)
		(end 85.1027 -110.349792)
		(width 0.127)
		(layer "In2.Cu")
		(net "SCC_RMT_HEARTBEAT")
	)
	(segment
		(start 83.938364 -34.324798)
		(end 83.938364 -60.494164)
		(width 0.127)
		(layer "In2.Cu")
		(net "SCC_RMT_HEARTBEAT")
	)
	(segment
		(start 82.747866 -152.82291)
		(end 82.747866 -158.859474)
		(width 0.127)
		(layer "In2.Cu")
		(net "SCC_RMT_HEARTBEAT")
	)
	(segment
		(start 85.2932 -163.5506)
		(end 85.2932 -164.6936)
		(width 0.127)
		(layer "In2.Cu")
		(net "SCC_RMT_HEARTBEAT")
	)
	(segment
		(start 86.0171 -62.5729)
		(end 86.0171 -93.563694)
		(width 0.127)
		(layer "In2.Cu")
		(net "SCC_RMT_HEARTBEAT")
	)
	(segment
		(start 85.4075 -116.717064)
		(end 85.4075 -122.278394)
		(width 0.127)
		(layer "In2.Cu")
		(net "SCC_RMT_HEARTBEAT")
	)
	(segment
		(start 85.1027 -110.349792)
		(end 85.1027 -113.01857)
		(width 0.127)
		(layer "In2.Cu")
		(net "SCC_RMT_HEARTBEAT")
	)
	(segment
		(start 81.6737 -151.748744)
		(end 82.747866 -152.82291)
		(width 0.127)
		(layer "In2.Cu")
		(net "SCC_RMT_HEARTBEAT")
	)
	(segment
		(start 81.8134 -133.870954)
		(end 81.5086 -134.175754)
		(width 0.127)
		(layer "In2.Cu")
		(net "SCC_RMT_HEARTBEAT")
	)
	(segment
		(start 82.181954 -10.145014)
		(end 82.181954 -32.568388)
		(width 0.127)
		(layer "In2.Cu")
		(net "SCC_RMT_HEARTBEAT")
	)
	(segment
		(start 96.697038 -13.773658)
		(end 96.697038 -10.53592)
		(width 0.127)
		(layer "In2.Cu")
		(net "SCC_RMT_HEARTBEAT")
	)
	(segment
		(start 81.6737 -146.318224)
		(end 81.6737 -151.748744)
		(width 0.127)
		(layer "In2.Cu")
		(net "SCC_RMT_HEARTBEAT")
	)
	(segment
		(start 85.2932 -164.6936)
		(end 85.442298 -164.842698)
		(width 0.127)
		(layer "In2.Cu")
		(net "SCC_RMT_HEARTBEAT")
	)
	(segment
		(start 82.156554 -145.83537)
		(end 81.6737 -146.318224)
		(width 0.127)
		(layer "In2.Cu")
		(net "SCC_RMT_HEARTBEAT")
	)
	(segment
		(start 96.697038 -10.53592)
		(end 94.325694 -8.164576)
		(width 0.127)
		(layer "In2.Cu")
		(net "SCC_RMT_HEARTBEAT")
	)
	(segment
		(start 84.5312 -160.642808)
		(end 84.5312 -162.7886)
		(width 0.127)
		(layer "In2.Cu")
		(net "SCC_RMT_HEARTBEAT")
	)
	(segment
		(start 118.461536 -18.4658)
		(end 115.94084 -15.945104)
		(width 0.127)
		(layer "In2.Cu")
		(net "SCC_RMT_HEARTBEAT")
	)
	(segment
		(start 83.938364 -60.494164)
		(end 86.0171 -62.5729)
		(width 0.127)
		(layer "In2.Cu")
		(net "SCC_RMT_HEARTBEAT")
	)
	(segment
		(start 98.868484 -15.945104)
		(end 96.697038 -13.773658)
		(width 0.127)
		(layer "In2.Cu")
		(net "SCC_RMT_HEARTBEAT")
	)
	(segment
		(start 84.162392 -8.164576)
		(end 82.181954 -10.145014)
		(width 0.127)
		(layer "In2.Cu")
		(net "SCC_RMT_HEARTBEAT")
	)
	(segment
		(start 84.666582 -99.20859)
		(end 87.3633 -101.905308)
		(width 0.127)
		(layer "In2.Cu")
		(net "SCC_RMT_HEARTBEAT")
	)
	(segment
		(start 115.94084 -15.945104)
		(end 98.868484 -15.945104)
		(width 0.127)
		(layer "In2.Cu")
		(net "SCC_RMT_HEARTBEAT")
	)
	(segment
		(start 84.666582 -94.914212)
		(end 84.666582 -99.20859)
		(width 0.127)
		(layer "In2.Cu")
		(net "SCC_RMT_HEARTBEAT")
	)
	(segment
		(start 86.0171 -93.563694)
		(end 84.666582 -94.914212)
		(width 0.127)
		(layer "In2.Cu")
		(net "SCC_RMT_HEARTBEAT")
	)
	(segment
		(start 126.314708 -24.4602)
		(end 120.320308 -18.4658)
		(width 0.127)
		(layer "In2.Cu")
		(net "SCC_RMT_HEARTBEAT")
	)
	(segment
		(start 82.181954 -32.568388)
		(end 83.938364 -34.324798)
		(width 0.127)
		(layer "In2.Cu")
		(net "SCC_RMT_HEARTBEAT")
	)
	(segment
		(start 120.320308 -18.4658)
		(end 118.461536 -18.4658)
		(width 0.127)
		(layer "In2.Cu")
		(net "SCC_RMT_HEARTBEAT")
	)
	(segment
		(start 85.1027 -113.01857)
		(end 84.6074 -113.51387)
		(width 0.127)
		(layer "In2.Cu")
		(net "SCC_RMT_HEARTBEAT")
	)
	(segment
		(start 94.325694 -8.164576)
		(end 84.162392 -8.164576)
		(width 0.127)
		(layer "In2.Cu")
		(net "SCC_RMT_HEARTBEAT")
	)
	(segment
		(start 87.3633 -101.905308)
		(end 87.3633 -108.089192)
		(width 0.127)
		(layer "In2.Cu")
		(net "SCC_RMT_HEARTBEAT")
	)
	(segment
		(start 84.5312 -162.7886)
		(end 85.2932 -163.5506)
		(width 0.127)
		(layer "In2.Cu")
		(net "SCC_RMT_HEARTBEAT")
	)
	(segment
		(start 82.156554 -137.172954)
		(end 82.156554 -145.83537)
		(width 0.127)
		(layer "In2.Cu")
		(net "SCC_RMT_HEARTBEAT")
	)
	(segment
		(start 138.652504 -39.647622)
		(end 138.652504 -30.5054)
		(width 0.127)
		(layer "In2.Cu")
		(net "SCC_RMT_HEARTBEAT")
	)
	(segment
		(start 81.5086 -134.175754)
		(end 81.5086 -136.525)
		(width 0.127)
		(layer "In2.Cu")
		(net "SCC_RMT_HEARTBEAT")
	)
	(segment
		(start 81.8134 -130.5052)
		(end 81.8134 -133.870954)
		(width 0.127)
		(layer "In2.Cu")
		(net "SCC_RMT_HEARTBEAT")
	)
	(segment
		(start 83.185762 -163.877244)
		(end 79.709518 -160.401)
		(width 0.127)
		(layer "In5.Cu")
		(net "SCC_RMT_HEARTBEAT")
	)
	(segment
		(start 42.36466 -157.822138)
		(end 41.666922 -157.1244)
		(width 0.127)
		(layer "In5.Cu")
		(net "SCC_RMT_HEARTBEAT")
	)
	(segment
		(start 55.362094 -162.0774)
		(end 51.106832 -157.822138)
		(width 0.127)
		(layer "In5.Cu")
		(net "SCC_RMT_HEARTBEAT")
	)
	(segment
		(start 84.907882 -164.719)
		(end 84.066126 -163.877244)
		(width 0.127)
		(layer "In5.Cu")
		(net "SCC_RMT_HEARTBEAT")
	)
	(segment
		(start 73.025 -162.3314)
		(end 63.353188 -162.3314)
		(width 0.127)
		(layer "In5.Cu")
		(net "SCC_RMT_HEARTBEAT")
	)
	(segment
		(start 85.442298 -164.842698)
		(end 85.3186 -164.719)
		(width 0.127)
		(layer "In5.Cu")
		(net "SCC_RMT_HEARTBEAT")
	)
	(segment
		(start 79.709518 -160.401)
		(end 74.9554 -160.401)
		(width 0.127)
		(layer "In5.Cu")
		(net "SCC_RMT_HEARTBEAT")
	)
	(segment
		(start 36.642802 -156.20365)
		(end 36.642802 -154.691842)
		(width 0.127)
		(layer "In5.Cu")
		(net "SCC_RMT_HEARTBEAT")
	)
	(segment
		(start 41.666922 -157.1244)
		(end 37.563552 -157.1244)
		(width 0.127)
		(layer "In5.Cu")
		(net "SCC_RMT_HEARTBEAT")
	)
	(segment
		(start 85.3186 -164.719)
		(end 84.907882 -164.719)
		(width 0.127)
		(layer "In5.Cu")
		(net "SCC_RMT_HEARTBEAT")
	)
	(segment
		(start 61.565282 -162.4584)
		(end 57.319418 -162.4584)
		(width 0.127)
		(layer "In5.Cu")
		(net "SCC_RMT_HEARTBEAT")
	)
	(segment
		(start 37.563552 -157.1244)
		(end 36.642802 -156.20365)
		(width 0.127)
		(layer "In5.Cu")
		(net "SCC_RMT_HEARTBEAT")
	)
	(segment
		(start 57.319418 -162.4584)
		(end 56.938418 -162.0774)
		(width 0.127)
		(layer "In5.Cu")
		(net "SCC_RMT_HEARTBEAT")
	)
	(segment
		(start 56.938418 -162.0774)
		(end 55.362094 -162.0774)
		(width 0.127)
		(layer "In5.Cu")
		(net "SCC_RMT_HEARTBEAT")
	)
	(segment
		(start 51.106832 -157.822138)
		(end 42.36466 -157.822138)
		(width 0.127)
		(layer "In5.Cu")
		(net "SCC_RMT_HEARTBEAT")
	)
	(segment
		(start 62.984888 -161.9631)
		(end 62.060582 -161.9631)
		(width 0.127)
		(layer "In5.Cu")
		(net "SCC_RMT_HEARTBEAT")
	)
	(segment
		(start 62.060582 -161.9631)
		(end 61.565282 -162.4584)
		(width 0.127)
		(layer "In5.Cu")
		(net "SCC_RMT_HEARTBEAT")
	)
	(segment
		(start 84.066126 -163.877244)
		(end 83.185762 -163.877244)
		(width 0.127)
		(layer "In5.Cu")
		(net "SCC_RMT_HEARTBEAT")
	)
	(segment
		(start 63.353188 -162.3314)
		(end 62.984888 -161.9631)
		(width 0.127)
		(layer "In5.Cu")
		(net "SCC_RMT_HEARTBEAT")
	)
	(segment
		(start 74.9554 -160.401)
		(end 73.025 -162.3314)
		(width 0.127)
		(layer "In5.Cu")
		(net "SCC_RMT_HEARTBEAT")
	)
	(segment
		(start 58.049414 -134.503414)
		(end 59.279028 -133.2738)
		(width 0.127)
		(layer "F.Cu")
		(net "SCC_PWR_EN_R")
	)
	(segment
		(start 56.099964 -137.40003)
		(end 56.438292 -137.40003)
		(width 0.127)
		(layer "F.Cu")
		(net "SCC_PWR_EN_R")
	)
	(segment
		(start 57.658 -136.180322)
		(end 57.658 -134.894828)
		(width 0.127)
		(layer "F.Cu")
		(net "SCC_PWR_EN_R")
	)
	(segment
		(start 56.438292 -137.40003)
		(end 57.658 -136.180322)
		(width 0.127)
		(layer "F.Cu")
		(net "SCC_PWR_EN_R")
	)
	(segment
		(start 57.658 -134.894828)
		(end 58.049414 -134.503414)
		(width 0.127)
		(layer "F.Cu")
		(net "SCC_PWR_EN_R")
	)
	(segment
		(start 59.279028 -133.2738)
		(end 59.857386 -133.2738)
		(width 0.127)
		(layer "F.Cu")
		(net "SCC_PWR_EN_R")
	)
	(via
		(at 58.049414 -134.503414)
		(size 0.6604)
		(drill 0.3302)
		(layers "F.Cu" "B.Cu")
		(net "SCC_PWR_EN_R")
	)
	(segment
		(start 33.59023 -156.807916)
		(end 33.160716 -156.807916)
		(width 0.127)
		(layer "F.Cu")
		(net "SCC_LOC_HEARTBEAT")
	)
	(segment
		(start 33.160716 -156.807916)
		(end 32.6898 -156.337)
		(width 0.127)
		(layer "F.Cu")
		(net "SCC_LOC_HEARTBEAT")
	)
	(via
		(at 85.344 -168.1988)
		(size 0.508)
		(drill 0.254)
		(layers "F.Cu" "B.Cu")
		(net "SCC_LOC_HEARTBEAT")
	)
	(via
		(at 32.6898 -156.337)
		(size 0.508)
		(drill 0.254)
		(layers "F.Cu" "B.Cu")
		(net "SCC_LOC_HEARTBEAT")
	)
	(segment
		(start 86.0679 -165.9255)
		(end 85.5091 -166.4843)
		(width 0.127)
		(layer "In2.Cu")
		(net "SCC_LOC_HEARTBEAT")
	)
	(segment
		(start 84.9884 -115.758976)
		(end 85.7885 -116.559076)
		(width 0.127)
		(layer "In2.Cu")
		(net "SCC_LOC_HEARTBEAT")
	)
	(segment
		(start 118.379748 -18.923)
		(end 115.782852 -16.326104)
		(width 0.127)
		(layer "In2.Cu")
		(net "SCC_LOC_HEARTBEAT")
	)
	(segment
		(start 81.0895 -129.1971)
		(end 82.1944 -130.302)
		(width 0.127)
		(layer "In2.Cu")
		(net "SCC_LOC_HEARTBEAT")
	)
	(segment
		(start 84.32038 -8.545576)
		(end 82.562954 -10.303002)
		(width 0.127)
		(layer "In2.Cu")
		(net "SCC_LOC_HEARTBEAT")
	)
	(segment
		(start 84.9884 -113.671858)
		(end 84.9884 -115.758976)
		(width 0.127)
		(layer "In2.Cu")
		(net "SCC_LOC_HEARTBEAT")
	)
	(segment
		(start 82.1944 -130.302)
		(end 82.1944 -134.0358)
		(width 0.127)
		(layer "In2.Cu")
		(net "SCC_LOC_HEARTBEAT")
	)
	(segment
		(start 82.1944 -134.0358)
		(end 82.537554 -134.378954)
		(width 0.127)
		(layer "In2.Cu")
		(net "SCC_LOC_HEARTBEAT")
	)
	(segment
		(start 85.4837 -110.50778)
		(end 85.4837 -113.176558)
		(width 0.127)
		(layer "In2.Cu")
		(net "SCC_LOC_HEARTBEAT")
	)
	(segment
		(start 85.5091 -168.0337)
		(end 85.344 -168.1988)
		(width 0.127)
		(layer "In2.Cu")
		(net "SCC_LOC_HEARTBEAT")
	)
	(segment
		(start 84.319364 -59.147964)
		(end 86.4362 -61.2648)
		(width 0.127)
		(layer "In2.Cu")
		(net "SCC_LOC_HEARTBEAT")
	)
	(segment
		(start 96.316038 -10.693908)
		(end 94.167706 -8.545576)
		(width 0.127)
		(layer "In2.Cu")
		(net "SCC_LOC_HEARTBEAT")
	)
	(segment
		(start 85.5091 -166.4843)
		(end 85.5091 -168.0337)
		(width 0.127)
		(layer "In2.Cu")
		(net "SCC_LOC_HEARTBEAT")
	)
	(segment
		(start 126.156974 -24.841454)
		(end 120.23852 -18.923)
		(width 0.127)
		(layer "In2.Cu")
		(net "SCC_LOC_HEARTBEAT")
	)
	(segment
		(start 86.0679 -161.64052)
		(end 86.0679 -165.9255)
		(width 0.127)
		(layer "In2.Cu")
		(net "SCC_LOC_HEARTBEAT")
	)
	(segment
		(start 85.4837 -113.176558)
		(end 84.9884 -113.671858)
		(width 0.127)
		(layer "In2.Cu")
		(net "SCC_LOC_HEARTBEAT")
	)
	(segment
		(start 87.7443 -108.24718)
		(end 85.4837 -110.50778)
		(width 0.127)
		(layer "In2.Cu")
		(net "SCC_LOC_HEARTBEAT")
	)
	(segment
		(start 85.7885 -122.604784)
		(end 81.0895 -127.303784)
		(width 0.127)
		(layer "In2.Cu")
		(net "SCC_LOC_HEARTBEAT")
	)
	(segment
		(start 82.537554 -134.378954)
		(end 82.537554 -145.993358)
		(width 0.127)
		(layer "In2.Cu")
		(net "SCC_LOC_HEARTBEAT")
	)
	(segment
		(start 82.0547 -146.852386)
		(end 82.0547 -151.590756)
		(width 0.127)
		(layer "In2.Cu")
		(net "SCC_LOC_HEARTBEAT")
	)
	(segment
		(start 85.87232 -94.247462)
		(end 85.87232 -97.92208)
		(width 0.127)
		(layer "In2.Cu")
		(net "SCC_LOC_HEARTBEAT")
	)
	(segment
		(start 85.6234 -99.62642)
		(end 87.7443 -101.74732)
		(width 0.127)
		(layer "In2.Cu")
		(net "SCC_LOC_HEARTBEAT")
	)
	(segment
		(start 83.12912 -158.70174)
		(end 86.0679 -161.64052)
		(width 0.127)
		(layer "In2.Cu")
		(net "SCC_LOC_HEARTBEAT")
	)
	(segment
		(start 87.7443 -101.74732)
		(end 87.7443 -108.24718)
		(width 0.127)
		(layer "In2.Cu")
		(net "SCC_LOC_HEARTBEAT")
	)
	(segment
		(start 94.167706 -8.545576)
		(end 84.32038 -8.545576)
		(width 0.127)
		(layer "In2.Cu")
		(net "SCC_LOC_HEARTBEAT")
	)
	(segment
		(start 126.472442 -24.841454)
		(end 126.156974 -24.841454)
		(width 0.127)
		(layer "In2.Cu")
		(net "SCC_LOC_HEARTBEAT")
	)
	(segment
		(start 98.710496 -16.326104)
		(end 96.316038 -13.931646)
		(width 0.127)
		(layer "In2.Cu")
		(net "SCC_LOC_HEARTBEAT")
	)
	(segment
		(start 82.476086 -146.054826)
		(end 82.476086 -146.431)
		(width 0.127)
		(layer "In2.Cu")
		(net "SCC_LOC_HEARTBEAT")
	)
	(segment
		(start 83.12912 -152.665176)
		(end 83.12912 -158.70174)
		(width 0.127)
		(layer "In2.Cu")
		(net "SCC_LOC_HEARTBEAT")
	)
	(segment
		(start 120.23852 -18.923)
		(end 118.379748 -18.923)
		(width 0.127)
		(layer "In2.Cu")
		(net "SCC_LOC_HEARTBEAT")
	)
	(segment
		(start 85.87232 -97.92208)
		(end 85.6234 -98.171)
		(width 0.127)
		(layer "In2.Cu")
		(net "SCC_LOC_HEARTBEAT")
	)
	(segment
		(start 96.316038 -13.931646)
		(end 96.316038 -10.693908)
		(width 0.127)
		(layer "In2.Cu")
		(net "SCC_LOC_HEARTBEAT")
	)
	(segment
		(start 85.7885 -116.559076)
		(end 85.7885 -122.604784)
		(width 0.127)
		(layer "In2.Cu")
		(net "SCC_LOC_HEARTBEAT")
	)
	(segment
		(start 82.562954 -32.4104)
		(end 84.319364 -34.16681)
		(width 0.127)
		(layer "In2.Cu")
		(net "SCC_LOC_HEARTBEAT")
	)
	(segment
		(start 115.782852 -16.326104)
		(end 98.710496 -16.326104)
		(width 0.127)
		(layer "In2.Cu")
		(net "SCC_LOC_HEARTBEAT")
	)
	(segment
		(start 84.319364 -34.16681)
		(end 84.319364 -59.147964)
		(width 0.127)
		(layer "In2.Cu")
		(net "SCC_LOC_HEARTBEAT")
	)
	(segment
		(start 81.0895 -127.303784)
		(end 81.0895 -129.1971)
		(width 0.127)
		(layer "In2.Cu")
		(net "SCC_LOC_HEARTBEAT")
	)
	(segment
		(start 126.472696 -24.8412)
		(end 126.472442 -24.841454)
		(width 0.127)
		(layer "In2.Cu")
		(net "SCC_LOC_HEARTBEAT")
	)
	(segment
		(start 86.4362 -61.2648)
		(end 86.4362 -93.683582)
		(width 0.127)
		(layer "In2.Cu")
		(net "SCC_LOC_HEARTBEAT")
	)
	(segment
		(start 132.449316 -24.8412)
		(end 126.472696 -24.8412)
		(width 0.127)
		(layer "In2.Cu")
		(net "SCC_LOC_HEARTBEAT")
	)
	(segment
		(start 82.562954 -10.303002)
		(end 82.562954 -32.4104)
		(width 0.127)
		(layer "In2.Cu")
		(net "SCC_LOC_HEARTBEAT")
	)
	(segment
		(start 138.271504 -38.628574)
		(end 138.271504 -30.663388)
		(width 0.127)
		(layer "In2.Cu")
		(net "SCC_LOC_HEARTBEAT")
	)
	(segment
		(start 82.476086 -146.431)
		(end 82.0547 -146.852386)
		(width 0.127)
		(layer "In2.Cu")
		(net "SCC_LOC_HEARTBEAT")
	)
	(segment
		(start 85.6234 -98.171)
		(end 85.6234 -99.62642)
		(width 0.127)
		(layer "In2.Cu")
		(net "SCC_LOC_HEARTBEAT")
	)
	(segment
		(start 137.700004 -39.200074)
		(end 138.271504 -38.628574)
		(width 0.127)
		(layer "In2.Cu")
		(net "SCC_LOC_HEARTBEAT")
	)
	(segment
		(start 86.4362 -93.683582)
		(end 85.87232 -94.247462)
		(width 0.127)
		(layer "In2.Cu")
		(net "SCC_LOC_HEARTBEAT")
	)
	(segment
		(start 82.0547 -151.590756)
		(end 83.12912 -152.665176)
		(width 0.127)
		(layer "In2.Cu")
		(net "SCC_LOC_HEARTBEAT")
	)
	(segment
		(start 82.537554 -145.993358)
		(end 82.476086 -146.054826)
		(width 0.127)
		(layer "In2.Cu")
		(net "SCC_LOC_HEARTBEAT")
	)
	(segment
		(start 138.271504 -30.663388)
		(end 132.449316 -24.8412)
		(width 0.127)
		(layer "In2.Cu")
		(net "SCC_LOC_HEARTBEAT")
	)
	(segment
		(start 43.4721 -162.17138)
		(end 43.4721 -162.856418)
		(width 0.127)
		(layer "In5.Cu")
		(net "SCC_LOC_HEARTBEAT")
	)
	(segment
		(start 32.6898 -156.337)
		(end 33.0962 -156.337)
		(width 0.127)
		(layer "In5.Cu")
		(net "SCC_LOC_HEARTBEAT")
	)
	(segment
		(start 85.1535 -168.3893)
		(end 85.344 -168.1988)
		(width 0.127)
		(layer "In5.Cu")
		(net "SCC_LOC_HEARTBEAT")
	)
	(segment
		(start 64.90462 -168.28262)
		(end 65.309496 -168.687496)
		(width 0.127)
		(layer "In5.Cu")
		(net "SCC_LOC_HEARTBEAT")
	)
	(segment
		(start 45.48632 -163.169346)
		(end 47.442374 -165.1254)
		(width 0.127)
		(layer "In5.Cu")
		(net "SCC_LOC_HEARTBEAT")
	)
	(segment
		(start 53.733954 -165.1254)
		(end 56.891174 -168.28262)
		(width 0.127)
		(layer "In5.Cu")
		(net "SCC_LOC_HEARTBEAT")
	)
	(segment
		(start 65.309496 -168.687496)
		(end 68.345304 -168.687496)
		(width 0.127)
		(layer "In5.Cu")
		(net "SCC_LOC_HEARTBEAT")
	)
	(segment
		(start 35.49015 -157.20695)
		(end 36.9316 -158.6484)
		(width 0.127)
		(layer "In5.Cu")
		(net "SCC_LOC_HEARTBEAT")
	)
	(segment
		(start 68.345304 -168.687496)
		(end 68.6435 -168.3893)
		(width 0.127)
		(layer "In5.Cu")
		(net "SCC_LOC_HEARTBEAT")
	)
	(segment
		(start 33.0962 -156.337)
		(end 33.96615 -157.20695)
		(width 0.127)
		(layer "In5.Cu")
		(net "SCC_LOC_HEARTBEAT")
	)
	(segment
		(start 47.442374 -165.1254)
		(end 53.733954 -165.1254)
		(width 0.127)
		(layer "In5.Cu")
		(net "SCC_LOC_HEARTBEAT")
	)
	(segment
		(start 68.6435 -168.3893)
		(end 85.1535 -168.3893)
		(width 0.127)
		(layer "In5.Cu")
		(net "SCC_LOC_HEARTBEAT")
	)
	(segment
		(start 43.4721 -162.856418)
		(end 43.785028 -163.169346)
		(width 0.127)
		(layer "In5.Cu")
		(net "SCC_LOC_HEARTBEAT")
	)
	(segment
		(start 43.785028 -163.169346)
		(end 45.48632 -163.169346)
		(width 0.127)
		(layer "In5.Cu")
		(net "SCC_LOC_HEARTBEAT")
	)
	(segment
		(start 33.96615 -157.20695)
		(end 35.49015 -157.20695)
		(width 0.127)
		(layer "In5.Cu")
		(net "SCC_LOC_HEARTBEAT")
	)
	(segment
		(start 56.891174 -168.28262)
		(end 64.90462 -168.28262)
		(width 0.127)
		(layer "In5.Cu")
		(net "SCC_LOC_HEARTBEAT")
	)
	(segment
		(start 39.94912 -158.6484)
		(end 43.4721 -162.17138)
		(width 0.127)
		(layer "In5.Cu")
		(net "SCC_LOC_HEARTBEAT")
	)
	(segment
		(start 36.9316 -158.6484)
		(end 39.94912 -158.6484)
		(width 0.127)
		(layer "In5.Cu")
		(net "SCC_LOC_HEARTBEAT")
	)
	(segment
		(start 67.6148 -170.6626)
		(end 67.8434 -170.6626)
		(width 0.127)
		(layer "F.Cu")
		(net "Q4_G")
	)
	(segment
		(start 67.4116 -170.8658)
		(end 67.6148 -170.6626)
		(width 0.127)
		(layer "F.Cu")
		(net "Q4_G")
	)
	(segment
		(start 65.919604 -170.111674)
		(end 65.919604 -170.6626)
		(width 0.127)
		(layer "F.Cu")
		(net "Q4_G")
	)
	(segment
		(start 65.919604 -169.170096)
		(end 65.9257 -169.164)
		(width 0.127)
		(layer "F.Cu")
		(net "Q4_G")
	)
	(segment
		(start 65.9257 -169.164)
		(end 65.9257 -168.4401)
		(width 0.127)
		(layer "F.Cu")
		(net "Q4_G")
	)
	(segment
		(start 65.919604 -170.111674)
		(end 65.919604 -169.170096)
		(width 0.127)
		(layer "F.Cu")
		(net "Q4_G")
	)
	(segment
		(start 65.9257 -168.4401)
		(end 65.6336 -168.148)
		(width 0.127)
		(layer "F.Cu")
		(net "Q4_G")
	)
	(segment
		(start 64.0715 -168.30675)
		(end 64.73825 -168.30675)
		(width 0.127)
		(layer "F.Cu")
		(net "Q4_G")
	)
	(segment
		(start 66.122804 -170.8658)
		(end 67.4116 -170.8658)
		(width 0.127)
		(layer "F.Cu")
		(net "Q4_G")
	)
	(segment
		(start 65.919604 -170.6626)
		(end 66.122804 -170.8658)
		(width 0.127)
		(layer "F.Cu")
		(net "Q4_G")
	)
	(segment
		(start 64.897 -168.148)
		(end 65.6336 -168.148)
		(width 0.127)
		(layer "F.Cu")
		(net "Q4_G")
	)
	(segment
		(start 64.73825 -168.30675)
		(end 64.897 -168.148)
		(width 0.127)
		(layer "F.Cu")
		(net "Q4_G")
	)
	(via
		(at 65.6336 -168.148)
		(size 0.6604)
		(drill 0.3302)
		(layers "F.Cu" "B.Cu")
		(net "Q4_G")
	)
	(via
		(at 206.734664 -86.007956)
		(size 0.6096)
		(drill 0.3048)
		(layers "F.Cu" "B.Cu")
		(net "Q21_G")
	)
	(segment
		(start 207.014064 -87.646256)
		(end 207.014064 -86.287356)
		(width 0.127)
		(layer "B.Cu")
		(net "Q21_G")
	)
	(segment
		(start 207.014064 -86.287356)
		(end 206.734664 -86.007956)
		(width 0.127)
		(layer "B.Cu")
		(net "Q21_G")
	)
	(segment
		(start 207.382364 -87.646256)
		(end 207.014064 -87.646256)
		(width 0.127)
		(layer "B.Cu")
		(net "Q21_G")
	)
	(segment
		(start 209.325464 -84.974176)
		(end 207.057244 -84.974176)
		(width 0.127)
		(layer "B.Cu")
		(net "Q21_G")
	)
	(segment
		(start 207.706214 -87.970106)
		(end 207.382364 -87.646256)
		(width 0.127)
		(layer "B.Cu")
		(net "Q21_G")
	)
	(segment
		(start 207.057244 -84.974176)
		(end 206.734664 -85.296756)
		(width 0.127)
		(layer "B.Cu")
		(net "Q21_G")
	)
	(segment
		(start 206.734664 -85.296756)
		(end 206.734664 -86.007956)
		(width 0.127)
		(layer "B.Cu")
		(net "Q21_G")
	)
	(segment
		(start 208.474564 -87.970106)
		(end 207.706214 -87.970106)
		(width 0.127)
		(layer "B.Cu")
		(net "Q21_G")
	)
	(segment
		(start 151.013414 -7.500874)
		(end 151.013414 -6.575552)
		(width 0.254)
		(layer "F.Cu")
		(net "PWRGD_P2V5_STBY")
	)
	(segment
		(start 74.44105 -185.10885)
		(end 74.0918 -185.4581)
		(width 0.254)
		(layer "F.Cu")
		(net "PWRGD_P2V5_STBY")
	)
	(segment
		(start 74.44105 -182.832502)
		(end 74.44105 -184.5564)
		(width 0.254)
		(layer "F.Cu")
		(net "PWRGD_P2V5_STBY")
	)
	(segment
		(start 150.554182 -6.11632)
		(end 149.543262 -6.11632)
		(width 0.254)
		(layer "F.Cu")
		(net "PWRGD_P2V5_STBY")
	)
	(segment
		(start 74.44105 -184.5564)
		(end 74.44105 -185.10885)
		(width 0.254)
		(layer "F.Cu")
		(net "PWRGD_P2V5_STBY")
	)
	(segment
		(start 150.765002 -6.32714)
		(end 150.554182 -6.11632)
		(width 0.254)
		(layer "F.Cu")
		(net "PWRGD_P2V5_STBY")
	)
	(segment
		(start 151.013414 -6.575552)
		(end 150.765002 -6.32714)
		(width 0.254)
		(layer "F.Cu")
		(net "PWRGD_P2V5_STBY")
	)
	(via
		(at 74.44105 -184.5564)
		(size 0.508)
		(drill 0.254)
		(layers "F.Cu" "B.Cu")
		(net "PWRGD_P2V5_STBY")
	)
	(via
		(at 149.543262 -6.11632)
		(size 0.508)
		(drill 0.254)
		(layers "F.Cu" "B.Cu")
		(net "PWRGD_P2V5_STBY")
	)
	(via
		(at 150.765002 -6.32714)
		(size 0.6604)
		(drill 0.3302)
		(layers "F.Cu" "B.Cu")
		(net "PWRGD_P2V5_STBY")
	)
	(segment
		(start 77.9145 -96.038162)
		(end 78.836012 -96.959674)
		(width 0.254)
		(layer "In2.Cu")
		(net "PWRGD_P2V5_STBY")
	)
	(segment
		(start 67.4878 -130.3782)
		(end 67.4878 -138.303)
		(width 0.254)
		(layer "In2.Cu")
		(net "PWRGD_P2V5_STBY")
	)
	(segment
		(start 70.1167 -165.2905)
		(end 71.53148 -166.70528)
		(width 0.254)
		(layer "In2.Cu")
		(net "PWRGD_P2V5_STBY")
	)
	(segment
		(start 68.119498 -150.212298)
		(end 72.261476 -154.354276)
		(width 0.254)
		(layer "In2.Cu")
		(net "PWRGD_P2V5_STBY")
	)
	(segment
		(start 66.7258 -115.53571)
		(end 66.7258 -120.82272)
		(width 0.254)
		(layer "In2.Cu")
		(net "PWRGD_P2V5_STBY")
	)
	(segment
		(start 95.532956 -2.8702)
		(end 92.58808 -5.815076)
		(width 0.254)
		(layer "In2.Cu")
		(net "PWRGD_P2V5_STBY")
	)
	(segment
		(start 82.4484 -103.9368)
		(end 82.4484 -106.161332)
		(width 0.254)
		(layer "In2.Cu")
		(net "PWRGD_P2V5_STBY")
	)
	(segment
		(start 72.718676 -170.964352)
		(end 72.718676 -173.780196)
		(width 0.254)
		(layer "In2.Cu")
		(net "PWRGD_P2V5_STBY")
	)
	(segment
		(start 67.08648 -147.55241)
		(end 68.119498 -148.585428)
		(width 0.254)
		(layer "In2.Cu")
		(net "PWRGD_P2V5_STBY")
	)
	(segment
		(start 66.7258 -120.82272)
		(end 66.575686 -120.972834)
		(width 0.254)
		(layer "In2.Cu")
		(net "PWRGD_P2V5_STBY")
	)
	(segment
		(start 79.754476 -34.266124)
		(end 76.276454 -37.744146)
		(width 0.254)
		(layer "In2.Cu")
		(net "PWRGD_P2V5_STBY")
	)
	(segment
		(start 74.32802 -184.5818)
		(end 74.41565 -184.5818)
		(width 0.254)
		(layer "In2.Cu")
		(net "PWRGD_P2V5_STBY")
	)
	(segment
		(start 64.697864 -144.607026)
		(end 67.0814 -146.990562)
		(width 0.254)
		(layer "In2.Cu")
		(net "PWRGD_P2V5_STBY")
	)
	(segment
		(start 69.852794 -112.408716)
		(end 66.7258 -115.53571)
		(width 0.254)
		(layer "In2.Cu")
		(net "PWRGD_P2V5_STBY")
	)
	(segment
		(start 149.543262 -6.11632)
		(end 146.297142 -2.8702)
		(width 0.254)
		(layer "In2.Cu")
		(net "PWRGD_P2V5_STBY")
	)
	(segment
		(start 65.518284 -141.43609)
		(end 64.697864 -142.25651)
		(width 0.254)
		(layer "In2.Cu")
		(net "PWRGD_P2V5_STBY")
	)
	(segment
		(start 92.58808 -5.815076)
		(end 82.926682 -5.815076)
		(width 0.254)
		(layer "In2.Cu")
		(net "PWRGD_P2V5_STBY")
	)
	(segment
		(start 67.0814 -138.7094)
		(end 66.29527 -138.7094)
		(width 0.254)
		(layer "In2.Cu")
		(net "PWRGD_P2V5_STBY")
	)
	(segment
		(start 82.926682 -5.815076)
		(end 79.754222 -8.987536)
		(width 0.254)
		(layer "In2.Cu")
		(net "PWRGD_P2V5_STBY")
	)
	(segment
		(start 78.6638 -66.886074)
		(end 78.6638 -91.8972)
		(width 0.254)
		(layer "In2.Cu")
		(net "PWRGD_P2V5_STBY")
	)
	(segment
		(start 77.9145 -92.6465)
		(end 77.9145 -96.038162)
		(width 0.254)
		(layer "In2.Cu")
		(net "PWRGD_P2V5_STBY")
	)
	(segment
		(start 75.5396 -63.965582)
		(end 75.5396 -63.965836)
		(width 0.254)
		(layer "In2.Cu")
		(net "PWRGD_P2V5_STBY")
	)
	(segment
		(start 71.965566 -112.408716)
		(end 69.852794 -112.408716)
		(width 0.254)
		(layer "In2.Cu")
		(net "PWRGD_P2V5_STBY")
	)
	(segment
		(start 71.53148 -166.70528)
		(end 71.53148 -169.777156)
		(width 0.254)
		(layer "In2.Cu")
		(net "PWRGD_P2V5_STBY")
	)
	(segment
		(start 66.575686 -120.972834)
		(end 66.575686 -126.75743)
		(width 0.254)
		(layer "In2.Cu")
		(net "PWRGD_P2V5_STBY")
	)
	(segment
		(start 75.911202 -64.337438)
		(end 75.911456 -64.337438)
		(width 0.254)
		(layer "In2.Cu")
		(net "PWRGD_P2V5_STBY")
	)
	(segment
		(start 67.08648 -147.461732)
		(end 67.08648 -147.55241)
		(width 0.254)
		(layer "In2.Cu")
		(net "PWRGD_P2V5_STBY")
	)
	(segment
		(start 78.836012 -96.959674)
		(end 78.836012 -100.324412)
		(width 0.254)
		(layer "In2.Cu")
		(net "PWRGD_P2V5_STBY")
	)
	(segment
		(start 81.282032 -107.3277)
		(end 77.6097 -107.3277)
		(width 0.254)
		(layer "In2.Cu")
		(net "PWRGD_P2V5_STBY")
	)
	(segment
		(start 76.276454 -47.467774)
		(end 75.3364 -48.407828)
		(width 0.254)
		(layer "In2.Cu")
		(net "PWRGD_P2V5_STBY")
	)
	(segment
		(start 75.5396 -63.965836)
		(end 75.911202 -64.337438)
		(width 0.254)
		(layer "In2.Cu")
		(net "PWRGD_P2V5_STBY")
	)
	(segment
		(start 72.261476 -157.735524)
		(end 70.1167 -159.8803)
		(width 0.254)
		(layer "In2.Cu")
		(net "PWRGD_P2V5_STBY")
	)
	(segment
		(start 66.8909 -127.072644)
		(end 66.8909 -129.7813)
		(width 0.254)
		(layer "In2.Cu")
		(net "PWRGD_P2V5_STBY")
	)
	(segment
		(start 66.8909 -129.7813)
		(end 67.4878 -130.3782)
		(width 0.254)
		(layer "In2.Cu")
		(net "PWRGD_P2V5_STBY")
	)
	(segment
		(start 75.911456 -64.337438)
		(end 77.36205 -65.788032)
		(width 0.254)
		(layer "In2.Cu")
		(net "PWRGD_P2V5_STBY")
	)
	(segment
		(start 71.53148 -169.777156)
		(end 72.718676 -170.964352)
		(width 0.254)
		(layer "In2.Cu")
		(net "PWRGD_P2V5_STBY")
	)
	(segment
		(start 77.565758 -65.788032)
		(end 78.6638 -66.886074)
		(width 0.254)
		(layer "In2.Cu")
		(net "PWRGD_P2V5_STBY")
	)
	(segment
		(start 78.6638 -91.8972)
		(end 77.9145 -92.6465)
		(width 0.254)
		(layer "In2.Cu")
		(net "PWRGD_P2V5_STBY")
	)
	(segment
		(start 76.276454 -37.744146)
		(end 76.276454 -47.467774)
		(width 0.254)
		(layer "In2.Cu")
		(net "PWRGD_P2V5_STBY")
	)
	(segment
		(start 67.0814 -146.990562)
		(end 67.0814 -147.456652)
		(width 0.254)
		(layer "In2.Cu")
		(net "PWRGD_P2V5_STBY")
	)
	(segment
		(start 74.41565 -184.5818)
		(end 74.44105 -184.5564)
		(width 0.254)
		(layer "In2.Cu")
		(net "PWRGD_P2V5_STBY")
	)
	(segment
		(start 71.96582 -112.408462)
		(end 71.965566 -112.408716)
		(width 0.254)
		(layer "In2.Cu")
		(net "PWRGD_P2V5_STBY")
	)
	(segment
		(start 68.119498 -148.585428)
		(end 68.119498 -150.212298)
		(width 0.254)
		(layer "In2.Cu")
		(net "PWRGD_P2V5_STBY")
	)
	(segment
		(start 78.836012 -100.324412)
		(end 82.4484 -103.9368)
		(width 0.254)
		(layer "In2.Cu")
		(net "PWRGD_P2V5_STBY")
	)
	(segment
		(start 75.3364 -63.762382)
		(end 75.5396 -63.965582)
		(width 0.254)
		(layer "In2.Cu")
		(net "PWRGD_P2V5_STBY")
	)
	(segment
		(start 72.528938 -112.408462)
		(end 71.96582 -112.408462)
		(width 0.254)
		(layer "In2.Cu")
		(net "PWRGD_P2V5_STBY")
	)
	(segment
		(start 70.1167 -159.8803)
		(end 70.1167 -165.2905)
		(width 0.254)
		(layer "In2.Cu")
		(net "PWRGD_P2V5_STBY")
	)
	(segment
		(start 66.575686 -126.75743)
		(end 66.8909 -127.072644)
		(width 0.254)
		(layer "In2.Cu")
		(net "PWRGD_P2V5_STBY")
	)
	(segment
		(start 82.4484 -106.161332)
		(end 81.282032 -107.3277)
		(width 0.254)
		(layer "In2.Cu")
		(net "PWRGD_P2V5_STBY")
	)
	(segment
		(start 66.29527 -138.7094)
		(end 65.518284 -139.486386)
		(width 0.254)
		(layer "In2.Cu")
		(net "PWRGD_P2V5_STBY")
	)
	(segment
		(start 65.518284 -139.486386)
		(end 65.518284 -141.43609)
		(width 0.254)
		(layer "In2.Cu")
		(net "PWRGD_P2V5_STBY")
	)
	(segment
		(start 79.754222 -9.513316)
		(end 79.754476 -9.51357)
		(width 0.254)
		(layer "In2.Cu")
		(net "PWRGD_P2V5_STBY")
	)
	(segment
		(start 69.6341 -176.864772)
		(end 69.6341 -179.88788)
		(width 0.254)
		(layer "In2.Cu")
		(net "PWRGD_P2V5_STBY")
	)
	(segment
		(start 72.718676 -173.780196)
		(end 69.6341 -176.864772)
		(width 0.254)
		(layer "In2.Cu")
		(net "PWRGD_P2V5_STBY")
	)
	(segment
		(start 75.3364 -48.407828)
		(end 75.3364 -63.762382)
		(width 0.254)
		(layer "In2.Cu")
		(net "PWRGD_P2V5_STBY")
	)
	(segment
		(start 146.297142 -2.8702)
		(end 95.532956 -2.8702)
		(width 0.254)
		(layer "In2.Cu")
		(net "PWRGD_P2V5_STBY")
	)
	(segment
		(start 72.261476 -154.354276)
		(end 72.261476 -157.735524)
		(width 0.254)
		(layer "In2.Cu")
		(net "PWRGD_P2V5_STBY")
	)
	(segment
		(start 64.697864 -142.25651)
		(end 64.697864 -144.607026)
		(width 0.254)
		(layer "In2.Cu")
		(net "PWRGD_P2V5_STBY")
	)
	(segment
		(start 77.6097 -107.3277)
		(end 72.528938 -112.408462)
		(width 0.254)
		(layer "In2.Cu")
		(net "PWRGD_P2V5_STBY")
	)
	(segment
		(start 79.754222 -8.987536)
		(end 79.754222 -9.513316)
		(width 0.254)
		(layer "In2.Cu")
		(net "PWRGD_P2V5_STBY")
	)
	(segment
		(start 69.6341 -179.88788)
		(end 74.32802 -184.5818)
		(width 0.254)
		(layer "In2.Cu")
		(net "PWRGD_P2V5_STBY")
	)
	(segment
		(start 67.0814 -147.456652)
		(end 67.08648 -147.461732)
		(width 0.254)
		(layer "In2.Cu")
		(net "PWRGD_P2V5_STBY")
	)
	(segment
		(start 77.36205 -65.788032)
		(end 77.565758 -65.788032)
		(width 0.254)
		(layer "In2.Cu")
		(net "PWRGD_P2V5_STBY")
	)
	(segment
		(start 79.754476 -9.51357)
		(end 79.754476 -34.266124)
		(width 0.254)
		(layer "In2.Cu")
		(net "PWRGD_P2V5_STBY")
	)
	(segment
		(start 67.4878 -138.303)
		(end 67.0814 -138.7094)
		(width 0.254)
		(layer "In2.Cu")
		(net "PWRGD_P2V5_STBY")
	)
	(segment
		(start 21.202904 -174.532798)
		(end 20.177252 -174.532798)
		(width 0.254)
		(layer "F.Cu")
		(net "PWRGD_P1V2_STBY")
	)
	(segment
		(start 71.78548 -166.14648)
		(end 71.78548 -165.619176)
		(width 0.254)
		(layer "F.Cu")
		(net "PWRGD_P1V2_STBY")
	)
	(segment
		(start 16.04137 -172.768006)
		(end 16.04137 -171.600622)
		(width 0.254)
		(layer "F.Cu")
		(net "PWRGD_P1V2_STBY")
	)
	(segment
		(start 73.526142 -166.893494)
		(end 72.586342 -166.893494)
		(width 0.254)
		(layer "F.Cu")
		(net "PWRGD_P1V2_STBY")
	)
	(segment
		(start 19.51355 -173.869096)
		(end 17.14246 -173.869096)
		(width 0.254)
		(layer "F.Cu")
		(net "PWRGD_P1V2_STBY")
	)
	(segment
		(start 72.586342 -166.893494)
		(end 72.532494 -166.893494)
		(width 0.254)
		(layer "F.Cu")
		(net "PWRGD_P1V2_STBY")
	)
	(segment
		(start 72.532494 -166.893494)
		(end 71.78548 -166.14648)
		(width 0.254)
		(layer "F.Cu")
		(net "PWRGD_P1V2_STBY")
	)
	(segment
		(start 20.177252 -174.532798)
		(end 19.51355 -173.869096)
		(width 0.254)
		(layer "F.Cu")
		(net "PWRGD_P1V2_STBY")
	)
	(segment
		(start 21.851112 -175.181006)
		(end 21.202904 -174.532798)
		(width 0.254)
		(layer "F.Cu")
		(net "PWRGD_P1V2_STBY")
	)
	(segment
		(start 22.682962 -175.181006)
		(end 22.826472 -175.037496)
		(width 0.254)
		(layer "F.Cu")
		(net "PWRGD_P1V2_STBY")
	)
	(segment
		(start 21.851112 -175.181006)
		(end 22.682962 -175.181006)
		(width 0.254)
		(layer "F.Cu")
		(net "PWRGD_P1V2_STBY")
	)
	(segment
		(start 17.14246 -173.869096)
		(end 16.04137 -172.768006)
		(width 0.254)
		(layer "F.Cu")
		(net "PWRGD_P1V2_STBY")
	)
	(via
		(at 72.586342 -166.893494)
		(size 0.6604)
		(drill 0.3302)
		(layers "F.Cu" "B.Cu")
		(net "PWRGD_P1V2_STBY")
	)
	(via
		(at 30.8102 -165.5826)
		(size 0.508)
		(drill 0.254)
		(layers "F.Cu" "B.Cu")
		(net "PWRGD_P1V2_STBY")
	)
	(via
		(at 73.526142 -166.893494)
		(size 0.508)
		(drill 0.254)
		(layers "F.Cu" "B.Cu")
		(net "PWRGD_P1V2_STBY")
	)
	(via
		(at 22.826472 -175.037496)
		(size 0.508)
		(drill 0.254)
		(layers "F.Cu" "B.Cu")
		(net "PWRGD_P1V2_STBY")
	)
	(segment
		(start 59.533536 -167.31742)
		(end 63.816484 -167.31742)
		(width 0.254)
		(layer "B.Cu")
		(net "PWRGD_P1V2_STBY")
	)
	(segment
		(start 63.816484 -167.31742)
		(end 65.779396 -165.354508)
		(width 0.254)
		(layer "B.Cu")
		(net "PWRGD_P1V2_STBY")
	)
	(segment
		(start 59.094116 -166.878)
		(end 59.533536 -167.31742)
		(width 0.254)
		(layer "B.Cu")
		(net "PWRGD_P1V2_STBY")
	)
	(segment
		(start 34.791904 -165.664896)
		(end 36.6014 -163.8554)
		(width 0.254)
		(layer "B.Cu")
		(net "PWRGD_P1V2_STBY")
	)
	(segment
		(start 30.892496 -165.664896)
		(end 34.791904 -165.664896)
		(width 0.254)
		(layer "B.Cu")
		(net "PWRGD_P1V2_STBY")
	)
	(segment
		(start 48.2092 -167.259)
		(end 53.513482 -167.259)
		(width 0.254)
		(layer "B.Cu")
		(net "PWRGD_P1V2_STBY")
	)
	(segment
		(start 71.093584 -165.355016)
		(end 72.632062 -166.893494)
		(width 0.254)
		(layer "B.Cu")
		(net "PWRGD_P1V2_STBY")
	)
	(segment
		(start 72.632062 -166.893494)
		(end 73.526142 -166.893494)
		(width 0.254)
		(layer "B.Cu")
		(net "PWRGD_P1V2_STBY")
	)
	(segment
		(start 69.61378 -165.355016)
		(end 71.093584 -165.355016)
		(width 0.254)
		(layer "B.Cu")
		(net "PWRGD_P1V2_STBY")
	)
	(segment
		(start 69.613272 -165.354508)
		(end 69.61378 -165.355016)
		(width 0.254)
		(layer "B.Cu")
		(net "PWRGD_P1V2_STBY")
	)
	(segment
		(start 53.894482 -166.878)
		(end 59.094116 -166.878)
		(width 0.254)
		(layer "B.Cu")
		(net "PWRGD_P1V2_STBY")
	)
	(segment
		(start 30.8102 -165.5826)
		(end 30.892496 -165.664896)
		(width 0.254)
		(layer "B.Cu")
		(net "PWRGD_P1V2_STBY")
	)
	(segment
		(start 53.513482 -167.259)
		(end 53.894482 -166.878)
		(width 0.254)
		(layer "B.Cu")
		(net "PWRGD_P1V2_STBY")
	)
	(segment
		(start 65.779396 -165.354508)
		(end 69.613272 -165.354508)
		(width 0.254)
		(layer "B.Cu")
		(net "PWRGD_P1V2_STBY")
	)
	(segment
		(start 44.8056 -163.8554)
		(end 48.2092 -167.259)
		(width 0.254)
		(layer "B.Cu")
		(net "PWRGD_P1V2_STBY")
	)
	(segment
		(start 36.6014 -163.8554)
		(end 44.8056 -163.8554)
		(width 0.254)
		(layer "B.Cu")
		(net "PWRGD_P1V2_STBY")
	)
	(segment
		(start 29.617416 -165.5826)
		(end 30.8102 -165.5826)
		(width 0.254)
		(layer "In5.Cu")
		(net "PWRGD_P1V2_STBY")
	)
	(segment
		(start 22.826472 -175.037496)
		(end 25.50033 -175.037496)
		(width 0.254)
		(layer "In5.Cu")
		(net "PWRGD_P1V2_STBY")
	)
	(segment
		(start 25.50033 -175.037496)
		(end 27.799792 -172.738034)
		(width 0.254)
		(layer "In5.Cu")
		(net "PWRGD_P1V2_STBY")
	)
	(segment
		(start 27.799792 -167.400224)
		(end 29.617416 -165.5826)
		(width 0.254)
		(layer "In5.Cu")
		(net "PWRGD_P1V2_STBY")
	)
	(segment
		(start 27.799792 -172.738034)
		(end 27.799792 -167.400224)
		(width 0.254)
		(layer "In5.Cu")
		(net "PWRGD_P1V2_STBY")
	)
	(segment
		(start 36.828222 -159.147256)
		(end 36.900866 -159.074612)
		(width 0.127)
		(layer "F.Cu")
		(net "PWM_OUT_ZONE_D")
	)
	(segment
		(start 36.900866 -159.074612)
		(end 36.900866 -158.14548)
		(width 0.127)
		(layer "F.Cu")
		(net "PWM_OUT_ZONE_D")
	)
	(segment
		(start 36.828222 -159.147256)
		(end 36.48456 -159.147256)
		(width 0.127)
		(layer "F.Cu")
		(net "PWM_OUT_ZONE_D")
	)
	(segment
		(start 36.48456 -159.147256)
		(end 36.002468 -158.665164)
		(width 0.127)
		(layer "F.Cu")
		(net "PWM_OUT_ZONE_D")
	)
	(via
		(at 36.828222 -159.147256)
		(size 0.6604)
		(drill 0.3302)
		(layers "F.Cu" "B.Cu")
		(net "PWM_OUT_ZONE_D")
	)
	(via
		(at 36.002468 -158.665164)
		(size 0.508)
		(drill 0.254)
		(layers "F.Cu" "B.Cu")
		(net "PWM_OUT_ZONE_D")
	)
	(segment
		(start 85.691218 -172.9105)
		(end 84.1375 -172.9105)
		(width 0.127)
		(layer "In5.Cu")
		(net "PWM_OUT_ZONE_D")
	)
	(segment
		(start 101.78034 -45.719492)
		(end 101.78034 -56.882792)
		(width 0.127)
		(layer "In5.Cu")
		(net "PWM_OUT_ZONE_D")
	)
	(segment
		(start 47.284386 -165.5064)
		(end 45.328332 -163.550346)
		(width 0.127)
		(layer "In5.Cu")
		(net "PWM_OUT_ZONE_D")
	)
	(segment
		(start 99.949 -115.7986)
		(end 102.108 -117.9576)
		(width 0.127)
		(layer "In5.Cu")
		(net "PWM_OUT_ZONE_D")
	)
	(segment
		(start 102.108 -117.9576)
		(end 102.108 -169.5704)
		(width 0.127)
		(layer "In5.Cu")
		(net "PWM_OUT_ZONE_D")
	)
	(segment
		(start 107.099862 -40.39997)
		(end 101.78034 -45.719492)
		(width 0.127)
		(layer "In5.Cu")
		(net "PWM_OUT_ZONE_D")
	)
	(segment
		(start 84.1375 -172.9105)
		(end 83.40852 -173.63948)
		(width 0.127)
		(layer "In5.Cu")
		(net "PWM_OUT_ZONE_D")
	)
	(segment
		(start 99.8601 -171.8183)
		(end 86.783418 -171.8183)
		(width 0.127)
		(layer "In5.Cu")
		(net "PWM_OUT_ZONE_D")
	)
	(segment
		(start 41.247314 -162.257232)
		(end 41.247314 -161.257996)
		(width 0.127)
		(layer "In5.Cu")
		(net "PWM_OUT_ZONE_D")
	)
	(segment
		(start 72.134476 -170.4213)
		(end 66.504312 -170.4213)
		(width 0.127)
		(layer "In5.Cu")
		(net "PWM_OUT_ZONE_D")
	)
	(segment
		(start 101.78034 -56.882792)
		(end 99.949 -58.714132)
		(width 0.127)
		(layer "In5.Cu")
		(net "PWM_OUT_ZONE_D")
	)
	(segment
		(start 73.716642 -172.003466)
		(end 72.134476 -170.4213)
		(width 0.127)
		(layer "In5.Cu")
		(net "PWM_OUT_ZONE_D")
	)
	(segment
		(start 39.018718 -159.0294)
		(end 36.366704 -159.0294)
		(width 0.127)
		(layer "In5.Cu")
		(net "PWM_OUT_ZONE_D")
	)
	(segment
		(start 86.783418 -171.8183)
		(end 85.691218 -172.9105)
		(width 0.127)
		(layer "In5.Cu")
		(net "PWM_OUT_ZONE_D")
	)
	(segment
		(start 76.539344 -172.003466)
		(end 73.716642 -172.003466)
		(width 0.127)
		(layer "In5.Cu")
		(net "PWM_OUT_ZONE_D")
	)
	(segment
		(start 45.328332 -163.550346)
		(end 42.540428 -163.550346)
		(width 0.127)
		(layer "In5.Cu")
		(net "PWM_OUT_ZONE_D")
	)
	(segment
		(start 53.575966 -165.5064)
		(end 47.284386 -165.5064)
		(width 0.127)
		(layer "In5.Cu")
		(net "PWM_OUT_ZONE_D")
	)
	(segment
		(start 66.504312 -170.4213)
		(end 64.746632 -168.66362)
		(width 0.127)
		(layer "In5.Cu")
		(net "PWM_OUT_ZONE_D")
	)
	(segment
		(start 83.40852 -173.63948)
		(end 78.175358 -173.63948)
		(width 0.127)
		(layer "In5.Cu")
		(net "PWM_OUT_ZONE_D")
	)
	(segment
		(start 99.949 -58.714132)
		(end 99.949 -115.7986)
		(width 0.127)
		(layer "In5.Cu")
		(net "PWM_OUT_ZONE_D")
	)
	(segment
		(start 64.746632 -168.66362)
		(end 56.733186 -168.66362)
		(width 0.127)
		(layer "In5.Cu")
		(net "PWM_OUT_ZONE_D")
	)
	(segment
		(start 42.540428 -163.550346)
		(end 41.247314 -162.257232)
		(width 0.127)
		(layer "In5.Cu")
		(net "PWM_OUT_ZONE_D")
	)
	(segment
		(start 102.108 -169.5704)
		(end 99.8601 -171.8183)
		(width 0.127)
		(layer "In5.Cu")
		(net "PWM_OUT_ZONE_D")
	)
	(segment
		(start 36.366704 -159.0294)
		(end 36.002468 -158.665164)
		(width 0.127)
		(layer "In5.Cu")
		(net "PWM_OUT_ZONE_D")
	)
	(segment
		(start 56.733186 -168.66362)
		(end 53.575966 -165.5064)
		(width 0.127)
		(layer "In5.Cu")
		(net "PWM_OUT_ZONE_D")
	)
	(segment
		(start 78.175358 -173.63948)
		(end 76.539344 -172.003466)
		(width 0.127)
		(layer "In5.Cu")
		(net "PWM_OUT_ZONE_D")
	)
	(segment
		(start 41.247314 -161.257996)
		(end 39.018718 -159.0294)
		(width 0.127)
		(layer "In5.Cu")
		(net "PWM_OUT_ZONE_D")
	)
	(segment
		(start 37.64534 -159.47136)
		(end 37.9476 -159.1691)
		(width 0.127)
		(layer "F.Cu")
		(net "PWM_OUT_ZONE_C")
	)
	(segment
		(start 37.64534 -159.97682)
		(end 37.64534 -159.47136)
		(width 0.127)
		(layer "F.Cu")
		(net "PWM_OUT_ZONE_C")
	)
	(via
		(at 37.64534 -159.97682)
		(size 0.508)
		(drill 0.254)
		(layers "F.Cu" "B.Cu")
		(net "PWM_OUT_ZONE_C")
	)
	(via
		(at 101.854 -171.831)
		(size 0.508)
		(drill 0.254)
		(layers "F.Cu" "B.Cu")
		(net "PWM_OUT_ZONE_C")
	)
	(segment
		(start 101.727 -130.9624)
		(end 100.270818 -129.506218)
		(width 0.127)
		(layer "In2.Cu")
		(net "PWM_OUT_ZONE_C")
	)
	(segment
		(start 100.4824 -135.556752)
		(end 101.727 -134.312152)
		(width 0.127)
		(layer "In2.Cu")
		(net "PWM_OUT_ZONE_C")
	)
	(segment
		(start 102.09911 -171.58589)
		(end 102.09911 -138.192256)
		(width 0.127)
		(layer "In2.Cu")
		(net "PWM_OUT_ZONE_C")
	)
	(segment
		(start 102.09911 -138.192256)
		(end 100.4824 -136.575546)
		(width 0.127)
		(layer "In2.Cu")
		(net "PWM_OUT_ZONE_C")
	)
	(segment
		(start 101.346 -127.620776)
		(end 101.346 -46.820328)
		(width 0.127)
		(layer "In2.Cu")
		(net "PWM_OUT_ZONE_C")
	)
	(segment
		(start 101.727 -134.312152)
		(end 101.727 -130.9624)
		(width 0.127)
		(layer "In2.Cu")
		(net "PWM_OUT_ZONE_C")
	)
	(segment
		(start 105.641648 -42.52468)
		(end 106.3752 -42.52468)
		(width 0.127)
		(layer "In2.Cu")
		(net "PWM_OUT_ZONE_C")
	)
	(segment
		(start 100.270818 -129.506218)
		(end 100.270818 -128.695958)
		(width 0.127)
		(layer "In2.Cu")
		(net "PWM_OUT_ZONE_C")
	)
	(segment
		(start 100.270818 -128.695958)
		(end 101.346 -127.620776)
		(width 0.127)
		(layer "In2.Cu")
		(net "PWM_OUT_ZONE_C")
	)
	(segment
		(start 101.346 -46.820328)
		(end 105.641648 -42.52468)
		(width 0.127)
		(layer "In2.Cu")
		(net "PWM_OUT_ZONE_C")
	)
	(segment
		(start 101.854 -171.831)
		(end 102.09911 -171.58589)
		(width 0.127)
		(layer "In2.Cu")
		(net "PWM_OUT_ZONE_C")
	)
	(segment
		(start 106.3752 -42.52468)
		(end 107.099862 -41.800018)
		(width 0.127)
		(layer "In2.Cu")
		(net "PWM_OUT_ZONE_C")
	)
	(segment
		(start 100.4824 -136.575546)
		(end 100.4824 -135.556752)
		(width 0.127)
		(layer "In2.Cu")
		(net "PWM_OUT_ZONE_C")
	)
	(segment
		(start 64.588644 -169.04462)
		(end 56.21782 -169.04462)
		(width 0.127)
		(layer "In5.Cu")
		(net "PWM_OUT_ZONE_C")
	)
	(segment
		(start 51.562 -165.8874)
		(end 47.126398 -165.8874)
		(width 0.127)
		(layer "In5.Cu")
		(net "PWM_OUT_ZONE_C")
	)
	(segment
		(start 66.346324 -170.8023)
		(end 64.588644 -169.04462)
		(width 0.127)
		(layer "In5.Cu")
		(net "PWM_OUT_ZONE_C")
	)
	(segment
		(start 45.170344 -163.931346)
		(end 42.38244 -163.931346)
		(width 0.127)
		(layer "In5.Cu")
		(net "PWM_OUT_ZONE_C")
	)
	(segment
		(start 53.9242 -166.751)
		(end 52.4256 -166.751)
		(width 0.127)
		(layer "In5.Cu")
		(net "PWM_OUT_ZONE_C")
	)
	(segment
		(start 78.27137 -174.27448)
		(end 76.53401 -172.53712)
		(width 0.127)
		(layer "In5.Cu")
		(net "PWM_OUT_ZONE_C")
	)
	(segment
		(start 56.21782 -169.04462)
		(end 53.9242 -166.751)
		(width 0.127)
		(layer "In5.Cu")
		(net "PWM_OUT_ZONE_C")
	)
	(segment
		(start 101.854 -171.831)
		(end 101.4857 -172.1993)
		(width 0.127)
		(layer "In5.Cu")
		(net "PWM_OUT_ZONE_C")
	)
	(segment
		(start 85.168994 -174.27448)
		(end 78.27137 -174.27448)
		(width 0.127)
		(layer "In5.Cu")
		(net "PWM_OUT_ZONE_C")
	)
	(segment
		(start 38.427914 -159.97682)
		(end 37.64534 -159.97682)
		(width 0.127)
		(layer "In5.Cu")
		(net "PWM_OUT_ZONE_C")
	)
	(segment
		(start 73.711308 -172.53712)
		(end 71.976488 -170.8023)
		(width 0.127)
		(layer "In5.Cu")
		(net "PWM_OUT_ZONE_C")
	)
	(segment
		(start 76.53401 -172.53712)
		(end 73.711308 -172.53712)
		(width 0.127)
		(layer "In5.Cu")
		(net "PWM_OUT_ZONE_C")
	)
	(segment
		(start 101.4857 -172.1993)
		(end 87.244174 -172.1993)
		(width 0.127)
		(layer "In5.Cu")
		(net "PWM_OUT_ZONE_C")
	)
	(segment
		(start 71.976488 -170.8023)
		(end 66.346324 -170.8023)
		(width 0.127)
		(layer "In5.Cu")
		(net "PWM_OUT_ZONE_C")
	)
	(segment
		(start 42.38244 -163.931346)
		(end 38.427914 -159.97682)
		(width 0.127)
		(layer "In5.Cu")
		(net "PWM_OUT_ZONE_C")
	)
	(segment
		(start 47.126398 -165.8874)
		(end 45.170344 -163.931346)
		(width 0.127)
		(layer "In5.Cu")
		(net "PWM_OUT_ZONE_C")
	)
	(segment
		(start 87.244174 -172.1993)
		(end 85.168994 -174.27448)
		(width 0.127)
		(layer "In5.Cu")
		(net "PWM_OUT_ZONE_C")
	)
	(segment
		(start 52.4256 -166.751)
		(end 51.562 -165.8874)
		(width 0.127)
		(layer "In5.Cu")
		(net "PWM_OUT_ZONE_C")
	)
	(segment
		(start 93.728286 -43.680126)
		(end 93.900244 -43.680126)
		(width 0.127)
		(layer "F.Cu")
		(net "PQ2_G")
	)
	(segment
		(start 95.220282 -46.000162)
		(end 95.220282 -45.00372)
		(width 0.127)
		(layer "F.Cu")
		(net "PQ2_G")
	)
	(segment
		(start 93.900244 -43.680126)
		(end 95.22206 -45.001942)
		(width 0.127)
		(layer "F.Cu")
		(net "PQ2_G")
	)
	(segment
		(start 95.220282 -45.00372)
		(end 95.22206 -45.001942)
		(width 0.127)
		(layer "F.Cu")
		(net "PQ2_G")
	)
	(via
		(at 95.22206 -45.001942)
		(size 0.6604)
		(drill 0.3302)
		(layers "F.Cu" "B.Cu")
		(net "PQ2_G")
	)
	(segment
		(start 90.579194 -50.426112)
		(end 90.569034 -50.415952)
		(width 0.127)
		(layer "F.Cu")
		(net "PQ2_D")
	)
	(segment
		(start 91.537028 -48.2981)
		(end 93.0021 -48.2981)
		(width 0.127)
		(layer "F.Cu")
		(net "PQ2_D")
	)
	(segment
		(start 93.0021 -48.2981)
		(end 93.0402 -48.26)
		(width 0.127)
		(layer "F.Cu")
		(net "PQ2_D")
	)
	(segment
		(start 93.0402 -48.26)
		(end 93.07195 -48.22825)
		(width 0.127)
		(layer "F.Cu")
		(net "PQ2_D")
	)
	(segment
		(start 92.375228 -45.216318)
		(end 91.823286 -44.664376)
		(width 0.127)
		(layer "F.Cu")
		(net "PQ2_D")
	)
	(segment
		(start 90.579194 -50.791872)
		(end 90.579194 -50.426112)
		(width 0.127)
		(layer "F.Cu")
		(net "PQ2_D")
	)
	(segment
		(start 93.07195 -47.730918)
		(end 92.375228 -47.034196)
		(width 0.127)
		(layer "F.Cu")
		(net "PQ2_D")
	)
	(segment
		(start 92.375228 -47.034196)
		(end 92.375228 -45.216318)
		(width 0.127)
		(layer "F.Cu")
		(net "PQ2_D")
	)
	(segment
		(start 91.1479 -48.2981)
		(end 91.537028 -48.2981)
		(width 0.127)
		(layer "F.Cu")
		(net "PQ2_D")
	)
	(segment
		(start 90.569034 -50.415952)
		(end 90.569034 -48.876966)
		(width 0.127)
		(layer "F.Cu")
		(net "PQ2_D")
	)
	(segment
		(start 93.07195 -48.22825)
		(end 93.07195 -47.730918)
		(width 0.127)
		(layer "F.Cu")
		(net "PQ2_D")
	)
	(segment
		(start 90.569034 -48.876966)
		(end 91.1479 -48.2981)
		(width 0.127)
		(layer "F.Cu")
		(net "PQ2_D")
	)
	(via
		(at 93.0402 -48.26)
		(size 0.6604)
		(drill 0.3302)
		(layers "F.Cu" "B.Cu")
		(net "PQ2_D")
	)
	(segment
		(start 37.1348 -139.827)
		(end 36.7792 -139.4714)
		(width 0.127)
		(layer "F.Cu")
		(net "PECI")
	)
	(segment
		(start 35.691318 -136.59993)
		(end 35.691318 -138.383518)
		(width 0.127)
		(layer "F.Cu")
		(net "PECI")
	)
	(segment
		(start 35.691318 -138.383518)
		(end 36.7792 -139.4714)
		(width 0.127)
		(layer "F.Cu")
		(net "PECI")
	)
	(segment
		(start 39.299896 -139.800076)
		(end 39.272972 -139.827)
		(width 0.127)
		(layer "F.Cu")
		(net "PECI")
	)
	(segment
		(start 39.272972 -139.827)
		(end 37.1348 -139.827)
		(width 0.127)
		(layer "F.Cu")
		(net "PECI")
	)
	(via
		(at 36.7792 -139.4714)
		(size 0.6604)
		(drill 0.3302)
		(layers "F.Cu" "B.Cu")
		(net "PECI")
	)
	(segment
		(start 59.958224 -151.60879)
		(end 60.24753 -151.898096)
		(width 0.127)
		(layer "F.Cu")
		(net "PD_USB2BVRES")
	)
	(segment
		(start 55.645558 -148.9456)
		(end 55.299864 -148.599906)
		(width 0.127)
		(layer "F.Cu")
		(net "PD_USB2BVRES")
	)
	(segment
		(start 57.295034 -148.9456)
		(end 55.645558 -148.9456)
		(width 0.127)
		(layer "F.Cu")
		(net "PD_USB2BVRES")
	)
	(segment
		(start 60.24753 -151.97963)
		(end 60.9219 -152.654)
		(width 0.127)
		(layer "F.Cu")
		(net "PD_USB2BVRES")
	)
	(segment
		(start 60.24753 -151.898096)
		(end 60.24753 -151.97963)
		(width 0.127)
		(layer "F.Cu")
		(net "PD_USB2BVRES")
	)
	(segment
		(start 59.958224 -151.60879)
		(end 57.295034 -148.9456)
		(width 0.127)
		(layer "F.Cu")
		(net "PD_USB2BVRES")
	)
	(via
		(at 59.958224 -151.60879)
		(size 0.6604)
		(drill 0.3302)
		(layers "F.Cu" "B.Cu")
		(net "PD_USB2BVRES")
	)
	(segment
		(start 61.5569 -150.3426)
		(end 63.369698 -150.3426)
		(width 0.127)
		(layer "F.Cu")
		(net "PD_USB2AVRES")
	)
	(segment
		(start 63.522098 -150.1902)
		(end 63.959232 -149.753066)
		(width 0.127)
		(layer "F.Cu")
		(net "PD_USB2AVRES")
	)
	(segment
		(start 57.617614 -147.45716)
		(end 55.642764 -147.45716)
		(width 0.127)
		(layer "F.Cu")
		(net "PD_USB2AVRES")
	)
	(segment
		(start 59.537854 -149.3774)
		(end 57.617614 -147.45716)
		(width 0.127)
		(layer "F.Cu")
		(net "PD_USB2AVRES")
	)
	(segment
		(start 61.0235 -149.8092)
		(end 60.5917 -149.3774)
		(width 0.127)
		(layer "F.Cu")
		(net "PD_USB2AVRES")
	)
	(segment
		(start 55.642764 -147.45716)
		(end 55.299864 -147.80006)
		(width 0.127)
		(layer "F.Cu")
		(net "PD_USB2AVRES")
	)
	(segment
		(start 63.959232 -149.753066)
		(end 64.772032 -149.753066)
		(width 0.127)
		(layer "F.Cu")
		(net "PD_USB2AVRES")
	)
	(segment
		(start 63.369698 -150.3426)
		(end 63.522098 -150.1902)
		(width 0.127)
		(layer "F.Cu")
		(net "PD_USB2AVRES")
	)
	(segment
		(start 61.0235 -149.8092)
		(end 61.5569 -150.3426)
		(width 0.127)
		(layer "F.Cu")
		(net "PD_USB2AVRES")
	)
	(segment
		(start 60.5917 -149.3774)
		(end 59.537854 -149.3774)
		(width 0.127)
		(layer "F.Cu")
		(net "PD_USB2AVRES")
	)
	(via
		(at 63.522098 -150.1902)
		(size 0.6604)
		(drill 0.3302)
		(layers "F.Cu" "B.Cu")
		(net "PD_USB2AVRES")
	)
	(via
		(at 89.549478 -172.691552)
		(size 0.6096)
		(drill 0.3048)
		(layers "F.Cu" "B.Cu")
		(net "PCIE_RST_R_N")
	)
	(segment
		(start 87.032846 -171.970446)
		(end 87.690706 -171.970446)
		(width 0.127)
		(layer "B.Cu")
		(net "PCIE_RST_R_N")
	)
	(segment
		(start 88.964516 -172.691552)
		(end 88.24341 -171.970446)
		(width 0.127)
		(layer "B.Cu")
		(net "PCIE_RST_R_N")
	)
	(segment
		(start 88.24341 -171.970446)
		(end 87.690706 -171.970446)
		(width 0.127)
		(layer "B.Cu")
		(net "PCIE_RST_R_N")
	)
	(segment
		(start 86.614 -170.434)
		(end 86.614 -171.5516)
		(width 0.127)
		(layer "B.Cu")
		(net "PCIE_RST_R_N")
	)
	(segment
		(start 90.84437 -172.13453)
		(end 90.1065 -172.13453)
		(width 0.127)
		(layer "B.Cu")
		(net "PCIE_RST_R_N")
	)
	(segment
		(start 87.028274 -170.019726)
		(end 86.614 -170.434)
		(width 0.127)
		(layer "B.Cu")
		(net "PCIE_RST_R_N")
	)
	(segment
		(start 86.614 -171.5516)
		(end 87.032846 -171.970446)
		(width 0.127)
		(layer "B.Cu")
		(net "PCIE_RST_R_N")
	)
	(segment
		(start 87.690706 -170.019726)
		(end 87.028274 -170.019726)
		(width 0.127)
		(layer "B.Cu")
		(net "PCIE_RST_R_N")
	)
	(segment
		(start 89.549478 -172.691552)
		(end 88.964516 -172.691552)
		(width 0.127)
		(layer "B.Cu")
		(net "PCIE_RST_R_N")
	)
	(segment
		(start 90.1065 -172.13453)
		(end 89.549478 -172.691552)
		(width 0.127)
		(layer "B.Cu")
		(net "PCIE_RST_R_N")
	)
	(segment
		(start 203.527914 -139.841732)
		(end 202.548744 -138.862562)
		(width 0.14605)
		(layer "F.Cu")
		(net "PCIE_IOM_TO_COMP_9_DP")
	)
	(segment
		(start 202.548744 -138.862562)
		(end 202.548744 -135.8138)
		(width 0.14605)
		(layer "F.Cu")
		(net "PCIE_IOM_TO_COMP_9_DP")
	)
	(segment
		(start 203.527914 -140.476224)
		(end 203.527914 -139.841732)
		(width 0.14605)
		(layer "F.Cu")
		(net "PCIE_IOM_TO_COMP_9_DP")
	)
	(segment
		(start 202.548744 -135.8138)
		(end 202.649836 -135.712708)
		(width 0.14605)
		(layer "F.Cu")
		(net "PCIE_IOM_TO_COMP_9_DP")
	)
	(segment
		(start 203.34478 -140.918692)
		(end 203.34478 -140.918438)
		(width 0.14605)
		(layer "F.Cu")
		(net "PCIE_IOM_TO_COMP_9_DP")
	)
	(segment
		(start 203.170536 -141.092936)
		(end 203.34478 -140.918692)
		(width 0.14605)
		(layer "F.Cu")
		(net "PCIE_IOM_TO_COMP_9_DP")
	)
	(segment
		(start 202.649836 -135.712708)
		(end 202.649836 -134.875016)
		(width 0.14605)
		(layer "F.Cu")
		(net "PCIE_IOM_TO_COMP_9_DP")
	)
	(segment
		(start 203.260198 -141.411198)
		(end 203.170536 -141.321536)
		(width 0.14605)
		(layer "F.Cu")
		(net "PCIE_IOM_TO_COMP_9_DP")
	)
	(arc
		(start 203.34478 -140.918438)
		(mid 203.480322 -140.715535)
		(end 203.527914 -140.476224)
		(width 0.14605)
		(layer "F.Cu")
		(net "PCIE_IOM_TO_COMP_9_DP")
	)
	(arc
		(start 203.170536 -141.321536)
		(mid 203.123191 -141.207236)
		(end 203.170536 -141.092936)
		(width 0.14605)
		(layer "F.Cu")
		(net "PCIE_IOM_TO_COMP_9_DP")
	)
	(segment
		(start 201.905362 -143.337788)
		(end 195.782184 -144.529048)
		(width 0.1397)
		(layer "In5.Cu")
		(net "PCIE_IOM_TO_COMP_9_DP")
	)
	(segment
		(start 150.1394 -37.650166)
		(end 149.036532 -35.951922)
		(width 0.1397)
		(layer "In5.Cu")
		(net "PCIE_IOM_TO_COMP_9_DP")
	)
	(segment
		(start 145.931636 -31.17088)
		(end 143.028162 -29.234892)
		(width 0.1397)
		(layer "In5.Cu")
		(net "PCIE_IOM_TO_COMP_9_DP")
	)
	(segment
		(start 139.499848 -37.181028)
		(end 139.499848 -36.800028)
		(width 0.1397)
		(layer "In5.Cu")
		(net "PCIE_IOM_TO_COMP_9_DP")
	)
	(segment
		(start 202.954636 -141.321536)
		(end 202.745086 -141.531086)
		(width 0.1397)
		(layer "In5.Cu")
		(net "PCIE_IOM_TO_COMP_9_DP")
	)
	(segment
		(start 202.30465 -142.939008)
		(end 201.905362 -143.337788)
		(width 0.1397)
		(layer "In5.Cu")
		(net "PCIE_IOM_TO_COMP_9_DP")
	)
	(segment
		(start 147.314158 -33.299908)
		(end 145.931636 -31.17088)
		(width 0.1397)
		(layer "In5.Cu")
		(net "PCIE_IOM_TO_COMP_9_DP")
	)
	(segment
		(start 148.14042 -34.898584)
		(end 147.912074 -34.547048)
		(width 0.1397)
		(layer "In5.Cu")
		(net "PCIE_IOM_TO_COMP_9_DP")
	)
	(segment
		(start 147.262088 -33.54578)
		(end 147.314158 -33.299908)
		(width 0.1397)
		(layer "In5.Cu")
		(net "PCIE_IOM_TO_COMP_9_DP")
	)
	(segment
		(start 147.964398 -34.301176)
		(end 147.736052 -33.94964)
		(width 0.1397)
		(layer "In5.Cu")
		(net "PCIE_IOM_TO_COMP_9_DP")
	)
	(segment
		(start 149.036532 -35.951922)
		(end 148.79066 -35.899852)
		(width 0.1397)
		(layer "In5.Cu")
		(net "PCIE_IOM_TO_COMP_9_DP")
	)
	(segment
		(start 148.562314 -35.548316)
		(end 148.614638 -35.302444)
		(width 0.1397)
		(layer "In5.Cu")
		(net "PCIE_IOM_TO_COMP_9_DP")
	)
	(segment
		(start 140.221462 -29.018738)
		(end 138.765026 -30.475174)
		(width 0.1397)
		(layer "In5.Cu")
		(net "PCIE_IOM_TO_COMP_9_DP")
	)
	(segment
		(start 157.05709 -83.991958)
		(end 158.52267 -77.094334)
		(width 0.1397)
		(layer "In5.Cu")
		(net "PCIE_IOM_TO_COMP_9_DP")
	)
	(segment
		(start 148.79066 -35.899852)
		(end 148.562314 -35.548316)
		(width 0.1397)
		(layer "In5.Cu")
		(net "PCIE_IOM_TO_COMP_9_DP")
	)
	(segment
		(start 163.467288 -144.036288)
		(end 163.403788 -144.02308)
		(width 0.1397)
		(layer "In5.Cu")
		(net "PCIE_IOM_TO_COMP_9_DP")
	)
	(segment
		(start 148.386292 -34.950908)
		(end 148.14042 -34.898584)
		(width 0.1397)
		(layer "In5.Cu")
		(net "PCIE_IOM_TO_COMP_9_DP")
	)
	(segment
		(start 203.260198 -141.411198)
		(end 203.170536 -141.321536)
		(width 0.1397)
		(layer "In5.Cu")
		(net "PCIE_IOM_TO_COMP_9_DP")
	)
	(segment
		(start 159.639508 -141.484096)
		(end 157.9626 -138.99769)
		(width 0.1397)
		(layer "In5.Cu")
		(net "PCIE_IOM_TO_COMP_9_DP")
	)
	(segment
		(start 147.49018 -33.897316)
		(end 147.262088 -33.54578)
		(width 0.1397)
		(layer "In5.Cu")
		(net "PCIE_IOM_TO_COMP_9_DP")
	)
	(segment
		(start 202.68692 -141.671548)
		(end 202.68692 -142.089124)
		(width 0.1397)
		(layer "In5.Cu")
		(net "PCIE_IOM_TO_COMP_9_DP")
	)
	(segment
		(start 192.78219 -143.946372)
		(end 177.628296 -146.976592)
		(width 0.1397)
		(layer "In5.Cu")
		(net "PCIE_IOM_TO_COMP_9_DP")
	)
	(segment
		(start 195.782184 -144.529048)
		(end 192.78219 -143.946372)
		(width 0.1397)
		(layer "In5.Cu")
		(net "PCIE_IOM_TO_COMP_9_DP")
	)
	(segment
		(start 158.52267 -77.094334)
		(end 150.1394 -37.650166)
		(width 0.1397)
		(layer "In5.Cu")
		(net "PCIE_IOM_TO_COMP_9_DP")
	)
	(segment
		(start 157.9626 -138.99769)
		(end 156.499306 -131.470908)
		(width 0.1397)
		(layer "In5.Cu")
		(net "PCIE_IOM_TO_COMP_9_DP")
	)
	(segment
		(start 177.628296 -146.976592)
		(end 163.467542 -144.036288)
		(width 0.1397)
		(layer "In5.Cu")
		(net "PCIE_IOM_TO_COMP_9_DP")
	)
	(segment
		(start 163.403788 -144.02308)
		(end 159.639508 -141.484096)
		(width 0.1397)
		(layer "In5.Cu")
		(net "PCIE_IOM_TO_COMP_9_DP")
	)
	(segment
		(start 156.499306 -131.470908)
		(end 161.614866 -105.438448)
		(width 0.1397)
		(layer "In5.Cu")
		(net "PCIE_IOM_TO_COMP_9_DP")
	)
	(segment
		(start 138.765026 -30.475174)
		(end 138.765026 -37.102288)
		(width 0.1397)
		(layer "In5.Cu")
		(net "PCIE_IOM_TO_COMP_9_DP")
	)
	(segment
		(start 148.614638 -35.302444)
		(end 148.386292 -34.950908)
		(width 0.1397)
		(layer "In5.Cu")
		(net "PCIE_IOM_TO_COMP_9_DP")
	)
	(segment
		(start 147.912074 -34.547048)
		(end 147.964398 -34.301176)
		(width 0.1397)
		(layer "In5.Cu")
		(net "PCIE_IOM_TO_COMP_9_DP")
	)
	(segment
		(start 161.614866 -105.438448)
		(end 157.05709 -83.991958)
		(width 0.1397)
		(layer "In5.Cu")
		(net "PCIE_IOM_TO_COMP_9_DP")
	)
	(segment
		(start 143.028162 -29.234892)
		(end 141.947646 -29.018738)
		(width 0.1397)
		(layer "In5.Cu")
		(net "PCIE_IOM_TO_COMP_9_DP")
	)
	(segment
		(start 138.99769 -37.334952)
		(end 139.345924 -37.334952)
		(width 0.1397)
		(layer "In5.Cu")
		(net "PCIE_IOM_TO_COMP_9_DP")
	)
	(segment
		(start 147.736052 -33.94964)
		(end 147.49018 -33.897316)
		(width 0.1397)
		(layer "In5.Cu")
		(net "PCIE_IOM_TO_COMP_9_DP")
	)
	(segment
		(start 141.947646 -29.018738)
		(end 140.221462 -29.018738)
		(width 0.1397)
		(layer "In5.Cu")
		(net "PCIE_IOM_TO_COMP_9_DP")
	)
	(segment
		(start 163.467542 -144.036288)
		(end 163.467288 -144.036288)
		(width 0.1397)
		(layer "In5.Cu")
		(net "PCIE_IOM_TO_COMP_9_DP")
	)
	(arc
		(start 202.68692 -142.089124)
		(mid 202.586954 -142.555073)
		(end 202.30465 -142.939008)
		(width 0.1397)
		(layer "In5.Cu")
		(net "PCIE_IOM_TO_COMP_9_DP")
	)
	(arc
		(start 138.765026 -37.102288)
		(mid 138.833172 -37.266806)
		(end 138.99769 -37.334952)
		(width 0.1397)
		(layer "In5.Cu")
		(net "PCIE_IOM_TO_COMP_9_DP")
	)
	(arc
		(start 202.745086 -141.531086)
		(mid 202.702026 -141.595531)
		(end 202.68692 -141.671548)
		(width 0.1397)
		(layer "In5.Cu")
		(net "PCIE_IOM_TO_COMP_9_DP")
	)
	(arc
		(start 203.170536 -141.321536)
		(mid 203.062586 -141.276822)
		(end 202.954636 -141.321536)
		(width 0.1397)
		(layer "In5.Cu")
		(net "PCIE_IOM_TO_COMP_9_DP")
	)
	(arc
		(start 139.345924 -37.334952)
		(mid 139.454765 -37.289869)
		(end 139.499848 -37.181028)
		(width 0.1397)
		(layer "In5.Cu")
		(net "PCIE_IOM_TO_COMP_9_DP")
	)
	(segment
		(start 202.631802 -140.782802)
		(end 202.721464 -140.872464)
		(width 0.14605)
		(layer "F.Cu")
		(net "PCIE_IOM_TO_COMP_9_DN")
	)
	(segment
		(start 202.237594 -135.80745)
		(end 202.149964 -135.71982)
		(width 0.14605)
		(layer "F.Cu")
		(net "PCIE_IOM_TO_COMP_9_DN")
	)
	(segment
		(start 203.216764 -139.970764)
		(end 202.237594 -138.991594)
		(width 0.14605)
		(layer "F.Cu")
		(net "PCIE_IOM_TO_COMP_9_DN")
	)
	(segment
		(start 202.950572 -140.872464)
		(end 203.124562 -140.698474)
		(width 0.14605)
		(layer "F.Cu")
		(net "PCIE_IOM_TO_COMP_9_DN")
	)
	(segment
		(start 203.216764 -140.47597)
		(end 203.216764 -139.970764)
		(width 0.14605)
		(layer "F.Cu")
		(net "PCIE_IOM_TO_COMP_9_DN")
	)
	(segment
		(start 202.237594 -138.991594)
		(end 202.237594 -135.80745)
		(width 0.14605)
		(layer "F.Cu")
		(net "PCIE_IOM_TO_COMP_9_DN")
	)
	(segment
		(start 202.149964 -135.71982)
		(end 202.149964 -134.875016)
		(width 0.14605)
		(layer "F.Cu")
		(net "PCIE_IOM_TO_COMP_9_DN")
	)
	(arc
		(start 203.124562 -140.698474)
		(mid 203.192773 -140.596388)
		(end 203.216764 -140.47597)
		(width 0.14605)
		(layer "F.Cu")
		(net "PCIE_IOM_TO_COMP_9_DN")
	)
	(arc
		(start 202.721464 -140.872464)
		(mid 202.836018 -140.919914)
		(end 202.950572 -140.872464)
		(width 0.14605)
		(layer "F.Cu")
		(net "PCIE_IOM_TO_COMP_9_DN")
	)
	(segment
		(start 140.084556 -28.688538)
		(end 138.434826 -30.338268)
		(width 0.1397)
		(layer "In5.Cu")
		(net "PCIE_IOM_TO_COMP_9_DN")
	)
	(segment
		(start 202.631802 -140.782802)
		(end 202.721464 -140.872464)
		(width 0.1397)
		(layer "In5.Cu")
		(net "PCIE_IOM_TO_COMP_9_DN")
	)
	(segment
		(start 159.877506 -141.246098)
		(end 158.274004 -138.868658)
		(width 0.1397)
		(layer "In5.Cu")
		(net "PCIE_IOM_TO_COMP_9_DN")
	)
	(segment
		(start 202.078844 -142.697708)
		(end 201.74331 -143.032734)
		(width 0.1397)
		(layer "In5.Cu")
		(net "PCIE_IOM_TO_COMP_9_DN")
	)
	(segment
		(start 192.781174 -143.609568)
		(end 177.629566 -146.639534)
		(width 0.1397)
		(layer "In5.Cu")
		(net "PCIE_IOM_TO_COMP_9_DN")
	)
	(segment
		(start 163.534598 -143.712946)
		(end 159.877506 -141.246098)
		(width 0.1397)
		(layer "In5.Cu")
		(net "PCIE_IOM_TO_COMP_9_DN")
	)
	(segment
		(start 158.274004 -138.868658)
		(end 156.835856 -131.471162)
		(width 0.1397)
		(layer "In5.Cu")
		(net "PCIE_IOM_TO_COMP_9_DN")
	)
	(segment
		(start 139.499848 -37.819076)
		(end 139.499848 -38.200076)
		(width 0.1397)
		(layer "In5.Cu")
		(net "PCIE_IOM_TO_COMP_9_DN")
	)
	(segment
		(start 202.721464 -141.087348)
		(end 202.511406 -141.297406)
		(width 0.1397)
		(layer "In5.Cu")
		(net "PCIE_IOM_TO_COMP_9_DN")
	)
	(segment
		(start 138.99769 -37.665152)
		(end 139.345924 -37.665152)
		(width 0.1397)
		(layer "In5.Cu")
		(net "PCIE_IOM_TO_COMP_9_DN")
	)
	(segment
		(start 195.782184 -144.192498)
		(end 192.781174 -143.609568)
		(width 0.1397)
		(layer "In5.Cu")
		(net "PCIE_IOM_TO_COMP_9_DN")
	)
	(segment
		(start 157.39491 -83.991958)
		(end 158.86049 -77.094334)
		(width 0.1397)
		(layer "In5.Cu")
		(net "PCIE_IOM_TO_COMP_9_DN")
	)
	(segment
		(start 202.35672 -141.671802)
		(end 202.35672 -142.089124)
		(width 0.1397)
		(layer "In5.Cu")
		(net "PCIE_IOM_TO_COMP_9_DN")
	)
	(segment
		(start 146.171666 -30.933644)
		(end 143.15694 -28.923742)
		(width 0.1397)
		(layer "In5.Cu")
		(net "PCIE_IOM_TO_COMP_9_DN")
	)
	(segment
		(start 161.951924 -105.435908)
		(end 157.39491 -83.991958)
		(width 0.1397)
		(layer "In5.Cu")
		(net "PCIE_IOM_TO_COMP_9_DN")
	)
	(segment
		(start 201.74331 -143.032734)
		(end 195.782184 -144.192498)
		(width 0.1397)
		(layer "In5.Cu")
		(net "PCIE_IOM_TO_COMP_9_DN")
	)
	(segment
		(start 143.15694 -28.923742)
		(end 141.980412 -28.688538)
		(width 0.1397)
		(layer "In5.Cu")
		(net "PCIE_IOM_TO_COMP_9_DN")
	)
	(segment
		(start 138.434826 -30.338268)
		(end 138.434826 -37.102288)
		(width 0.1397)
		(layer "In5.Cu")
		(net "PCIE_IOM_TO_COMP_9_DN")
	)
	(segment
		(start 177.629566 -146.639534)
		(end 163.534598 -143.712946)
		(width 0.1397)
		(layer "In5.Cu")
		(net "PCIE_IOM_TO_COMP_9_DN")
	)
	(segment
		(start 156.835856 -131.471162)
		(end 161.951924 -105.435908)
		(width 0.1397)
		(layer "In5.Cu")
		(net "PCIE_IOM_TO_COMP_9_DN")
	)
	(segment
		(start 158.86049 -77.094334)
		(end 150.449788 -37.521642)
		(width 0.1397)
		(layer "In5.Cu")
		(net "PCIE_IOM_TO_COMP_9_DN")
	)
	(segment
		(start 150.449788 -37.521642)
		(end 146.171666 -30.933644)
		(width 0.1397)
		(layer "In5.Cu")
		(net "PCIE_IOM_TO_COMP_9_DN")
	)
	(segment
		(start 141.980412 -28.688538)
		(end 140.084556 -28.688538)
		(width 0.1397)
		(layer "In5.Cu")
		(net "PCIE_IOM_TO_COMP_9_DN")
	)
	(arc
		(start 202.721464 -140.872464)
		(mid 202.765968 -140.979906)
		(end 202.721464 -141.087348)
		(width 0.1397)
		(layer "In5.Cu")
		(net "PCIE_IOM_TO_COMP_9_DN")
	)
	(arc
		(start 202.511406 -141.297406)
		(mid 202.396796 -141.46921)
		(end 202.35672 -141.671802)
		(width 0.1397)
		(layer "In5.Cu")
		(net "PCIE_IOM_TO_COMP_9_DN")
	)
	(arc
		(start 139.345924 -37.665152)
		(mid 139.454765 -37.710235)
		(end 139.499848 -37.819076)
		(width 0.1397)
		(layer "In5.Cu")
		(net "PCIE_IOM_TO_COMP_9_DN")
	)
	(arc
		(start 138.434826 -37.102288)
		(mid 138.599685 -37.500293)
		(end 138.99769 -37.665152)
		(width 0.1397)
		(layer "In5.Cu")
		(net "PCIE_IOM_TO_COMP_9_DN")
	)
	(arc
		(start 202.35672 -142.089124)
		(mid 202.283969 -142.423639)
		(end 202.078844 -142.697708)
		(width 0.1397)
		(layer "In5.Cu")
		(net "PCIE_IOM_TO_COMP_9_DN")
	)
	(segment
		(start 205.64983 -135.712708)
		(end 205.64983 -134.875016)
		(width 0.14605)
		(layer "F.Cu")
		(net "PCIE_IOM_TO_COMP_8_DP")
	)
	(segment
		(start 207.266794 -138.448542)
		(end 205.59141 -136.77392)
		(width 0.14605)
		(layer "F.Cu")
		(net "PCIE_IOM_TO_COMP_8_DP")
	)
	(segment
		(start 207.071468 -139.478258)
		(end 207.266794 -139.283186)
		(width 0.14605)
		(layer "F.Cu")
		(net "PCIE_IOM_TO_COMP_8_DP")
	)
	(segment
		(start 205.548738 -135.8138)
		(end 205.64983 -135.712708)
		(width 0.14605)
		(layer "F.Cu")
		(net "PCIE_IOM_TO_COMP_8_DP")
	)
	(segment
		(start 205.548738 -136.731248)
		(end 205.548738 -135.8138)
		(width 0.14605)
		(layer "F.Cu")
		(net "PCIE_IOM_TO_COMP_8_DP")
	)
	(segment
		(start 207.070198 -139.887198)
		(end 206.980536 -139.797536)
		(width 0.14605)
		(layer "F.Cu")
		(net "PCIE_IOM_TO_COMP_8_DP")
	)
	(segment
		(start 205.590394 -136.77265)
		(end 205.548738 -136.731248)
		(width 0.14605)
		(layer "F.Cu")
		(net "PCIE_IOM_TO_COMP_8_DP")
	)
	(segment
		(start 206.980536 -139.56919)
		(end 207.071468 -139.478258)
		(width 0.14605)
		(layer "F.Cu")
		(net "PCIE_IOM_TO_COMP_8_DP")
	)
	(arc
		(start 205.59141 -136.77392)
		(mid 205.5909 -136.773286)
		(end 205.590394 -136.77265)
		(width 0.14605)
		(layer "F.Cu")
		(net "PCIE_IOM_TO_COMP_8_DP")
	)
	(arc
		(start 206.980536 -139.797536)
		(mid 206.933371 -139.6834)
		(end 206.980536 -139.56919)
		(width 0.14605)
		(layer "F.Cu")
		(net "PCIE_IOM_TO_COMP_8_DP")
	)
	(arc
		(start 207.266794 -139.283186)
		(mid 207.439654 -138.865864)
		(end 207.266794 -138.448542)
		(width 0.14605)
		(layer "F.Cu")
		(net "PCIE_IOM_TO_COMP_8_DP")
	)
	(segment
		(start 162.828224 -144.983454)
		(end 158.81731 -142.2781)
		(width 0.1397)
		(layer "In5.Cu")
		(net "PCIE_IOM_TO_COMP_8_DP")
	)
	(segment
		(start 205.904846 -143.8783)
		(end 201.127614 -144.833594)
		(width 0.1397)
		(layer "In5.Cu")
		(net "PCIE_IOM_TO_COMP_8_DP")
	)
	(segment
		(start 145.480024 -33.300924)
		(end 144.809464 -32.267906)
		(width 0.1397)
		(layer "In5.Cu")
		(net "PCIE_IOM_TO_COMP_8_DP")
	)
	(segment
		(start 146.306032 -34.8996)
		(end 146.077686 -34.548064)
		(width 0.1397)
		(layer "In5.Cu")
		(net "PCIE_IOM_TO_COMP_8_DP")
	)
	(segment
		(start 147.20189 -35.953192)
		(end 146.956018 -35.900868)
		(width 0.1397)
		(layer "In5.Cu")
		(net "PCIE_IOM_TO_COMP_8_DP")
	)
	(segment
		(start 148.468588 -37.90442)
		(end 147.20189 -35.953192)
		(width 0.1397)
		(layer "In5.Cu")
		(net "PCIE_IOM_TO_COMP_8_DP")
	)
	(segment
		(start 207.33639 -142.632684)
		(end 206.987902 -143.155924)
		(width 0.1397)
		(layer "In5.Cu")
		(net "PCIE_IOM_TO_COMP_8_DP")
	)
	(segment
		(start 140.784326 -36.135056)
		(end 141.146022 -36.135056)
		(width 0.1397)
		(layer "In5.Cu")
		(net "PCIE_IOM_TO_COMP_8_DP")
	)
	(segment
		(start 146.551904 -34.951924)
		(end 146.306032 -34.8996)
		(width 0.1397)
		(layer "In5.Cu")
		(net "PCIE_IOM_TO_COMP_8_DP")
	)
	(segment
		(start 145.655792 -33.898332)
		(end 145.4277 -33.546796)
		(width 0.1397)
		(layer "In5.Cu")
		(net "PCIE_IOM_TO_COMP_8_DP")
	)
	(segment
		(start 141.299946 -35.981132)
		(end 141.299946 -35.600132)
		(width 0.1397)
		(layer "In5.Cu")
		(net "PCIE_IOM_TO_COMP_8_DP")
	)
	(segment
		(start 145.901918 -33.950656)
		(end 145.655792 -33.898332)
		(width 0.1397)
		(layer "In5.Cu")
		(net "PCIE_IOM_TO_COMP_8_DP")
	)
	(segment
		(start 140.97 -30.1244)
		(end 140.565124 -30.529276)
		(width 0.1397)
		(layer "In5.Cu")
		(net "PCIE_IOM_TO_COMP_8_DP")
	)
	(segment
		(start 206.480156 -140.607542)
		(end 207.33639 -141.463776)
		(width 0.1397)
		(layer "In5.Cu")
		(net "PCIE_IOM_TO_COMP_8_DP")
	)
	(segment
		(start 144.21231 -31.670752)
		(end 142.139162 -30.288738)
		(width 0.1397)
		(layer "In5.Cu")
		(net "PCIE_IOM_TO_COMP_8_DP")
	)
	(segment
		(start 160.223454 -106.023156)
		(end 155.399994 -83.331558)
		(width 0.1397)
		(layer "In5.Cu")
		(net "PCIE_IOM_TO_COMP_8_DP")
	)
	(segment
		(start 207.070198 -139.887198)
		(end 206.980536 -139.797536)
		(width 0.1397)
		(layer "In5.Cu")
		(net "PCIE_IOM_TO_COMP_8_DP")
	)
	(segment
		(start 207.33639 -141.463776)
		(end 207.33639 -142.632684)
		(width 0.1397)
		(layer "In5.Cu")
		(net "PCIE_IOM_TO_COMP_8_DP")
	)
	(segment
		(start 199.575166 -145.143982)
		(end 198.021956 -145.454624)
		(width 0.1397)
		(layer "In5.Cu")
		(net "PCIE_IOM_TO_COMP_8_DP")
	)
	(segment
		(start 146.956018 -35.900868)
		(end 146.727672 -35.549332)
		(width 0.1397)
		(layer "In5.Cu")
		(net "PCIE_IOM_TO_COMP_8_DP")
	)
	(segment
		(start 156.761942 -76.921868)
		(end 148.468588 -37.90442)
		(width 0.1397)
		(layer "In5.Cu")
		(net "PCIE_IOM_TO_COMP_8_DP")
	)
	(segment
		(start 144.809464 -32.267906)
		(end 144.21231 -31.670752)
		(width 0.1397)
		(layer "In5.Cu")
		(net "PCIE_IOM_TO_COMP_8_DP")
	)
	(segment
		(start 201.127614 -144.833594)
		(end 199.575166 -145.143982)
		(width 0.1397)
		(layer "In5.Cu")
		(net "PCIE_IOM_TO_COMP_8_DP")
	)
	(segment
		(start 177.500026 -147.835874)
		(end 162.828224 -144.983454)
		(width 0.1397)
		(layer "In5.Cu")
		(net "PCIE_IOM_TO_COMP_8_DP")
	)
	(segment
		(start 155.399994 -83.331558)
		(end 156.761942 -76.921868)
		(width 0.1397)
		(layer "In5.Cu")
		(net "PCIE_IOM_TO_COMP_8_DP")
	)
	(segment
		(start 206.987902 -143.155924)
		(end 205.904846 -143.8783)
		(width 0.1397)
		(layer "In5.Cu")
		(net "PCIE_IOM_TO_COMP_8_DP")
	)
	(segment
		(start 141.317218 -30.1244)
		(end 140.97 -30.1244)
		(width 0.1397)
		(layer "In5.Cu")
		(net "PCIE_IOM_TO_COMP_8_DP")
	)
	(segment
		(start 196.678296 -145.723356)
		(end 192.523364 -144.915636)
		(width 0.1397)
		(layer "In5.Cu")
		(net "PCIE_IOM_TO_COMP_8_DP")
	)
	(segment
		(start 146.13001 -34.302192)
		(end 145.901918 -33.950656)
		(width 0.1397)
		(layer "In5.Cu")
		(net "PCIE_IOM_TO_COMP_8_DP")
	)
	(segment
		(start 198.021956 -145.454624)
		(end 197.108064 -145.637504)
		(width 0.1397)
		(layer "In5.Cu")
		(net "PCIE_IOM_TO_COMP_8_DP")
	)
	(segment
		(start 156.895038 -139.428474)
		(end 155.28544 -131.146804)
		(width 0.1397)
		(layer "In5.Cu")
		(net "PCIE_IOM_TO_COMP_8_DP")
	)
	(segment
		(start 140.565124 -30.529276)
		(end 140.565124 -35.915854)
		(width 0.1397)
		(layer "In5.Cu")
		(net "PCIE_IOM_TO_COMP_8_DP")
	)
	(segment
		(start 145.4277 -33.546796)
		(end 145.480024 -33.300924)
		(width 0.1397)
		(layer "In5.Cu")
		(net "PCIE_IOM_TO_COMP_8_DP")
	)
	(segment
		(start 146.077686 -34.548064)
		(end 146.13001 -34.302192)
		(width 0.1397)
		(layer "In5.Cu")
		(net "PCIE_IOM_TO_COMP_8_DP")
	)
	(segment
		(start 197.108064 -145.637504)
		(end 196.678296 -145.723356)
		(width 0.1397)
		(layer "In5.Cu")
		(net "PCIE_IOM_TO_COMP_8_DP")
	)
	(segment
		(start 192.523364 -144.915636)
		(end 177.500026 -147.835874)
		(width 0.1397)
		(layer "In5.Cu")
		(net "PCIE_IOM_TO_COMP_8_DP")
	)
	(segment
		(start 155.28544 -131.146804)
		(end 160.223454 -106.023156)
		(width 0.1397)
		(layer "In5.Cu")
		(net "PCIE_IOM_TO_COMP_8_DP")
	)
	(segment
		(start 206.764636 -139.797536)
		(end 206.480156 -140.082016)
		(width 0.1397)
		(layer "In5.Cu")
		(net "PCIE_IOM_TO_COMP_8_DP")
	)
	(segment
		(start 158.81731 -142.2781)
		(end 156.895038 -139.428474)
		(width 0.1397)
		(layer "In5.Cu")
		(net "PCIE_IOM_TO_COMP_8_DP")
	)
	(segment
		(start 146.727672 -35.549332)
		(end 146.779996 -35.30346)
		(width 0.1397)
		(layer "In5.Cu")
		(net "PCIE_IOM_TO_COMP_8_DP")
	)
	(segment
		(start 142.139162 -30.288738)
		(end 141.317218 -30.1244)
		(width 0.1397)
		(layer "In5.Cu")
		(net "PCIE_IOM_TO_COMP_8_DP")
	)
	(segment
		(start 146.779996 -35.30346)
		(end 146.551904 -34.951924)
		(width 0.1397)
		(layer "In5.Cu")
		(net "PCIE_IOM_TO_COMP_8_DP")
	)
	(arc
		(start 140.565124 -35.915854)
		(mid 140.629327 -36.070853)
		(end 140.784326 -36.135056)
		(width 0.1397)
		(layer "In5.Cu")
		(net "PCIE_IOM_TO_COMP_8_DP")
	)
	(arc
		(start 206.480156 -140.082016)
		(mid 206.371263 -140.344816)
		(end 206.480156 -140.607542)
		(width 0.1397)
		(layer "In5.Cu")
		(net "PCIE_IOM_TO_COMP_8_DP")
	)
	(arc
		(start 141.146022 -36.135056)
		(mid 141.254863 -36.089973)
		(end 141.299946 -35.981132)
		(width 0.1397)
		(layer "In5.Cu")
		(net "PCIE_IOM_TO_COMP_8_DP")
	)
	(arc
		(start 206.980536 -139.797536)
		(mid 206.872586 -139.752822)
		(end 206.764636 -139.797536)
		(width 0.1397)
		(layer "In5.Cu")
		(net "PCIE_IOM_TO_COMP_8_DP")
	)
	(segment
		(start 207.046576 -138.66876)
		(end 205.237588 -136.86028)
		(width 0.14605)
		(layer "F.Cu")
		(net "PCIE_IOM_TO_COMP_8_DN")
	)
	(segment
		(start 205.237588 -136.86028)
		(end 205.237588 -135.80745)
		(width 0.14605)
		(layer "F.Cu")
		(net "PCIE_IOM_TO_COMP_8_DN")
	)
	(segment
		(start 206.441802 -139.258802)
		(end 206.531464 -139.348464)
		(width 0.14605)
		(layer "F.Cu")
		(net "PCIE_IOM_TO_COMP_8_DN")
	)
	(segment
		(start 206.760572 -139.348464)
		(end 206.760572 -139.348718)
		(width 0.14605)
		(layer "F.Cu")
		(net "PCIE_IOM_TO_COMP_8_DN")
	)
	(segment
		(start 205.237588 -135.80745)
		(end 205.149958 -135.71982)
		(width 0.14605)
		(layer "F.Cu")
		(net "PCIE_IOM_TO_COMP_8_DN")
	)
	(segment
		(start 205.149958 -135.71982)
		(end 205.149958 -134.875016)
		(width 0.14605)
		(layer "F.Cu")
		(net "PCIE_IOM_TO_COMP_8_DN")
	)
	(segment
		(start 206.760572 -139.348718)
		(end 207.046576 -139.062968)
		(width 0.14605)
		(layer "F.Cu")
		(net "PCIE_IOM_TO_COMP_8_DN")
	)
	(arc
		(start 207.046576 -139.062968)
		(mid 207.128219 -138.865864)
		(end 207.046576 -138.66876)
		(width 0.14605)
		(layer "F.Cu")
		(net "PCIE_IOM_TO_COMP_8_DN")
	)
	(arc
		(start 206.531464 -139.348464)
		(mid 206.646018 -139.395914)
		(end 206.760572 -139.348464)
		(width 0.14605)
		(layer "F.Cu")
		(net "PCIE_IOM_TO_COMP_8_DN")
	)
	(segment
		(start 157.099762 -76.921868)
		(end 148.778976 -37.775896)
		(width 0.1397)
		(layer "In5.Cu")
		(net "PCIE_IOM_TO_COMP_8_DN")
	)
	(segment
		(start 140.833094 -29.7942)
		(end 140.234924 -30.39237)
		(width 0.1397)
		(layer "In5.Cu")
		(net "PCIE_IOM_TO_COMP_8_DN")
	)
	(segment
		(start 206.531464 -139.563348)
		(end 206.246476 -139.848336)
		(width 0.1397)
		(layer "In5.Cu")
		(net "PCIE_IOM_TO_COMP_8_DN")
	)
	(segment
		(start 205.775814 -143.56715)
		(end 201.062844 -144.509744)
		(width 0.1397)
		(layer "In5.Cu")
		(net "PCIE_IOM_TO_COMP_8_DN")
	)
	(segment
		(start 207.00619 -142.532608)
		(end 206.74965 -142.917672)
		(width 0.1397)
		(layer "In5.Cu")
		(net "PCIE_IOM_TO_COMP_8_DN")
	)
	(segment
		(start 177.500026 -147.499324)
		(end 162.957256 -144.67205)
		(width 0.1397)
		(layer "In5.Cu")
		(net "PCIE_IOM_TO_COMP_8_DN")
	)
	(segment
		(start 196.67728 -145.386552)
		(end 192.523364 -144.579086)
		(width 0.1397)
		(layer "In5.Cu")
		(net "PCIE_IOM_TO_COMP_8_DN")
	)
	(segment
		(start 148.778976 -37.775896)
		(end 145.067528 -32.058864)
		(width 0.1397)
		(layer "In5.Cu")
		(net "PCIE_IOM_TO_COMP_8_DN")
	)
	(segment
		(start 207.00619 -141.600682)
		(end 207.00619 -142.532608)
		(width 0.1397)
		(layer "In5.Cu")
		(net "PCIE_IOM_TO_COMP_8_DN")
	)
	(segment
		(start 140.234924 -30.39237)
		(end 140.234924 -35.915854)
		(width 0.1397)
		(layer "In5.Cu")
		(net "PCIE_IOM_TO_COMP_8_DN")
	)
	(segment
		(start 155.737814 -83.331558)
		(end 157.099762 -76.921868)
		(width 0.1397)
		(layer "In5.Cu")
		(net "PCIE_IOM_TO_COMP_8_DN")
	)
	(segment
		(start 206.246476 -140.840968)
		(end 207.00619 -141.600682)
		(width 0.1397)
		(layer "In5.Cu")
		(net "PCIE_IOM_TO_COMP_8_DN")
	)
	(segment
		(start 196.678042 -145.386552)
		(end 196.67728 -145.386552)
		(width 0.1397)
		(layer "In5.Cu")
		(net "PCIE_IOM_TO_COMP_8_DN")
	)
	(segment
		(start 141.349984 -29.7942)
		(end 140.833094 -29.7942)
		(width 0.1397)
		(layer "In5.Cu")
		(net "PCIE_IOM_TO_COMP_8_DN")
	)
	(segment
		(start 192.523364 -144.579086)
		(end 177.500026 -147.499324)
		(width 0.1397)
		(layer "In5.Cu")
		(net "PCIE_IOM_TO_COMP_8_DN")
	)
	(segment
		(start 144.42186 -31.413196)
		(end 142.26794 -29.977588)
		(width 0.1397)
		(layer "In5.Cu")
		(net "PCIE_IOM_TO_COMP_8_DN")
	)
	(segment
		(start 140.784326 -36.465256)
		(end 141.146022 -36.465256)
		(width 0.1397)
		(layer "In5.Cu")
		(net "PCIE_IOM_TO_COMP_8_DN")
	)
	(segment
		(start 157.206442 -139.299442)
		(end 155.62199 -131.147058)
		(width 0.1397)
		(layer "In5.Cu")
		(net "PCIE_IOM_TO_COMP_8_DN")
	)
	(segment
		(start 155.62199 -131.147058)
		(end 160.560512 -106.020616)
		(width 0.1397)
		(layer "In5.Cu")
		(net "PCIE_IOM_TO_COMP_8_DN")
	)
	(segment
		(start 162.957256 -144.67205)
		(end 159.055308 -142.040102)
		(width 0.1397)
		(layer "In5.Cu")
		(net "PCIE_IOM_TO_COMP_8_DN")
	)
	(segment
		(start 201.062844 -144.509744)
		(end 196.678042 -145.386552)
		(width 0.1397)
		(layer "In5.Cu")
		(net "PCIE_IOM_TO_COMP_8_DN")
	)
	(segment
		(start 141.299946 -36.61918)
		(end 141.299946 -37.00018)
		(width 0.1397)
		(layer "In5.Cu")
		(net "PCIE_IOM_TO_COMP_8_DN")
	)
	(segment
		(start 145.067528 -32.058864)
		(end 144.42186 -31.413196)
		(width 0.1397)
		(layer "In5.Cu")
		(net "PCIE_IOM_TO_COMP_8_DN")
	)
	(segment
		(start 206.441802 -139.258802)
		(end 206.531464 -139.348464)
		(width 0.1397)
		(layer "In5.Cu")
		(net "PCIE_IOM_TO_COMP_8_DN")
	)
	(segment
		(start 160.560512 -106.020616)
		(end 155.737814 -83.331558)
		(width 0.1397)
		(layer "In5.Cu")
		(net "PCIE_IOM_TO_COMP_8_DN")
	)
	(segment
		(start 206.74965 -142.917672)
		(end 205.775814 -143.56715)
		(width 0.1397)
		(layer "In5.Cu")
		(net "PCIE_IOM_TO_COMP_8_DN")
	)
	(segment
		(start 159.055308 -142.040102)
		(end 157.206442 -139.299442)
		(width 0.1397)
		(layer "In5.Cu")
		(net "PCIE_IOM_TO_COMP_8_DN")
	)
	(segment
		(start 142.26794 -29.977588)
		(end 141.349984 -29.7942)
		(width 0.1397)
		(layer "In5.Cu")
		(net "PCIE_IOM_TO_COMP_8_DN")
	)
	(segment
		(start 206.246222 -140.840968)
		(end 206.246476 -140.840968)
		(width 0.1397)
		(layer "In5.Cu")
		(net "PCIE_IOM_TO_COMP_8_DN")
	)
	(arc
		(start 206.246476 -139.848336)
		(mid 206.04079 -140.344637)
		(end 206.246222 -140.840968)
		(width 0.1397)
		(layer "In5.Cu")
		(net "PCIE_IOM_TO_COMP_8_DN")
	)
	(arc
		(start 141.146022 -36.465256)
		(mid 141.254863 -36.510339)
		(end 141.299946 -36.61918)
		(width 0.1397)
		(layer "In5.Cu")
		(net "PCIE_IOM_TO_COMP_8_DN")
	)
	(arc
		(start 140.234924 -35.915854)
		(mid 140.39584 -36.30434)
		(end 140.784326 -36.465256)
		(width 0.1397)
		(layer "In5.Cu")
		(net "PCIE_IOM_TO_COMP_8_DN")
	)
	(arc
		(start 206.531464 -139.348464)
		(mid 206.575968 -139.455906)
		(end 206.531464 -139.563348)
		(width 0.1397)
		(layer "In5.Cu")
		(net "PCIE_IOM_TO_COMP_8_DN")
	)
	(segment
		(start 81.28889 -94.781624)
		(end 82.660744 -94.781624)
		(width 0.14605)
		(layer "F.Cu")
		(net "PCIE_IOM_TO_COMP_23_DP")
	)
	(segment
		(start 82.660744 -94.781624)
		(end 82.660998 -94.78137)
		(width 0.14605)
		(layer "F.Cu")
		(net "PCIE_IOM_TO_COMP_23_DP")
	)
	(segment
		(start 79.925164 -94.549976)
		(end 81.057242 -94.549976)
		(width 0.14605)
		(layer "F.Cu")
		(net "PCIE_IOM_TO_COMP_23_DP")
	)
	(segment
		(start 81.057242 -94.549976)
		(end 81.28889 -94.781624)
		(width 0.14605)
		(layer "F.Cu")
		(net "PCIE_IOM_TO_COMP_23_DP")
	)
	(arc
		(start 82.660998 -94.78137)
		(mid 83.038335 -94.706313)
		(end 83.358228 -94.492572)
		(width 0.14605)
		(layer "F.Cu")
		(net "PCIE_IOM_TO_COMP_23_DP")
	)
	(segment
		(start 97.714054 -46.479206)
		(end 98.990912 -52.488084)
		(width 0.1397)
		(layer "In5.Cu")
		(net "PCIE_IOM_TO_COMP_23_DP")
	)
	(segment
		(start 98.990912 -52.488084)
		(end 91.348306 -88.864694)
		(width 0.1397)
		(layer "In5.Cu")
		(net "PCIE_IOM_TO_COMP_23_DP")
	)
	(segment
		(start 85.441028 -94.771972)
		(end 83.637628 -94.771972)
		(width 0.1397)
		(layer "In5.Cu")
		(net "PCIE_IOM_TO_COMP_23_DP")
	)
	(segment
		(start 98.906584 -40.518842)
		(end 97.714054 -46.479206)
		(width 0.1397)
		(layer "In5.Cu")
		(net "PCIE_IOM_TO_COMP_23_DP")
	)
	(segment
		(start 83.637628 -94.771972)
		(end 83.358228 -94.492572)
		(width 0.1397)
		(layer "In5.Cu")
		(net "PCIE_IOM_TO_COMP_23_DP")
	)
	(segment
		(start 100.348288 -38.350698)
		(end 98.906584 -40.518842)
		(width 0.1397)
		(layer "In5.Cu")
		(net "PCIE_IOM_TO_COMP_23_DP")
	)
	(segment
		(start 107.099862 -36.800028)
		(end 107.099862 -37.181028)
		(width 0.1397)
		(layer "In5.Cu")
		(net "PCIE_IOM_TO_COMP_23_DP")
	)
	(segment
		(start 101.87051 -37.334952)
		(end 100.348288 -38.350698)
		(width 0.1397)
		(layer "In5.Cu")
		(net "PCIE_IOM_TO_COMP_23_DP")
	)
	(segment
		(start 91.348306 -88.864694)
		(end 85.441028 -94.771972)
		(width 0.1397)
		(layer "In5.Cu")
		(net "PCIE_IOM_TO_COMP_23_DP")
	)
	(segment
		(start 106.945938 -37.334952)
		(end 101.87051 -37.334952)
		(width 0.1397)
		(layer "In5.Cu")
		(net "PCIE_IOM_TO_COMP_23_DP")
	)
	(arc
		(start 107.099862 -37.181028)
		(mid 107.054779 -37.289869)
		(end 106.945938 -37.334952)
		(width 0.1397)
		(layer "In5.Cu")
		(net "PCIE_IOM_TO_COMP_23_DP")
	)
	(segment
		(start 81.058258 -95.350076)
		(end 81.31556 -95.092774)
		(width 0.14605)
		(layer "F.Cu")
		(net "PCIE_IOM_TO_COMP_23_DN")
	)
	(segment
		(start 79.925164 -95.350076)
		(end 81.058258 -95.350076)
		(width 0.14605)
		(layer "F.Cu")
		(net "PCIE_IOM_TO_COMP_23_DN")
	)
	(segment
		(start 81.31556 -95.092774)
		(end 82.660998 -95.092774)
		(width 0.14605)
		(layer "F.Cu")
		(net "PCIE_IOM_TO_COMP_23_DN")
	)
	(arc
		(start 82.660998 -95.092774)
		(mid 83.038335 -95.167831)
		(end 83.358228 -95.381572)
		(width 0.14605)
		(layer "F.Cu")
		(net "PCIE_IOM_TO_COMP_23_DN")
	)
	(segment
		(start 99.217734 -40.64762)
		(end 98.051366 -46.477174)
		(width 0.1397)
		(layer "In5.Cu")
		(net "PCIE_IOM_TO_COMP_23_DN")
	)
	(segment
		(start 99.328478 -52.487576)
		(end 91.651328 -89.028778)
		(width 0.1397)
		(layer "In5.Cu")
		(net "PCIE_IOM_TO_COMP_23_DN")
	)
	(segment
		(start 83.637628 -95.102172)
		(end 83.358228 -95.381572)
		(width 0.1397)
		(layer "In5.Cu")
		(net "PCIE_IOM_TO_COMP_23_DN")
	)
	(segment
		(start 101.970586 -37.665152)
		(end 100.586794 -38.588696)
		(width 0.1397)
		(layer "In5.Cu")
		(net "PCIE_IOM_TO_COMP_23_DN")
	)
	(segment
		(start 107.099862 -38.200076)
		(end 107.099862 -37.819076)
		(width 0.1397)
		(layer "In5.Cu")
		(net "PCIE_IOM_TO_COMP_23_DN")
	)
	(segment
		(start 98.051366 -46.477174)
		(end 99.328478 -52.487576)
		(width 0.1397)
		(layer "In5.Cu")
		(net "PCIE_IOM_TO_COMP_23_DN")
	)
	(segment
		(start 106.945938 -37.665152)
		(end 101.970586 -37.665152)
		(width 0.1397)
		(layer "In5.Cu")
		(net "PCIE_IOM_TO_COMP_23_DN")
	)
	(segment
		(start 91.651328 -89.028778)
		(end 85.577934 -95.102172)
		(width 0.1397)
		(layer "In5.Cu")
		(net "PCIE_IOM_TO_COMP_23_DN")
	)
	(segment
		(start 100.586794 -38.588696)
		(end 99.217734 -40.64762)
		(width 0.1397)
		(layer "In5.Cu")
		(net "PCIE_IOM_TO_COMP_23_DN")
	)
	(segment
		(start 85.577934 -95.102172)
		(end 83.637628 -95.102172)
		(width 0.1397)
		(layer "In5.Cu")
		(net "PCIE_IOM_TO_COMP_23_DN")
	)
	(arc
		(start 107.099862 -37.819076)
		(mid 107.054779 -37.710235)
		(end 106.945938 -37.665152)
		(width 0.1397)
		(layer "In5.Cu")
		(net "PCIE_IOM_TO_COMP_23_DN")
	)
	(segment
		(start 79.925164 -91.350084)
		(end 81.077562 -91.350084)
		(width 0.14605)
		(layer "F.Cu")
		(net "PCIE_IOM_TO_COMP_22_DP")
	)
	(segment
		(start 81.322926 -91.595448)
		(end 84.286344 -91.595448)
		(width 0.14605)
		(layer "F.Cu")
		(net "PCIE_IOM_TO_COMP_22_DP")
	)
	(segment
		(start 84.286344 -91.595448)
		(end 84.286598 -91.595194)
		(width 0.14605)
		(layer "F.Cu")
		(net "PCIE_IOM_TO_COMP_22_DP")
	)
	(segment
		(start 81.077562 -91.350084)
		(end 81.322926 -91.595448)
		(width 0.14605)
		(layer "F.Cu")
		(net "PCIE_IOM_TO_COMP_22_DP")
	)
	(arc
		(start 84.286598 -91.595194)
		(mid 84.663935 -91.520137)
		(end 84.983828 -91.306396)
		(width 0.14605)
		(layer "F.Cu")
		(net "PCIE_IOM_TO_COMP_22_DP")
	)
	(segment
		(start 108.164884 -35.9156)
		(end 108.164884 -31.65856)
		(width 0.1397)
		(layer "In5.Cu")
		(net "PCIE_IOM_TO_COMP_22_DP")
	)
	(segment
		(start 108.164884 -31.65856)
		(end 107.468924 -30.9626)
		(width 0.1397)
		(layer "In5.Cu")
		(net "PCIE_IOM_TO_COMP_22_DP")
	)
	(segment
		(start 85.263228 -91.585796)
		(end 84.983828 -91.306396)
		(width 0.1397)
		(layer "In5.Cu")
		(net "PCIE_IOM_TO_COMP_22_DP")
	)
	(segment
		(start 98.037396 -40.1066)
		(end 96.716342 -46.707044)
		(width 0.1397)
		(layer "In5.Cu")
		(net "PCIE_IOM_TO_COMP_22_DP")
	)
	(segment
		(start 90.7923 -87.099394)
		(end 86.305898 -91.585796)
		(width 0.1397)
		(layer "In5.Cu")
		(net "PCIE_IOM_TO_COMP_22_DP")
	)
	(segment
		(start 86.305898 -91.585796)
		(end 85.263228 -91.585796)
		(width 0.1397)
		(layer "In5.Cu")
		(net "PCIE_IOM_TO_COMP_22_DP")
	)
	(segment
		(start 97.988374 -52.690776)
		(end 90.7923 -87.099394)
		(width 0.1397)
		(layer "In5.Cu")
		(net "PCIE_IOM_TO_COMP_22_DP")
	)
	(segment
		(start 96.716342 -46.707044)
		(end 97.988374 -52.690776)
		(width 0.1397)
		(layer "In5.Cu")
		(net "PCIE_IOM_TO_COMP_22_DP")
	)
	(segment
		(start 107.079288 -30.9626)
		(end 105.889044 -31.215838)
		(width 0.1397)
		(layer "In5.Cu")
		(net "PCIE_IOM_TO_COMP_22_DP")
	)
	(segment
		(start 105.889044 -31.215838)
		(end 102.873302 -33.174432)
		(width 0.1397)
		(layer "In5.Cu")
		(net "PCIE_IOM_TO_COMP_22_DP")
	)
	(segment
		(start 108.746036 -36.135056)
		(end 108.38434 -36.135056)
		(width 0.1397)
		(layer "In5.Cu")
		(net "PCIE_IOM_TO_COMP_22_DP")
	)
	(segment
		(start 102.873302 -33.174432)
		(end 98.037396 -40.1066)
		(width 0.1397)
		(layer "In5.Cu")
		(net "PCIE_IOM_TO_COMP_22_DP")
	)
	(segment
		(start 107.468924 -30.9626)
		(end 107.079288 -30.9626)
		(width 0.1397)
		(layer "In5.Cu")
		(net "PCIE_IOM_TO_COMP_22_DP")
	)
	(segment
		(start 108.89996 -35.600132)
		(end 108.89996 -35.981132)
		(width 0.1397)
		(layer "In5.Cu")
		(net "PCIE_IOM_TO_COMP_22_DP")
	)
	(arc
		(start 108.89996 -35.981132)
		(mid 108.854877 -36.089973)
		(end 108.746036 -36.135056)
		(width 0.1397)
		(layer "In5.Cu")
		(net "PCIE_IOM_TO_COMP_22_DP")
	)
	(arc
		(start 108.38434 -36.135056)
		(mid 108.229161 -36.070779)
		(end 108.164884 -35.9156)
		(width 0.1397)
		(layer "In5.Cu")
		(net "PCIE_IOM_TO_COMP_22_DP")
	)
	(segment
		(start 81.08061 -92.14993)
		(end 81.323942 -91.906598)
		(width 0.14605)
		(layer "F.Cu")
		(net "PCIE_IOM_TO_COMP_22_DN")
	)
	(segment
		(start 81.323942 -91.906598)
		(end 84.286598 -91.906598)
		(width 0.14605)
		(layer "F.Cu")
		(net "PCIE_IOM_TO_COMP_22_DN")
	)
	(segment
		(start 79.925164 -92.14993)
		(end 81.08061 -92.14993)
		(width 0.14605)
		(layer "F.Cu")
		(net "PCIE_IOM_TO_COMP_22_DN")
	)
	(arc
		(start 84.286598 -91.906598)
		(mid 84.663935 -91.981655)
		(end 84.983828 -92.195396)
		(width 0.14605)
		(layer "F.Cu")
		(net "PCIE_IOM_TO_COMP_22_DN")
	)
	(segment
		(start 91.095576 -87.263224)
		(end 86.442804 -91.915996)
		(width 0.1397)
		(layer "In5.Cu")
		(net "PCIE_IOM_TO_COMP_22_DN")
	)
	(segment
		(start 108.746036 -36.465256)
		(end 108.38434 -36.465256)
		(width 0.1397)
		(layer "In5.Cu")
		(net "PCIE_IOM_TO_COMP_22_DN")
	)
	(segment
		(start 97.053654 -46.705012)
		(end 98.32594 -52.690268)
		(width 0.1397)
		(layer "In5.Cu")
		(net "PCIE_IOM_TO_COMP_22_DN")
	)
	(segment
		(start 85.263228 -91.915996)
		(end 84.983828 -92.195396)
		(width 0.1397)
		(layer "In5.Cu")
		(net "PCIE_IOM_TO_COMP_22_DN")
	)
	(segment
		(start 107.114086 -31.2928)
		(end 106.017822 -31.526226)
		(width 0.1397)
		(layer "In5.Cu")
		(net "PCIE_IOM_TO_COMP_22_DN")
	)
	(segment
		(start 103.107236 -33.41624)
		(end 98.347784 -40.239188)
		(width 0.1397)
		(layer "In5.Cu")
		(net "PCIE_IOM_TO_COMP_22_DN")
	)
	(segment
		(start 108.89996 -37.00018)
		(end 108.89996 -36.61918)
		(width 0.1397)
		(layer "In5.Cu")
		(net "PCIE_IOM_TO_COMP_22_DN")
	)
	(segment
		(start 98.347784 -40.239188)
		(end 97.053654 -46.705012)
		(width 0.1397)
		(layer "In5.Cu")
		(net "PCIE_IOM_TO_COMP_22_DN")
	)
	(segment
		(start 107.834684 -35.9156)
		(end 107.834684 -31.795466)
		(width 0.1397)
		(layer "In5.Cu")
		(net "PCIE_IOM_TO_COMP_22_DN")
	)
	(segment
		(start 106.017822 -31.526226)
		(end 103.107236 -33.41624)
		(width 0.1397)
		(layer "In5.Cu")
		(net "PCIE_IOM_TO_COMP_22_DN")
	)
	(segment
		(start 86.442804 -91.915996)
		(end 85.263228 -91.915996)
		(width 0.1397)
		(layer "In5.Cu")
		(net "PCIE_IOM_TO_COMP_22_DN")
	)
	(segment
		(start 107.834684 -31.795466)
		(end 107.332018 -31.2928)
		(width 0.1397)
		(layer "In5.Cu")
		(net "PCIE_IOM_TO_COMP_22_DN")
	)
	(segment
		(start 107.332018 -31.2928)
		(end 107.114086 -31.2928)
		(width 0.1397)
		(layer "In5.Cu")
		(net "PCIE_IOM_TO_COMP_22_DN")
	)
	(segment
		(start 98.32594 -52.690268)
		(end 91.095576 -87.263224)
		(width 0.1397)
		(layer "In5.Cu")
		(net "PCIE_IOM_TO_COMP_22_DN")
	)
	(arc
		(start 108.38434 -36.465256)
		(mid 107.995675 -36.304265)
		(end 107.834684 -35.9156)
		(width 0.1397)
		(layer "In5.Cu")
		(net "PCIE_IOM_TO_COMP_22_DN")
	)
	(arc
		(start 108.89996 -36.61918)
		(mid 108.854877 -36.510339)
		(end 108.746036 -36.465256)
		(width 0.1397)
		(layer "In5.Cu")
		(net "PCIE_IOM_TO_COMP_22_DN")
	)
	(segment
		(start 79.925164 -88.149938)
		(end 81.059782 -88.149938)
		(width 0.14605)
		(layer "F.Cu")
		(net "PCIE_IOM_TO_COMP_21_DP")
	)
	(segment
		(start 81.29016 -88.380316)
		(end 82.662014 -88.380316)
		(width 0.14605)
		(layer "F.Cu")
		(net "PCIE_IOM_TO_COMP_21_DP")
	)
	(segment
		(start 82.662014 -88.380316)
		(end 82.662268 -88.380062)
		(width 0.14605)
		(layer "F.Cu")
		(net "PCIE_IOM_TO_COMP_21_DP")
	)
	(segment
		(start 81.059782 -88.149938)
		(end 81.29016 -88.380316)
		(width 0.14605)
		(layer "F.Cu")
		(net "PCIE_IOM_TO_COMP_21_DP")
	)
	(arc
		(start 82.662268 -88.380062)
		(mid 83.039605 -88.305005)
		(end 83.359498 -88.091264)
		(width 0.14605)
		(layer "F.Cu")
		(net "PCIE_IOM_TO_COMP_21_DP")
	)
	(segment
		(start 107.22737 -29.746448)
		(end 107.193588 -29.75356)
		(width 0.1397)
		(layer "In5.Cu")
		(net "PCIE_IOM_TO_COMP_21_DP")
	)
	(segment
		(start 97.027492 -39.631366)
		(end 95.640144 -46.597062)
		(width 0.1397)
		(layer "In5.Cu")
		(net "PCIE_IOM_TO_COMP_21_DP")
	)
	(segment
		(start 105.41 -30.134052)
		(end 102.117906 -32.271716)
		(width 0.1397)
		(layer "In5.Cu")
		(net "PCIE_IOM_TO_COMP_21_DP")
	)
	(segment
		(start 96.891348 -52.483258)
		(end 90.524838 -83.109816)
		(width 0.1397)
		(layer "In5.Cu")
		(net "PCIE_IOM_TO_COMP_21_DP")
	)
	(segment
		(start 90.524838 -83.109816)
		(end 85.2678 -88.3666)
		(width 0.1397)
		(layer "In5.Cu")
		(net "PCIE_IOM_TO_COMP_21_DP")
	)
	(segment
		(start 109.965236 -37.102288)
		(end 109.965236 -30.437836)
		(width 0.1397)
		(layer "In5.Cu")
		(net "PCIE_IOM_TO_COMP_21_DP")
	)
	(segment
		(start 85.2678 -88.3666)
		(end 83.634834 -88.3666)
		(width 0.1397)
		(layer "In5.Cu")
		(net "PCIE_IOM_TO_COMP_21_DP")
	)
	(segment
		(start 107.193588 -29.75356)
		(end 105.41 -30.134052)
		(width 0.1397)
		(layer "In5.Cu")
		(net "PCIE_IOM_TO_COMP_21_DP")
	)
	(segment
		(start 110.700058 -36.800028)
		(end 110.700058 -37.181028)
		(width 0.1397)
		(layer "In5.Cu")
		(net "PCIE_IOM_TO_COMP_21_DP")
	)
	(segment
		(start 109.273848 -29.746448)
		(end 107.22737 -29.746448)
		(width 0.1397)
		(layer "In5.Cu")
		(net "PCIE_IOM_TO_COMP_21_DP")
	)
	(segment
		(start 102.117906 -32.271716)
		(end 97.027492 -39.631366)
		(width 0.1397)
		(layer "In5.Cu")
		(net "PCIE_IOM_TO_COMP_21_DP")
	)
	(segment
		(start 95.640144 -46.597062)
		(end 96.891348 -52.483258)
		(width 0.1397)
		(layer "In5.Cu")
		(net "PCIE_IOM_TO_COMP_21_DP")
	)
	(segment
		(start 110.546134 -37.334952)
		(end 110.1979 -37.334952)
		(width 0.1397)
		(layer "In5.Cu")
		(net "PCIE_IOM_TO_COMP_21_DP")
	)
	(segment
		(start 83.634834 -88.3666)
		(end 83.359498 -88.091264)
		(width 0.1397)
		(layer "In5.Cu")
		(net "PCIE_IOM_TO_COMP_21_DP")
	)
	(segment
		(start 109.965236 -30.437836)
		(end 109.273848 -29.746448)
		(width 0.1397)
		(layer "In5.Cu")
		(net "PCIE_IOM_TO_COMP_21_DP")
	)
	(arc
		(start 110.1979 -37.334952)
		(mid 110.033382 -37.266806)
		(end 109.965236 -37.102288)
		(width 0.1397)
		(layer "In5.Cu")
		(net "PCIE_IOM_TO_COMP_21_DP")
	)
	(arc
		(start 110.700058 -37.181028)
		(mid 110.654975 -37.289869)
		(end 110.546134 -37.334952)
		(width 0.1397)
		(layer "In5.Cu")
		(net "PCIE_IOM_TO_COMP_21_DP")
	)
	(segment
		(start 81.058258 -88.950038)
		(end 81.31683 -88.691466)
		(width 0.14605)
		(layer "F.Cu")
		(net "PCIE_IOM_TO_COMP_21_DN")
	)
	(segment
		(start 79.925164 -88.950038)
		(end 81.058258 -88.950038)
		(width 0.14605)
		(layer "F.Cu")
		(net "PCIE_IOM_TO_COMP_21_DN")
	)
	(segment
		(start 81.31683 -88.691466)
		(end 82.662268 -88.691466)
		(width 0.14605)
		(layer "F.Cu")
		(net "PCIE_IOM_TO_COMP_21_DN")
	)
	(arc
		(start 82.662268 -88.691466)
		(mid 83.039605 -88.766523)
		(end 83.359498 -88.980264)
		(width 0.14605)
		(layer "F.Cu")
		(net "PCIE_IOM_TO_COMP_21_DN")
	)
	(segment
		(start 85.404706 -88.6968)
		(end 83.642962 -88.6968)
		(width 0.1397)
		(layer "In5.Cu")
		(net "PCIE_IOM_TO_COMP_21_DN")
	)
	(segment
		(start 97.338134 -39.762938)
		(end 95.977456 -46.594776)
		(width 0.1397)
		(layer "In5.Cu")
		(net "PCIE_IOM_TO_COMP_21_DN")
	)
	(segment
		(start 109.136942 -30.076648)
		(end 107.262422 -30.076648)
		(width 0.1397)
		(layer "In5.Cu")
		(net "PCIE_IOM_TO_COMP_21_DN")
	)
	(segment
		(start 95.977456 -46.594776)
		(end 97.228914 -52.482496)
		(width 0.1397)
		(layer "In5.Cu")
		(net "PCIE_IOM_TO_COMP_21_DN")
	)
	(segment
		(start 109.635036 -37.102288)
		(end 109.635036 -30.574742)
		(width 0.1397)
		(layer "In5.Cu")
		(net "PCIE_IOM_TO_COMP_21_DN")
	)
	(segment
		(start 110.700058 -38.200076)
		(end 110.700058 -37.819076)
		(width 0.1397)
		(layer "In5.Cu")
		(net "PCIE_IOM_TO_COMP_21_DN")
	)
	(segment
		(start 102.352348 -32.51327)
		(end 97.338134 -39.762938)
		(width 0.1397)
		(layer "In5.Cu")
		(net "PCIE_IOM_TO_COMP_21_DN")
	)
	(segment
		(start 107.262422 -30.076648)
		(end 105.538778 -30.44444)
		(width 0.1397)
		(layer "In5.Cu")
		(net "PCIE_IOM_TO_COMP_21_DN")
	)
	(segment
		(start 110.546134 -37.665152)
		(end 110.1979 -37.665152)
		(width 0.1397)
		(layer "In5.Cu")
		(net "PCIE_IOM_TO_COMP_21_DN")
	)
	(segment
		(start 109.635036 -30.574742)
		(end 109.136942 -30.076648)
		(width 0.1397)
		(layer "In5.Cu")
		(net "PCIE_IOM_TO_COMP_21_DN")
	)
	(segment
		(start 90.828114 -83.273646)
		(end 85.404706 -88.6968)
		(width 0.1397)
		(layer "In5.Cu")
		(net "PCIE_IOM_TO_COMP_21_DN")
	)
	(segment
		(start 105.538778 -30.44444)
		(end 102.352348 -32.51327)
		(width 0.1397)
		(layer "In5.Cu")
		(net "PCIE_IOM_TO_COMP_21_DN")
	)
	(segment
		(start 83.642962 -88.6968)
		(end 83.359498 -88.980264)
		(width 0.1397)
		(layer "In5.Cu")
		(net "PCIE_IOM_TO_COMP_21_DN")
	)
	(segment
		(start 97.228914 -52.482496)
		(end 90.828114 -83.273646)
		(width 0.1397)
		(layer "In5.Cu")
		(net "PCIE_IOM_TO_COMP_21_DN")
	)
	(arc
		(start 110.1979 -37.665152)
		(mid 109.799895 -37.500293)
		(end 109.635036 -37.102288)
		(width 0.1397)
		(layer "In5.Cu")
		(net "PCIE_IOM_TO_COMP_21_DN")
	)
	(arc
		(start 110.700058 -37.819076)
		(mid 110.654975 -37.710235)
		(end 110.546134 -37.665152)
		(width 0.1397)
		(layer "In5.Cu")
		(net "PCIE_IOM_TO_COMP_21_DN")
	)
	(segment
		(start 81.091786 -84.950046)
		(end 81.322926 -85.181186)
		(width 0.14605)
		(layer "F.Cu")
		(net "PCIE_IOM_TO_COMP_20_DP")
	)
	(segment
		(start 81.322926 -85.181186)
		(end 84.286344 -85.181186)
		(width 0.14605)
		(layer "F.Cu")
		(net "PCIE_IOM_TO_COMP_20_DP")
	)
	(segment
		(start 84.286344 -85.181186)
		(end 84.286598 -85.180932)
		(width 0.14605)
		(layer "F.Cu")
		(net "PCIE_IOM_TO_COMP_20_DP")
	)
	(segment
		(start 79.925164 -84.950046)
		(end 81.091786 -84.950046)
		(width 0.14605)
		(layer "F.Cu")
		(net "PCIE_IOM_TO_COMP_20_DP")
	)
	(arc
		(start 84.286598 -85.180932)
		(mid 84.663935 -85.105875)
		(end 84.983828 -84.892134)
		(width 0.14605)
		(layer "F.Cu")
		(net "PCIE_IOM_TO_COMP_20_DP")
	)
	(segment
		(start 86.735666 -85.171534)
		(end 85.263228 -85.171534)
		(width 0.1397)
		(layer "In5.Cu")
		(net "PCIE_IOM_TO_COMP_20_DP")
	)
	(segment
		(start 95.874332 -52.763674)
		(end 89.594944 -82.312256)
		(width 0.1397)
		(layer "In5.Cu")
		(net "PCIE_IOM_TO_COMP_20_DP")
	)
	(segment
		(start 111.76508 -30.48508)
		(end 110.1471 -28.8671)
		(width 0.1397)
		(layer "In5.Cu")
		(net "PCIE_IOM_TO_COMP_20_DP")
	)
	(segment
		(start 111.76508 -35.915854)
		(end 111.76508 -30.48508)
		(width 0.1397)
		(layer "In5.Cu")
		(net "PCIE_IOM_TO_COMP_20_DP")
	)
	(segment
		(start 94.572328 -46.638464)
		(end 95.874332 -52.763674)
		(width 0.1397)
		(layer "In5.Cu")
		(net "PCIE_IOM_TO_COMP_20_DP")
	)
	(segment
		(start 104.381808 -29.299662)
		(end 104.382062 -29.299662)
		(width 0.1397)
		(layer "In5.Cu")
		(net "PCIE_IOM_TO_COMP_20_DP")
	)
	(segment
		(start 85.263228 -85.171534)
		(end 84.983828 -84.892134)
		(width 0.1397)
		(layer "In5.Cu")
		(net "PCIE_IOM_TO_COMP_20_DP")
	)
	(segment
		(start 112.345978 -36.135056)
		(end 111.984282 -36.135056)
		(width 0.1397)
		(layer "In5.Cu")
		(net "PCIE_IOM_TO_COMP_20_DP")
	)
	(segment
		(start 104.382062 -29.299662)
		(end 101.087682 -31.438596)
		(width 0.1397)
		(layer "In5.Cu")
		(net "PCIE_IOM_TO_COMP_20_DP")
	)
	(segment
		(start 110.1471 -28.8671)
		(end 106.411776 -28.8671)
		(width 0.1397)
		(layer "In5.Cu")
		(net "PCIE_IOM_TO_COMP_20_DP")
	)
	(segment
		(start 106.411776 -28.8671)
		(end 104.435148 -29.265118)
		(width 0.1397)
		(layer "In5.Cu")
		(net "PCIE_IOM_TO_COMP_20_DP")
	)
	(segment
		(start 104.435148 -29.265118)
		(end 104.381808 -29.299662)
		(width 0.1397)
		(layer "In5.Cu")
		(net "PCIE_IOM_TO_COMP_20_DP")
	)
	(segment
		(start 101.087682 -31.438596)
		(end 96.12122 -38.890448)
		(width 0.1397)
		(layer "In5.Cu")
		(net "PCIE_IOM_TO_COMP_20_DP")
	)
	(segment
		(start 112.499902 -35.600132)
		(end 112.499902 -35.981132)
		(width 0.1397)
		(layer "In5.Cu")
		(net "PCIE_IOM_TO_COMP_20_DP")
	)
	(segment
		(start 89.594944 -82.312256)
		(end 86.735666 -85.171534)
		(width 0.1397)
		(layer "In5.Cu")
		(net "PCIE_IOM_TO_COMP_20_DP")
	)
	(segment
		(start 96.12122 -38.890448)
		(end 94.572328 -46.638464)
		(width 0.1397)
		(layer "In5.Cu")
		(net "PCIE_IOM_TO_COMP_20_DP")
	)
	(arc
		(start 112.499902 -35.981132)
		(mid 112.454819 -36.089973)
		(end 112.345978 -36.135056)
		(width 0.1397)
		(layer "In5.Cu")
		(net "PCIE_IOM_TO_COMP_20_DP")
	)
	(arc
		(start 111.984282 -36.135056)
		(mid 111.829283 -36.070853)
		(end 111.76508 -35.915854)
		(width 0.1397)
		(layer "In5.Cu")
		(net "PCIE_IOM_TO_COMP_20_DP")
	)
	(segment
		(start 81.066132 -85.750146)
		(end 81.323942 -85.492336)
		(width 0.14605)
		(layer "F.Cu")
		(net "PCIE_IOM_TO_COMP_20_DN")
	)
	(segment
		(start 79.925164 -85.750146)
		(end 81.066132 -85.750146)
		(width 0.14605)
		(layer "F.Cu")
		(net "PCIE_IOM_TO_COMP_20_DN")
	)
	(segment
		(start 81.323942 -85.492336)
		(end 84.286598 -85.492336)
		(width 0.14605)
		(layer "F.Cu")
		(net "PCIE_IOM_TO_COMP_20_DN")
	)
	(arc
		(start 84.286598 -85.492336)
		(mid 84.663935 -85.567393)
		(end 84.983828 -85.781134)
		(width 0.14605)
		(layer "F.Cu")
		(net "PCIE_IOM_TO_COMP_20_DN")
	)
	(segment
		(start 112.345978 -36.465256)
		(end 111.984282 -36.465256)
		(width 0.1397)
		(layer "In5.Cu")
		(net "PCIE_IOM_TO_COMP_20_DN")
	)
	(segment
		(start 112.499902 -37.00018)
		(end 112.499902 -36.61918)
		(width 0.1397)
		(layer "In5.Cu")
		(net "PCIE_IOM_TO_COMP_20_DN")
	)
	(segment
		(start 94.90964 -46.636432)
		(end 96.212152 -52.763674)
		(width 0.1397)
		(layer "In5.Cu")
		(net "PCIE_IOM_TO_COMP_20_DN")
	)
	(segment
		(start 111.43488 -30.621986)
		(end 110.010194 -29.1973)
		(width 0.1397)
		(layer "In5.Cu")
		(net "PCIE_IOM_TO_COMP_20_DN")
	)
	(segment
		(start 86.872572 -85.501734)
		(end 85.263228 -85.501734)
		(width 0.1397)
		(layer "In5.Cu")
		(net "PCIE_IOM_TO_COMP_20_DN")
	)
	(segment
		(start 106.444796 -29.1973)
		(end 104.562148 -29.576522)
		(width 0.1397)
		(layer "In5.Cu")
		(net "PCIE_IOM_TO_COMP_20_DN")
	)
	(segment
		(start 101.324918 -31.678626)
		(end 96.43237 -39.019226)
		(width 0.1397)
		(layer "In5.Cu")
		(net "PCIE_IOM_TO_COMP_20_DN")
	)
	(segment
		(start 85.263228 -85.501734)
		(end 84.983828 -85.781134)
		(width 0.1397)
		(layer "In5.Cu")
		(net "PCIE_IOM_TO_COMP_20_DN")
	)
	(segment
		(start 110.010194 -29.1973)
		(end 106.444796 -29.1973)
		(width 0.1397)
		(layer "In5.Cu")
		(net "PCIE_IOM_TO_COMP_20_DN")
	)
	(segment
		(start 96.212152 -52.763674)
		(end 89.897712 -82.476594)
		(width 0.1397)
		(layer "In5.Cu")
		(net "PCIE_IOM_TO_COMP_20_DN")
	)
	(segment
		(start 96.43237 -39.019226)
		(end 94.90964 -46.636432)
		(width 0.1397)
		(layer "In5.Cu")
		(net "PCIE_IOM_TO_COMP_20_DN")
	)
	(segment
		(start 89.897712 -82.476594)
		(end 86.872572 -85.501734)
		(width 0.1397)
		(layer "In5.Cu")
		(net "PCIE_IOM_TO_COMP_20_DN")
	)
	(segment
		(start 111.43488 -35.915854)
		(end 111.43488 -30.621986)
		(width 0.1397)
		(layer "In5.Cu")
		(net "PCIE_IOM_TO_COMP_20_DN")
	)
	(segment
		(start 104.562148 -29.576522)
		(end 101.324918 -31.678626)
		(width 0.1397)
		(layer "In5.Cu")
		(net "PCIE_IOM_TO_COMP_20_DN")
	)
	(arc
		(start 111.984282 -36.465256)
		(mid 111.595796 -36.30434)
		(end 111.43488 -35.915854)
		(width 0.1397)
		(layer "In5.Cu")
		(net "PCIE_IOM_TO_COMP_20_DN")
	)
	(arc
		(start 112.499902 -36.61918)
		(mid 112.454819 -36.510339)
		(end 112.345978 -36.465256)
		(width 0.1397)
		(layer "In5.Cu")
		(net "PCIE_IOM_TO_COMP_20_DN")
	)
	(segment
		(start 79.925164 -81.7499)
		(end 81.057242 -81.7499)
		(width 0.14605)
		(layer "F.Cu")
		(net "PCIE_IOM_TO_COMP_19_DP")
	)
	(segment
		(start 81.28889 -81.981548)
		(end 82.660744 -81.981548)
		(width 0.14605)
		(layer "F.Cu")
		(net "PCIE_IOM_TO_COMP_19_DP")
	)
	(segment
		(start 81.057242 -81.7499)
		(end 81.28889 -81.981548)
		(width 0.14605)
		(layer "F.Cu")
		(net "PCIE_IOM_TO_COMP_19_DP")
	)
	(segment
		(start 82.660744 -81.981548)
		(end 82.660998 -81.981294)
		(width 0.14605)
		(layer "F.Cu")
		(net "PCIE_IOM_TO_COMP_19_DP")
	)
	(arc
		(start 82.660998 -81.981294)
		(mid 83.038335 -81.906237)
		(end 83.358228 -81.692496)
		(width 0.14605)
		(layer "F.Cu")
		(net "PCIE_IOM_TO_COMP_19_DP")
	)
	(segment
		(start 93.290644 -47.689262)
		(end 93.829378 -50.224182)
		(width 0.1397)
		(layer "In5.Cu")
		(net "PCIE_IOM_TO_COMP_19_DP")
	)
	(segment
		(start 110.849156 -27.70505)
		(end 106.439208 -27.70505)
		(width 0.1397)
		(layer "In5.Cu")
		(net "PCIE_IOM_TO_COMP_19_DP")
	)
	(segment
		(start 95.171006 -38.283642)
		(end 93.290644 -47.689262)
		(width 0.1397)
		(layer "In5.Cu")
		(net "PCIE_IOM_TO_COMP_19_DP")
	)
	(segment
		(start 114.3 -36.800028)
		(end 114.3 -37.181028)
		(width 0.1397)
		(layer "In5.Cu")
		(net "PCIE_IOM_TO_COMP_19_DP")
	)
	(segment
		(start 103.655114 -28.280868)
		(end 100.452682 -30.360366)
		(width 0.1397)
		(layer "In5.Cu")
		(net "PCIE_IOM_TO_COMP_19_DP")
	)
	(segment
		(start 100.452682 -30.360366)
		(end 95.171006 -38.283642)
		(width 0.1397)
		(layer "In5.Cu")
		(net "PCIE_IOM_TO_COMP_19_DP")
	)
	(segment
		(start 94.312486 -55.060342)
		(end 90.325956 -74.581766)
		(width 0.1397)
		(layer "In5.Cu")
		(net "PCIE_IOM_TO_COMP_19_DP")
	)
	(segment
		(start 93.556836 -51.50612)
		(end 94.312486 -55.060342)
		(width 0.1397)
		(layer "In5.Cu")
		(net "PCIE_IOM_TO_COMP_19_DP")
	)
	(segment
		(start 90.325956 -74.581766)
		(end 86.637368 -80.114902)
		(width 0.1397)
		(layer "In5.Cu")
		(net "PCIE_IOM_TO_COMP_19_DP")
	)
	(segment
		(start 114.146076 -37.334952)
		(end 113.797842 -37.334952)
		(width 0.1397)
		(layer "In5.Cu")
		(net "PCIE_IOM_TO_COMP_19_DP")
	)
	(segment
		(start 86.637368 -80.114902)
		(end 84.78647 -81.9658)
		(width 0.1397)
		(layer "In5.Cu")
		(net "PCIE_IOM_TO_COMP_19_DP")
	)
	(segment
		(start 84.78647 -81.9658)
		(end 83.631532 -81.9658)
		(width 0.1397)
		(layer "In5.Cu")
		(net "PCIE_IOM_TO_COMP_19_DP")
	)
	(segment
		(start 83.631532 -81.9658)
		(end 83.358228 -81.692496)
		(width 0.1397)
		(layer "In5.Cu")
		(net "PCIE_IOM_TO_COMP_19_DP")
	)
	(segment
		(start 93.829378 -50.224182)
		(end 93.556836 -51.50612)
		(width 0.1397)
		(layer "In5.Cu")
		(net "PCIE_IOM_TO_COMP_19_DP")
	)
	(segment
		(start 113.565178 -37.102288)
		(end 113.565178 -30.421072)
		(width 0.1397)
		(layer "In5.Cu")
		(net "PCIE_IOM_TO_COMP_19_DP")
	)
	(segment
		(start 106.439208 -27.70505)
		(end 103.655114 -28.280868)
		(width 0.1397)
		(layer "In5.Cu")
		(net "PCIE_IOM_TO_COMP_19_DP")
	)
	(segment
		(start 113.565178 -30.421072)
		(end 110.849156 -27.70505)
		(width 0.1397)
		(layer "In5.Cu")
		(net "PCIE_IOM_TO_COMP_19_DP")
	)
	(arc
		(start 113.797842 -37.334952)
		(mid 113.633324 -37.266806)
		(end 113.565178 -37.102288)
		(width 0.1397)
		(layer "In5.Cu")
		(net "PCIE_IOM_TO_COMP_19_DP")
	)
	(arc
		(start 114.3 -37.181028)
		(mid 114.254917 -37.289869)
		(end 114.146076 -37.334952)
		(width 0.1397)
		(layer "In5.Cu")
		(net "PCIE_IOM_TO_COMP_19_DP")
	)
	(segment
		(start 81.31556 -82.292698)
		(end 82.660998 -82.292698)
		(width 0.14605)
		(layer "F.Cu")
		(net "PCIE_IOM_TO_COMP_19_DN")
	)
	(segment
		(start 81.058258 -82.55)
		(end 81.31556 -82.292698)
		(width 0.14605)
		(layer "F.Cu")
		(net "PCIE_IOM_TO_COMP_19_DN")
	)
	(segment
		(start 79.925164 -82.55)
		(end 81.058258 -82.55)
		(width 0.14605)
		(layer "F.Cu")
		(net "PCIE_IOM_TO_COMP_19_DN")
	)
	(arc
		(start 82.660998 -82.292698)
		(mid 83.038335 -82.367755)
		(end 83.358228 -82.581496)
		(width 0.14605)
		(layer "F.Cu")
		(net "PCIE_IOM_TO_COMP_19_DN")
	)
	(segment
		(start 93.627956 -47.68723)
		(end 94.167198 -50.224182)
		(width 0.1397)
		(layer "In5.Cu")
		(net "PCIE_IOM_TO_COMP_19_DN")
	)
	(segment
		(start 100.689918 -30.600396)
		(end 95.482156 -38.41242)
		(width 0.1397)
		(layer "In5.Cu")
		(net "PCIE_IOM_TO_COMP_19_DN")
	)
	(segment
		(start 94.649798 -55.059072)
		(end 90.636852 -74.711306)
		(width 0.1397)
		(layer "In5.Cu")
		(net "PCIE_IOM_TO_COMP_19_DN")
	)
	(segment
		(start 113.234978 -37.102288)
		(end 113.234978 -30.557978)
		(width 0.1397)
		(layer "In5.Cu")
		(net "PCIE_IOM_TO_COMP_19_DN")
	)
	(segment
		(start 94.167198 -50.224182)
		(end 93.894656 -51.50612)
		(width 0.1397)
		(layer "In5.Cu")
		(net "PCIE_IOM_TO_COMP_19_DN")
	)
	(segment
		(start 83.643724 -82.296)
		(end 83.358228 -82.581496)
		(width 0.1397)
		(layer "In5.Cu")
		(net "PCIE_IOM_TO_COMP_19_DN")
	)
	(segment
		(start 95.482156 -38.41242)
		(end 93.627956 -47.68723)
		(width 0.1397)
		(layer "In5.Cu")
		(net "PCIE_IOM_TO_COMP_19_DN")
	)
	(segment
		(start 93.894656 -51.50612)
		(end 94.649798 -55.059072)
		(width 0.1397)
		(layer "In5.Cu")
		(net "PCIE_IOM_TO_COMP_19_DN")
	)
	(segment
		(start 86.894162 -80.325468)
		(end 84.923376 -82.296)
		(width 0.1397)
		(layer "In5.Cu")
		(net "PCIE_IOM_TO_COMP_19_DN")
	)
	(segment
		(start 90.636852 -74.711306)
		(end 86.894162 -80.325468)
		(width 0.1397)
		(layer "In5.Cu")
		(net "PCIE_IOM_TO_COMP_19_DN")
	)
	(segment
		(start 110.71225 -28.03525)
		(end 106.473244 -28.03525)
		(width 0.1397)
		(layer "In5.Cu")
		(net "PCIE_IOM_TO_COMP_19_DN")
	)
	(segment
		(start 106.473244 -28.03525)
		(end 103.782876 -28.591764)
		(width 0.1397)
		(layer "In5.Cu")
		(net "PCIE_IOM_TO_COMP_19_DN")
	)
	(segment
		(start 84.923376 -82.296)
		(end 83.643724 -82.296)
		(width 0.1397)
		(layer "In5.Cu")
		(net "PCIE_IOM_TO_COMP_19_DN")
	)
	(segment
		(start 103.782876 -28.591764)
		(end 100.689918 -30.600396)
		(width 0.1397)
		(layer "In5.Cu")
		(net "PCIE_IOM_TO_COMP_19_DN")
	)
	(segment
		(start 113.234978 -30.557978)
		(end 110.71225 -28.03525)
		(width 0.1397)
		(layer "In5.Cu")
		(net "PCIE_IOM_TO_COMP_19_DN")
	)
	(segment
		(start 114.146076 -37.665152)
		(end 113.797842 -37.665152)
		(width 0.1397)
		(layer "In5.Cu")
		(net "PCIE_IOM_TO_COMP_19_DN")
	)
	(segment
		(start 114.3 -38.200076)
		(end 114.3 -37.819076)
		(width 0.1397)
		(layer "In5.Cu")
		(net "PCIE_IOM_TO_COMP_19_DN")
	)
	(arc
		(start 113.797842 -37.665152)
		(mid 113.399837 -37.500293)
		(end 113.234978 -37.102288)
		(width 0.1397)
		(layer "In5.Cu")
		(net "PCIE_IOM_TO_COMP_19_DN")
	)
	(arc
		(start 114.3 -37.819076)
		(mid 114.254917 -37.710235)
		(end 114.146076 -37.665152)
		(width 0.1397)
		(layer "In5.Cu")
		(net "PCIE_IOM_TO_COMP_19_DN")
	)
	(segment
		(start 79.925164 -78.550008)
		(end 81.07934 -78.550008)
		(width 0.14605)
		(layer "F.Cu")
		(net "PCIE_IOM_TO_COMP_18_DP")
	)
	(segment
		(start 84.289138 -78.796388)
		(end 84.289392 -78.796134)
		(width 0.14605)
		(layer "F.Cu")
		(net "PCIE_IOM_TO_COMP_18_DP")
	)
	(segment
		(start 81.32572 -78.796388)
		(end 84.289138 -78.796388)
		(width 0.14605)
		(layer "F.Cu")
		(net "PCIE_IOM_TO_COMP_18_DP")
	)
	(segment
		(start 81.07934 -78.550008)
		(end 81.32572 -78.796388)
		(width 0.14605)
		(layer "F.Cu")
		(net "PCIE_IOM_TO_COMP_18_DP")
	)
	(arc
		(start 84.289392 -78.796134)
		(mid 84.666729 -78.721077)
		(end 84.986622 -78.507336)
		(width 0.14605)
		(layer "F.Cu")
		(net "PCIE_IOM_TO_COMP_18_DP")
	)
	(segment
		(start 94.38767 -37.527992)
		(end 91.778074 -50.57267)
		(width 0.1397)
		(layer "In5.Cu")
		(net "PCIE_IOM_TO_COMP_18_DP")
	)
	(segment
		(start 91.778074 -50.57267)
		(end 92.75826 -55.18404)
		(width 0.1397)
		(layer "In5.Cu")
		(net "PCIE_IOM_TO_COMP_18_DP")
	)
	(segment
		(start 112.258856 -26.93035)
		(end 103.86949 -26.93035)
		(width 0.1397)
		(layer "In5.Cu")
		(net "PCIE_IOM_TO_COMP_18_DP")
	)
	(segment
		(start 85.769958 -78.786736)
		(end 85.266022 -78.786736)
		(width 0.1397)
		(layer "In5.Cu")
		(net "PCIE_IOM_TO_COMP_18_DP")
	)
	(segment
		(start 115.365022 -35.915854)
		(end 115.365022 -30.036516)
		(width 0.1397)
		(layer "In5.Cu")
		(net "PCIE_IOM_TO_COMP_18_DP")
	)
	(segment
		(start 92.75826 -55.18404)
		(end 88.783414 -74.553826)
		(width 0.1397)
		(layer "In5.Cu")
		(net "PCIE_IOM_TO_COMP_18_DP")
	)
	(segment
		(start 99.605338 -29.699458)
		(end 94.38767 -37.527992)
		(width 0.1397)
		(layer "In5.Cu")
		(net "PCIE_IOM_TO_COMP_18_DP")
	)
	(segment
		(start 103.86949 -26.93035)
		(end 99.605338 -29.699458)
		(width 0.1397)
		(layer "In5.Cu")
		(net "PCIE_IOM_TO_COMP_18_DP")
	)
	(segment
		(start 86.52383 -78.032864)
		(end 85.769958 -78.786736)
		(width 0.1397)
		(layer "In5.Cu")
		(net "PCIE_IOM_TO_COMP_18_DP")
	)
	(segment
		(start 88.783414 -74.553826)
		(end 86.52383 -78.032864)
		(width 0.1397)
		(layer "In5.Cu")
		(net "PCIE_IOM_TO_COMP_18_DP")
	)
	(segment
		(start 115.94592 -36.135056)
		(end 115.584224 -36.135056)
		(width 0.1397)
		(layer "In5.Cu")
		(net "PCIE_IOM_TO_COMP_18_DP")
	)
	(segment
		(start 116.099844 -35.600132)
		(end 116.099844 -35.981132)
		(width 0.1397)
		(layer "In5.Cu")
		(net "PCIE_IOM_TO_COMP_18_DP")
	)
	(segment
		(start 85.266022 -78.786736)
		(end 84.986622 -78.507336)
		(width 0.1397)
		(layer "In5.Cu")
		(net "PCIE_IOM_TO_COMP_18_DP")
	)
	(segment
		(start 115.365022 -30.036516)
		(end 112.258856 -26.93035)
		(width 0.1397)
		(layer "In5.Cu")
		(net "PCIE_IOM_TO_COMP_18_DP")
	)
	(arc
		(start 116.099844 -35.981132)
		(mid 116.054761 -36.089973)
		(end 115.94592 -36.135056)
		(width 0.1397)
		(layer "In5.Cu")
		(net "PCIE_IOM_TO_COMP_18_DP")
	)
	(arc
		(start 115.584224 -36.135056)
		(mid 115.429225 -36.070853)
		(end 115.365022 -35.915854)
		(width 0.1397)
		(layer "In5.Cu")
		(net "PCIE_IOM_TO_COMP_18_DP")
	)
	(segment
		(start 81.084166 -79.350108)
		(end 81.326736 -79.107538)
		(width 0.14605)
		(layer "F.Cu")
		(net "PCIE_IOM_TO_COMP_18_DN")
	)
	(segment
		(start 81.326736 -79.107538)
		(end 84.289392 -79.107538)
		(width 0.14605)
		(layer "F.Cu")
		(net "PCIE_IOM_TO_COMP_18_DN")
	)
	(segment
		(start 79.925164 -79.350108)
		(end 81.084166 -79.350108)
		(width 0.14605)
		(layer "F.Cu")
		(net "PCIE_IOM_TO_COMP_18_DN")
	)
	(arc
		(start 84.289392 -79.107538)
		(mid 84.666729 -79.182595)
		(end 84.986622 -79.396336)
		(width 0.14605)
		(layer "F.Cu")
		(net "PCIE_IOM_TO_COMP_18_DN")
	)
	(segment
		(start 99.842574 -29.939488)
		(end 94.69882 -37.65677)
		(width 0.1397)
		(layer "In5.Cu")
		(net "PCIE_IOM_TO_COMP_18_DN")
	)
	(segment
		(start 115.94592 -36.465256)
		(end 115.584224 -36.465256)
		(width 0.1397)
		(layer "In5.Cu")
		(net "PCIE_IOM_TO_COMP_18_DN")
	)
	(segment
		(start 86.781894 -78.241906)
		(end 85.906864 -79.116936)
		(width 0.1397)
		(layer "In5.Cu")
		(net "PCIE_IOM_TO_COMP_18_DN")
	)
	(segment
		(start 85.266022 -79.116936)
		(end 84.986622 -79.396336)
		(width 0.1397)
		(layer "In5.Cu")
		(net "PCIE_IOM_TO_COMP_18_DN")
	)
	(segment
		(start 116.099844 -37.00018)
		(end 116.099844 -36.61918)
		(width 0.1397)
		(layer "In5.Cu")
		(net "PCIE_IOM_TO_COMP_18_DN")
	)
	(segment
		(start 92.115386 -50.570638)
		(end 93.095826 -55.18277)
		(width 0.1397)
		(layer "In5.Cu")
		(net "PCIE_IOM_TO_COMP_18_DN")
	)
	(segment
		(start 89.094564 -74.681334)
		(end 86.781894 -78.241906)
		(width 0.1397)
		(layer "In5.Cu")
		(net "PCIE_IOM_TO_COMP_18_DN")
	)
	(segment
		(start 94.69882 -37.65677)
		(end 92.115386 -50.570638)
		(width 0.1397)
		(layer "In5.Cu")
		(net "PCIE_IOM_TO_COMP_18_DN")
	)
	(segment
		(start 115.034822 -30.173422)
		(end 112.12195 -27.26055)
		(width 0.1397)
		(layer "In5.Cu")
		(net "PCIE_IOM_TO_COMP_18_DN")
	)
	(segment
		(start 103.967534 -27.26055)
		(end 99.842574 -29.939488)
		(width 0.1397)
		(layer "In5.Cu")
		(net "PCIE_IOM_TO_COMP_18_DN")
	)
	(segment
		(start 112.12195 -27.26055)
		(end 103.967534 -27.26055)
		(width 0.1397)
		(layer "In5.Cu")
		(net "PCIE_IOM_TO_COMP_18_DN")
	)
	(segment
		(start 85.906864 -79.116936)
		(end 85.266022 -79.116936)
		(width 0.1397)
		(layer "In5.Cu")
		(net "PCIE_IOM_TO_COMP_18_DN")
	)
	(segment
		(start 93.095826 -55.18277)
		(end 89.094564 -74.681334)
		(width 0.1397)
		(layer "In5.Cu")
		(net "PCIE_IOM_TO_COMP_18_DN")
	)
	(segment
		(start 115.034822 -35.915854)
		(end 115.034822 -30.173422)
		(width 0.1397)
		(layer "In5.Cu")
		(net "PCIE_IOM_TO_COMP_18_DN")
	)
	(arc
		(start 116.099844 -36.61918)
		(mid 116.054761 -36.510339)
		(end 115.94592 -36.465256)
		(width 0.1397)
		(layer "In5.Cu")
		(net "PCIE_IOM_TO_COMP_18_DN")
	)
	(arc
		(start 115.584224 -36.465256)
		(mid 115.195738 -36.30434)
		(end 115.034822 -35.915854)
		(width 0.1397)
		(layer "In5.Cu")
		(net "PCIE_IOM_TO_COMP_18_DN")
	)
	(segment
		(start 81.28889 -75.59421)
		(end 82.660744 -75.59421)
		(width 0.14605)
		(layer "F.Cu")
		(net "PCIE_IOM_TO_COMP_17_DP")
	)
	(segment
		(start 81.044796 -75.350116)
		(end 81.28889 -75.59421)
		(width 0.14605)
		(layer "F.Cu")
		(net "PCIE_IOM_TO_COMP_17_DP")
	)
	(segment
		(start 79.925164 -75.350116)
		(end 81.044796 -75.350116)
		(width 0.14605)
		(layer "F.Cu")
		(net "PCIE_IOM_TO_COMP_17_DP")
	)
	(segment
		(start 82.660744 -75.59421)
		(end 82.660998 -75.593956)
		(width 0.14605)
		(layer "F.Cu")
		(net "PCIE_IOM_TO_COMP_17_DP")
	)
	(arc
		(start 82.660998 -75.593956)
		(mid 83.038335 -75.518899)
		(end 83.358228 -75.305158)
		(width 0.14605)
		(layer "F.Cu")
		(net "PCIE_IOM_TO_COMP_17_DP")
	)
	(segment
		(start 117.899942 -36.800028)
		(end 117.899942 -37.181028)
		(width 0.1397)
		(layer "In5.Cu")
		(net "PCIE_IOM_TO_COMP_17_DP")
	)
	(segment
		(start 83.64474 -75.59167)
		(end 83.358228 -75.305158)
		(width 0.1397)
		(layer "In5.Cu")
		(net "PCIE_IOM_TO_COMP_17_DP")
	)
	(segment
		(start 117.746018 -37.334952)
		(end 117.397784 -37.334952)
		(width 0.1397)
		(layer "In5.Cu")
		(net "PCIE_IOM_TO_COMP_17_DP")
	)
	(segment
		(start 90.131392 -51.461924)
		(end 91.34221 -57.159906)
		(width 0.1397)
		(layer "In5.Cu")
		(net "PCIE_IOM_TO_COMP_17_DP")
	)
	(segment
		(start 88.480138 -70.60946)
		(end 86.619588 -73.47458)
		(width 0.1397)
		(layer "In5.Cu")
		(net "PCIE_IOM_TO_COMP_17_DP")
	)
	(segment
		(start 116.3574 -28.1178)
		(end 115.503706 -28.1178)
		(width 0.1397)
		(layer "In5.Cu")
		(net "PCIE_IOM_TO_COMP_17_DP")
	)
	(segment
		(start 117.16512 -28.92552)
		(end 116.3574 -28.1178)
		(width 0.1397)
		(layer "In5.Cu")
		(net "PCIE_IOM_TO_COMP_17_DP")
	)
	(segment
		(start 91.34221 -57.159906)
		(end 88.480138 -70.60946)
		(width 0.1397)
		(layer "In5.Cu")
		(net "PCIE_IOM_TO_COMP_17_DP")
	)
	(segment
		(start 113.522506 -26.1366)
		(end 103.060754 -26.1366)
		(width 0.1397)
		(layer "In5.Cu")
		(net "PCIE_IOM_TO_COMP_17_DP")
	)
	(segment
		(start 86.619588 -73.47458)
		(end 84.502498 -75.59167)
		(width 0.1397)
		(layer "In5.Cu")
		(net "PCIE_IOM_TO_COMP_17_DP")
	)
	(segment
		(start 115.503706 -28.1178)
		(end 113.522506 -26.1366)
		(width 0.1397)
		(layer "In5.Cu")
		(net "PCIE_IOM_TO_COMP_17_DP")
	)
	(segment
		(start 90.592656 -49.29251)
		(end 90.131392 -51.461924)
		(width 0.1397)
		(layer "In5.Cu")
		(net "PCIE_IOM_TO_COMP_17_DP")
	)
	(segment
		(start 103.060754 -26.1366)
		(end 98.990912 -28.777946)
		(width 0.1397)
		(layer "In5.Cu")
		(net "PCIE_IOM_TO_COMP_17_DP")
	)
	(segment
		(start 93.07195 -37.631624)
		(end 90.592656 -49.29251)
		(width 0.1397)
		(layer "In5.Cu")
		(net "PCIE_IOM_TO_COMP_17_DP")
	)
	(segment
		(start 84.502498 -75.59167)
		(end 83.64474 -75.59167)
		(width 0.1397)
		(layer "In5.Cu")
		(net "PCIE_IOM_TO_COMP_17_DP")
	)
	(segment
		(start 117.16512 -37.102288)
		(end 117.16512 -28.92552)
		(width 0.1397)
		(layer "In5.Cu")
		(net "PCIE_IOM_TO_COMP_17_DP")
	)
	(segment
		(start 98.990912 -28.777946)
		(end 93.07195 -37.631624)
		(width 0.1397)
		(layer "In5.Cu")
		(net "PCIE_IOM_TO_COMP_17_DP")
	)
	(arc
		(start 117.397784 -37.334952)
		(mid 117.233266 -37.266806)
		(end 117.16512 -37.102288)
		(width 0.1397)
		(layer "In5.Cu")
		(net "PCIE_IOM_TO_COMP_17_DP")
	)
	(arc
		(start 117.899942 -37.181028)
		(mid 117.854859 -37.289869)
		(end 117.746018 -37.334952)
		(width 0.1397)
		(layer "In5.Cu")
		(net "PCIE_IOM_TO_COMP_17_DP")
	)
	(segment
		(start 81.070958 -76.149962)
		(end 81.31556 -75.90536)
		(width 0.14605)
		(layer "F.Cu")
		(net "PCIE_IOM_TO_COMP_17_DN")
	)
	(segment
		(start 79.925164 -76.149962)
		(end 81.070958 -76.149962)
		(width 0.14605)
		(layer "F.Cu")
		(net "PCIE_IOM_TO_COMP_17_DN")
	)
	(segment
		(start 81.31556 -75.90536)
		(end 82.660998 -75.90536)
		(width 0.14605)
		(layer "F.Cu")
		(net "PCIE_IOM_TO_COMP_17_DN")
	)
	(arc
		(start 82.660998 -75.90536)
		(mid 83.038335 -75.980417)
		(end 83.358228 -76.194158)
		(width 0.14605)
		(layer "F.Cu")
		(net "PCIE_IOM_TO_COMP_17_DN")
	)
	(segment
		(start 103.158544 -26.4668)
		(end 99.22764 -29.017976)
		(width 0.1397)
		(layer "In5.Cu")
		(net "PCIE_IOM_TO_COMP_17_DN")
	)
	(segment
		(start 86.877652 -73.683622)
		(end 84.639404 -75.92187)
		(width 0.1397)
		(layer "In5.Cu")
		(net "PCIE_IOM_TO_COMP_17_DN")
	)
	(segment
		(start 83.630516 -75.92187)
		(end 83.358228 -76.194158)
		(width 0.1397)
		(layer "In5.Cu")
		(net "PCIE_IOM_TO_COMP_17_DN")
	)
	(segment
		(start 91.68003 -57.159906)
		(end 88.790526 -70.737984)
		(width 0.1397)
		(layer "In5.Cu")
		(net "PCIE_IOM_TO_COMP_17_DN")
	)
	(segment
		(start 84.639404 -75.92187)
		(end 83.630516 -75.92187)
		(width 0.1397)
		(layer "In5.Cu")
		(net "PCIE_IOM_TO_COMP_17_DN")
	)
	(segment
		(start 90.915744 -49.36109)
		(end 90.469212 -51.461924)
		(width 0.1397)
		(layer "In5.Cu")
		(net "PCIE_IOM_TO_COMP_17_DN")
	)
	(segment
		(start 117.746018 -37.665152)
		(end 117.397784 -37.665152)
		(width 0.1397)
		(layer "In5.Cu")
		(net "PCIE_IOM_TO_COMP_17_DN")
	)
	(segment
		(start 117.899942 -38.200076)
		(end 117.899942 -37.819076)
		(width 0.1397)
		(layer "In5.Cu")
		(net "PCIE_IOM_TO_COMP_17_DN")
	)
	(segment
		(start 99.22764 -29.017976)
		(end 93.38183 -37.762434)
		(width 0.1397)
		(layer "In5.Cu")
		(net "PCIE_IOM_TO_COMP_17_DN")
	)
	(segment
		(start 116.220494 -28.448)
		(end 115.3668 -28.448)
		(width 0.1397)
		(layer "In5.Cu")
		(net "PCIE_IOM_TO_COMP_17_DN")
	)
	(segment
		(start 115.3668 -28.448)
		(end 113.3856 -26.4668)
		(width 0.1397)
		(layer "In5.Cu")
		(net "PCIE_IOM_TO_COMP_17_DN")
	)
	(segment
		(start 88.790526 -70.737984)
		(end 86.877652 -73.683622)
		(width 0.1397)
		(layer "In5.Cu")
		(net "PCIE_IOM_TO_COMP_17_DN")
	)
	(segment
		(start 116.83492 -37.102288)
		(end 116.83492 -29.062426)
		(width 0.1397)
		(layer "In5.Cu")
		(net "PCIE_IOM_TO_COMP_17_DN")
	)
	(segment
		(start 90.469212 -51.461924)
		(end 91.68003 -57.159906)
		(width 0.1397)
		(layer "In5.Cu")
		(net "PCIE_IOM_TO_COMP_17_DN")
	)
	(segment
		(start 113.3856 -26.4668)
		(end 103.158544 -26.4668)
		(width 0.1397)
		(layer "In5.Cu")
		(net "PCIE_IOM_TO_COMP_17_DN")
	)
	(segment
		(start 116.83492 -29.062426)
		(end 116.220494 -28.448)
		(width 0.1397)
		(layer "In5.Cu")
		(net "PCIE_IOM_TO_COMP_17_DN")
	)
	(segment
		(start 93.38183 -37.762434)
		(end 90.915744 -49.36109)
		(width 0.1397)
		(layer "In5.Cu")
		(net "PCIE_IOM_TO_COMP_17_DN")
	)
	(arc
		(start 117.397784 -37.665152)
		(mid 116.999779 -37.500293)
		(end 116.83492 -37.102288)
		(width 0.1397)
		(layer "In5.Cu")
		(net "PCIE_IOM_TO_COMP_17_DN")
	)
	(arc
		(start 117.899942 -37.819076)
		(mid 117.854859 -37.710235)
		(end 117.746018 -37.665152)
		(width 0.1397)
		(layer "In5.Cu")
		(net "PCIE_IOM_TO_COMP_17_DN")
	)
	(segment
		(start 84.165694 -72.387968)
		(end 84.165948 -72.387714)
		(width 0.14605)
		(layer "F.Cu")
		(net "PCIE_IOM_TO_COMP_16_DP")
	)
	(segment
		(start 80.964278 -72.14997)
		(end 81.202276 -72.387968)
		(width 0.14605)
		(layer "F.Cu")
		(net "PCIE_IOM_TO_COMP_16_DP")
	)
	(segment
		(start 81.202276 -72.387968)
		(end 84.165694 -72.387968)
		(width 0.14605)
		(layer "F.Cu")
		(net "PCIE_IOM_TO_COMP_16_DP")
	)
	(segment
		(start 79.925164 -72.14997)
		(end 80.964278 -72.14997)
		(width 0.14605)
		(layer "F.Cu")
		(net "PCIE_IOM_TO_COMP_16_DP")
	)
	(arc
		(start 84.165948 -72.387714)
		(mid 84.543285 -72.312657)
		(end 84.863178 -72.098916)
		(width 0.14605)
		(layer "F.Cu")
		(net "PCIE_IOM_TO_COMP_16_DP")
	)
	(segment
		(start 118.965218 -35.915854)
		(end 118.965218 -28.998418)
		(width 0.1397)
		(layer "In5.Cu")
		(net "PCIE_IOM_TO_COMP_16_DP")
	)
	(segment
		(start 85.142578 -72.378316)
		(end 84.863178 -72.098916)
		(width 0.1397)
		(layer "In5.Cu")
		(net "PCIE_IOM_TO_COMP_16_DP")
	)
	(segment
		(start 117.1702 -27.2034)
		(end 115.732306 -27.2034)
		(width 0.1397)
		(layer "In5.Cu")
		(net "PCIE_IOM_TO_COMP_16_DP")
	)
	(segment
		(start 88.3285 -48.683926)
		(end 90.113866 -57.081928)
		(width 0.1397)
		(layer "In5.Cu")
		(net "PCIE_IOM_TO_COMP_16_DP")
	)
	(segment
		(start 102.707694 -25.349962)
		(end 98.217228 -28.265882)
		(width 0.1397)
		(layer "In5.Cu")
		(net "PCIE_IOM_TO_COMP_16_DP")
	)
	(segment
		(start 98.217228 -28.265882)
		(end 91.98229 -37.56025)
		(width 0.1397)
		(layer "In5.Cu")
		(net "PCIE_IOM_TO_COMP_16_DP")
	)
	(segment
		(start 86.6902 -71.550276)
		(end 85.861652 -72.378316)
		(width 0.1397)
		(layer "In5.Cu")
		(net "PCIE_IOM_TO_COMP_16_DP")
	)
	(segment
		(start 91.355418 -40.508682)
		(end 89.439242 -43.4594)
		(width 0.1397)
		(layer "In5.Cu")
		(net "PCIE_IOM_TO_COMP_16_DP")
	)
	(segment
		(start 119.546116 -36.135056)
		(end 119.18442 -36.135056)
		(width 0.1397)
		(layer "In5.Cu")
		(net "PCIE_IOM_TO_COMP_16_DP")
	)
	(segment
		(start 90.113866 -57.081928)
		(end 87.34425 -70.24116)
		(width 0.1397)
		(layer "In5.Cu")
		(net "PCIE_IOM_TO_COMP_16_DP")
	)
	(segment
		(start 115.732306 -27.2034)
		(end 113.878868 -25.349962)
		(width 0.1397)
		(layer "In5.Cu")
		(net "PCIE_IOM_TO_COMP_16_DP")
	)
	(segment
		(start 87.34425 -70.24116)
		(end 86.6902 -71.550276)
		(width 0.1397)
		(layer "In5.Cu")
		(net "PCIE_IOM_TO_COMP_16_DP")
	)
	(segment
		(start 91.98229 -37.56025)
		(end 91.355418 -40.508682)
		(width 0.1397)
		(layer "In5.Cu")
		(net "PCIE_IOM_TO_COMP_16_DP")
	)
	(segment
		(start 113.878868 -25.349962)
		(end 102.707694 -25.349962)
		(width 0.1397)
		(layer "In5.Cu")
		(net "PCIE_IOM_TO_COMP_16_DP")
	)
	(segment
		(start 118.965218 -28.998418)
		(end 117.1702 -27.2034)
		(width 0.1397)
		(layer "In5.Cu")
		(net "PCIE_IOM_TO_COMP_16_DP")
	)
	(segment
		(start 85.861652 -72.378316)
		(end 85.142578 -72.378316)
		(width 0.1397)
		(layer "In5.Cu")
		(net "PCIE_IOM_TO_COMP_16_DP")
	)
	(segment
		(start 89.439242 -43.4594)
		(end 88.3285 -48.683926)
		(width 0.1397)
		(layer "In5.Cu")
		(net "PCIE_IOM_TO_COMP_16_DP")
	)
	(segment
		(start 119.70004 -35.600132)
		(end 119.70004 -35.981132)
		(width 0.1397)
		(layer "In5.Cu")
		(net "PCIE_IOM_TO_COMP_16_DP")
	)
	(arc
		(start 119.18442 -36.135056)
		(mid 119.029421 -36.070853)
		(end 118.965218 -35.915854)
		(width 0.1397)
		(layer "In5.Cu")
		(net "PCIE_IOM_TO_COMP_16_DP")
	)
	(arc
		(start 119.70004 -35.981132)
		(mid 119.654957 -36.089973)
		(end 119.546116 -36.135056)
		(width 0.1397)
		(layer "In5.Cu")
		(net "PCIE_IOM_TO_COMP_16_DP")
	)
	(segment
		(start 80.95234 -72.95007)
		(end 81.203292 -72.699118)
		(width 0.14605)
		(layer "F.Cu")
		(net "PCIE_IOM_TO_COMP_16_DN")
	)
	(segment
		(start 79.925164 -72.95007)
		(end 80.95234 -72.95007)
		(width 0.14605)
		(layer "F.Cu")
		(net "PCIE_IOM_TO_COMP_16_DN")
	)
	(segment
		(start 81.203292 -72.699118)
		(end 84.165948 -72.699118)
		(width 0.14605)
		(layer "F.Cu")
		(net "PCIE_IOM_TO_COMP_16_DN")
	)
	(arc
		(start 84.165948 -72.699118)
		(mid 84.543285 -72.774175)
		(end 84.863178 -72.987916)
		(width 0.14605)
		(layer "F.Cu")
		(net "PCIE_IOM_TO_COMP_16_DN")
	)
	(segment
		(start 119.546116 -36.465256)
		(end 119.18442 -36.465256)
		(width 0.1397)
		(layer "In5.Cu")
		(net "PCIE_IOM_TO_COMP_16_DN")
	)
	(segment
		(start 117.033294 -27.5336)
		(end 115.5954 -27.5336)
		(width 0.1397)
		(layer "In5.Cu")
		(net "PCIE_IOM_TO_COMP_16_DN")
	)
	(segment
		(start 86.961726 -71.745856)
		(end 85.998558 -72.708516)
		(width 0.1397)
		(layer "In5.Cu")
		(net "PCIE_IOM_TO_COMP_16_DN")
	)
	(segment
		(start 92.29217 -37.691314)
		(end 91.665806 -40.637206)
		(width 0.1397)
		(layer "In5.Cu")
		(net "PCIE_IOM_TO_COMP_16_DN")
	)
	(segment
		(start 102.805738 -25.680162)
		(end 98.453956 -28.506166)
		(width 0.1397)
		(layer "In5.Cu")
		(net "PCIE_IOM_TO_COMP_16_DN")
	)
	(segment
		(start 91.665806 -40.637206)
		(end 89.74963 -43.587924)
		(width 0.1397)
		(layer "In5.Cu")
		(net "PCIE_IOM_TO_COMP_16_DN")
	)
	(segment
		(start 98.453956 -28.506166)
		(end 92.29217 -37.691314)
		(width 0.1397)
		(layer "In5.Cu")
		(net "PCIE_IOM_TO_COMP_16_DN")
	)
	(segment
		(start 115.5954 -27.5336)
		(end 113.741962 -25.680162)
		(width 0.1397)
		(layer "In5.Cu")
		(net "PCIE_IOM_TO_COMP_16_DN")
	)
	(segment
		(start 119.70004 -37.00018)
		(end 119.70004 -36.61918)
		(width 0.1397)
		(layer "In5.Cu")
		(net "PCIE_IOM_TO_COMP_16_DN")
	)
	(segment
		(start 88.66632 -48.683926)
		(end 90.451432 -57.081674)
		(width 0.1397)
		(layer "In5.Cu")
		(net "PCIE_IOM_TO_COMP_16_DN")
	)
	(segment
		(start 87.658702 -70.350634)
		(end 86.961726 -71.745856)
		(width 0.1397)
		(layer "In5.Cu")
		(net "PCIE_IOM_TO_COMP_16_DN")
	)
	(segment
		(start 90.451432 -57.081674)
		(end 87.658702 -70.350634)
		(width 0.1397)
		(layer "In5.Cu")
		(net "PCIE_IOM_TO_COMP_16_DN")
	)
	(segment
		(start 85.142578 -72.708516)
		(end 84.863178 -72.987916)
		(width 0.1397)
		(layer "In5.Cu")
		(net "PCIE_IOM_TO_COMP_16_DN")
	)
	(segment
		(start 118.635018 -35.915854)
		(end 118.635018 -29.135324)
		(width 0.1397)
		(layer "In5.Cu")
		(net "PCIE_IOM_TO_COMP_16_DN")
	)
	(segment
		(start 85.998558 -72.708516)
		(end 85.142578 -72.708516)
		(width 0.1397)
		(layer "In5.Cu")
		(net "PCIE_IOM_TO_COMP_16_DN")
	)
	(segment
		(start 89.74963 -43.587924)
		(end 88.66632 -48.683926)
		(width 0.1397)
		(layer "In5.Cu")
		(net "PCIE_IOM_TO_COMP_16_DN")
	)
	(segment
		(start 118.635018 -29.135324)
		(end 117.033294 -27.5336)
		(width 0.1397)
		(layer "In5.Cu")
		(net "PCIE_IOM_TO_COMP_16_DN")
	)
	(segment
		(start 113.741962 -25.680162)
		(end 102.805738 -25.680162)
		(width 0.1397)
		(layer "In5.Cu")
		(net "PCIE_IOM_TO_COMP_16_DN")
	)
	(arc
		(start 119.18442 -36.465256)
		(mid 118.795934 -36.30434)
		(end 118.635018 -35.915854)
		(width 0.1397)
		(layer "In5.Cu")
		(net "PCIE_IOM_TO_COMP_16_DN")
	)
	(arc
		(start 119.70004 -36.61918)
		(mid 119.654957 -36.510339)
		(end 119.546116 -36.465256)
		(width 0.1397)
		(layer "In5.Cu")
		(net "PCIE_IOM_TO_COMP_16_DN")
	)
	(segment
		(start 167.650668 -137.216134)
		(end 167.773858 -137.092944)
		(width 0.14605)
		(layer "F.Cu")
		(net "PCIE_IOM_TO_COMP_15_DP")
	)
	(segment
		(start 171.548806 -136.111996)
		(end 171.548806 -135.8138)
		(width 0.14605)
		(layer "F.Cu")
		(net "PCIE_IOM_TO_COMP_15_DP")
	)
	(segment
		(start 171.649898 -135.712708)
		(end 171.649898 -134.875016)
		(width 0.14605)
		(layer "F.Cu")
		(net "PCIE_IOM_TO_COMP_15_DP")
	)
	(segment
		(start 168.026588 -136.988296)
		(end 170.672506 -136.988296)
		(width 0.14605)
		(layer "F.Cu")
		(net "PCIE_IOM_TO_COMP_15_DP")
	)
	(segment
		(start 167.74033 -137.534396)
		(end 167.650668 -137.444734)
		(width 0.14605)
		(layer "F.Cu")
		(net "PCIE_IOM_TO_COMP_15_DP")
	)
	(segment
		(start 170.672506 -136.988296)
		(end 171.548806 -136.111996)
		(width 0.14605)
		(layer "F.Cu")
		(net "PCIE_IOM_TO_COMP_15_DP")
	)
	(segment
		(start 171.548806 -135.8138)
		(end 171.649898 -135.712708)
		(width 0.14605)
		(layer "F.Cu")
		(net "PCIE_IOM_TO_COMP_15_DP")
	)
	(arc
		(start 167.650668 -137.444734)
		(mid 167.603323 -137.330434)
		(end 167.650668 -137.216134)
		(width 0.14605)
		(layer "F.Cu")
		(net "PCIE_IOM_TO_COMP_15_DP")
	)
	(arc
		(start 167.773858 -137.092944)
		(mid 167.889812 -137.015466)
		(end 168.026588 -136.988296)
		(width 0.14605)
		(layer "F.Cu")
		(net "PCIE_IOM_TO_COMP_15_DP")
	)
	(segment
		(start 157.137862 -30.26156)
		(end 156.90977 -29.910024)
		(width 0.1397)
		(layer "In5.Cu")
		(net "PCIE_IOM_TO_COMP_15_DP")
	)
	(segment
		(start 156.435552 -29.506164)
		(end 156.487622 -29.260292)
		(width 0.1397)
		(layer "In5.Cu")
		(net "PCIE_IOM_TO_COMP_15_DP")
	)
	(segment
		(start 167.434768 -137.444734)
		(end 167.201596 -137.677906)
		(width 0.1397)
		(layer "In5.Cu")
		(net "PCIE_IOM_TO_COMP_15_DP")
	)
	(segment
		(start 148.370036 -22.388576)
		(end 145.109692 -21.6916)
		(width 0.1397)
		(layer "In5.Cu")
		(net "PCIE_IOM_TO_COMP_15_DP")
	)
	(segment
		(start 168.979596 -79.161386)
		(end 159.287464 -33.571434)
		(width 0.1397)
		(layer "In5.Cu")
		(net "PCIE_IOM_TO_COMP_15_DP")
	)
	(segment
		(start 159.287464 -33.571434)
		(end 157.559756 -30.911292)
		(width 0.1397)
		(layer "In5.Cu")
		(net "PCIE_IOM_TO_COMP_15_DP")
	)
	(segment
		(start 157.313884 -30.858968)
		(end 157.085538 -30.507432)
		(width 0.1397)
		(layer "In5.Cu")
		(net "PCIE_IOM_TO_COMP_15_DP")
	)
	(segment
		(start 163.612322 -132.754878)
		(end 170.478196 -100.465128)
		(width 0.1397)
		(layer "In5.Cu")
		(net "PCIE_IOM_TO_COMP_15_DP")
	)
	(segment
		(start 166.003986 -137.677906)
		(end 164.252656 -135.92683)
		(width 0.1397)
		(layer "In5.Cu")
		(net "PCIE_IOM_TO_COMP_15_DP")
	)
	(segment
		(start 128.700022 -37.181028)
		(end 128.700022 -36.800028)
		(width 0.1397)
		(layer "In5.Cu")
		(net "PCIE_IOM_TO_COMP_15_DP")
	)
	(segment
		(start 156.90977 -29.910024)
		(end 156.663644 -29.8577)
		(width 0.1397)
		(layer "In5.Cu")
		(net "PCIE_IOM_TO_COMP_15_DP")
	)
	(segment
		(start 127.9652 -30.724602)
		(end 127.9652 -37.102288)
		(width 0.1397)
		(layer "In5.Cu")
		(net "PCIE_IOM_TO_COMP_15_DP")
	)
	(segment
		(start 167.46474 -86.288118)
		(end 168.979596 -79.161386)
		(width 0.1397)
		(layer "In5.Cu")
		(net "PCIE_IOM_TO_COMP_15_DP")
	)
	(segment
		(start 170.478196 -100.465128)
		(end 167.46474 -86.288118)
		(width 0.1397)
		(layer "In5.Cu")
		(net "PCIE_IOM_TO_COMP_15_DP")
	)
	(segment
		(start 154.691842 -26.49474)
		(end 148.370036 -22.388576)
		(width 0.1397)
		(layer "In5.Cu")
		(net "PCIE_IOM_TO_COMP_15_DP")
	)
	(segment
		(start 167.74033 -137.534396)
		(end 167.650668 -137.444734)
		(width 0.1397)
		(layer "In5.Cu")
		(net "PCIE_IOM_TO_COMP_15_DP")
	)
	(segment
		(start 164.251894 -135.926068)
		(end 164.22243 -135.896604)
		(width 0.1397)
		(layer "In5.Cu")
		(net "PCIE_IOM_TO_COMP_15_DP")
	)
	(segment
		(start 157.085538 -30.507432)
		(end 157.137862 -30.26156)
		(width 0.1397)
		(layer "In5.Cu")
		(net "PCIE_IOM_TO_COMP_15_DP")
	)
	(segment
		(start 156.663644 -29.8577)
		(end 156.435552 -29.506164)
		(width 0.1397)
		(layer "In5.Cu")
		(net "PCIE_IOM_TO_COMP_15_DP")
	)
	(segment
		(start 156.013404 -28.856432)
		(end 155.785312 -28.504896)
		(width 0.1397)
		(layer "In5.Cu")
		(net "PCIE_IOM_TO_COMP_15_DP")
	)
	(segment
		(start 155.837636 -28.259024)
		(end 154.691842 -26.49474)
		(width 0.1397)
		(layer "In5.Cu")
		(net "PCIE_IOM_TO_COMP_15_DP")
	)
	(segment
		(start 155.785312 -28.504896)
		(end 155.837636 -28.259024)
		(width 0.1397)
		(layer "In5.Cu")
		(net "PCIE_IOM_TO_COMP_15_DP")
	)
	(segment
		(start 157.559756 -30.911292)
		(end 157.313884 -30.858968)
		(width 0.1397)
		(layer "In5.Cu")
		(net "PCIE_IOM_TO_COMP_15_DP")
	)
	(segment
		(start 145.109692 -21.6916)
		(end 136.998202 -21.6916)
		(width 0.1397)
		(layer "In5.Cu")
		(net "PCIE_IOM_TO_COMP_15_DP")
	)
	(segment
		(start 156.25953 -28.908756)
		(end 156.013404 -28.856432)
		(width 0.1397)
		(layer "In5.Cu")
		(net "PCIE_IOM_TO_COMP_15_DP")
	)
	(segment
		(start 164.22243 -135.896604)
		(end 163.612322 -132.754878)
		(width 0.1397)
		(layer "In5.Cu")
		(net "PCIE_IOM_TO_COMP_15_DP")
	)
	(segment
		(start 136.998202 -21.6916)
		(end 127.9652 -30.724602)
		(width 0.1397)
		(layer "In5.Cu")
		(net "PCIE_IOM_TO_COMP_15_DP")
	)
	(segment
		(start 128.197864 -37.334952)
		(end 128.546098 -37.334952)
		(width 0.1397)
		(layer "In5.Cu")
		(net "PCIE_IOM_TO_COMP_15_DP")
	)
	(segment
		(start 156.487622 -29.260292)
		(end 156.25953 -28.908756)
		(width 0.1397)
		(layer "In5.Cu")
		(net "PCIE_IOM_TO_COMP_15_DP")
	)
	(arc
		(start 167.650668 -137.444734)
		(mid 167.542718 -137.40002)
		(end 167.434768 -137.444734)
		(width 0.1397)
		(layer "In5.Cu")
		(net "PCIE_IOM_TO_COMP_15_DP")
	)
	(arc
		(start 128.546098 -37.334952)
		(mid 128.654939 -37.289869)
		(end 128.700022 -37.181028)
		(width 0.1397)
		(layer "In5.Cu")
		(net "PCIE_IOM_TO_COMP_15_DP")
	)
	(arc
		(start 127.9652 -37.102288)
		(mid 128.033346 -37.266806)
		(end 128.197864 -37.334952)
		(width 0.1397)
		(layer "In5.Cu")
		(net "PCIE_IOM_TO_COMP_15_DP")
	)
	(arc
		(start 164.252656 -135.92683)
		(mid 164.252274 -135.92645)
		(end 164.251894 -135.926068)
		(width 0.1397)
		(layer "In5.Cu")
		(net "PCIE_IOM_TO_COMP_15_DP")
	)
	(arc
		(start 167.201596 -137.677906)
		(mid 166.602828 -137.925887)
		(end 166.003986 -137.677906)
		(width 0.1397)
		(layer "In5.Cu")
		(net "PCIE_IOM_TO_COMP_15_DP")
	)
	(segment
		(start 171.150026 -135.71982)
		(end 171.150026 -134.875016)
		(width 0.14605)
		(layer "F.Cu")
		(net "PCIE_IOM_TO_COMP_15_DN")
	)
	(segment
		(start 168.026842 -136.677146)
		(end 170.543474 -136.677146)
		(width 0.14605)
		(layer "F.Cu")
		(net "PCIE_IOM_TO_COMP_15_DN")
	)
	(segment
		(start 171.237656 -135.80745)
		(end 171.150026 -135.71982)
		(width 0.14605)
		(layer "F.Cu")
		(net "PCIE_IOM_TO_COMP_15_DN")
	)
	(segment
		(start 167.111934 -136.906)
		(end 167.201596 -136.995662)
		(width 0.14605)
		(layer "F.Cu")
		(net "PCIE_IOM_TO_COMP_15_DN")
	)
	(segment
		(start 167.55364 -136.872726)
		(end 167.55364 -136.87298)
		(width 0.14605)
		(layer "F.Cu")
		(net "PCIE_IOM_TO_COMP_15_DN")
	)
	(segment
		(start 170.543474 -136.677146)
		(end 171.237656 -135.982964)
		(width 0.14605)
		(layer "F.Cu")
		(net "PCIE_IOM_TO_COMP_15_DN")
	)
	(segment
		(start 171.237656 -135.982964)
		(end 171.237656 -135.80745)
		(width 0.14605)
		(layer "F.Cu")
		(net "PCIE_IOM_TO_COMP_15_DN")
	)
	(segment
		(start 167.430704 -136.995662)
		(end 167.55364 -136.872726)
		(width 0.14605)
		(layer "F.Cu")
		(net "PCIE_IOM_TO_COMP_15_DN")
	)
	(arc
		(start 167.55364 -136.87298)
		(mid 167.770749 -136.727972)
		(end 168.026842 -136.677146)
		(width 0.14605)
		(layer "F.Cu")
		(net "PCIE_IOM_TO_COMP_15_DN")
	)
	(arc
		(start 167.201596 -136.995662)
		(mid 167.31615 -137.043112)
		(end 167.430704 -136.995662)
		(width 0.14605)
		(layer "F.Cu")
		(net "PCIE_IOM_TO_COMP_15_DN")
	)
	(segment
		(start 148.498814 -22.078188)
		(end 145.144744 -21.3614)
		(width 0.1397)
		(layer "In5.Cu")
		(net "PCIE_IOM_TO_COMP_15_DN")
	)
	(segment
		(start 154.930602 -26.25598)
		(end 148.498814 -22.078188)
		(width 0.1397)
		(layer "In5.Cu")
		(net "PCIE_IOM_TO_COMP_15_DN")
	)
	(segment
		(start 170.816016 -100.465128)
		(end 167.80256 -86.288118)
		(width 0.1397)
		(layer "In5.Cu")
		(net "PCIE_IOM_TO_COMP_15_DN")
	)
	(segment
		(start 163.94938 -132.757926)
		(end 170.816016 -100.465128)
		(width 0.1397)
		(layer "In5.Cu")
		(net "PCIE_IOM_TO_COMP_15_DN")
	)
	(segment
		(start 167.201596 -137.210546)
		(end 166.967916 -137.444226)
		(width 0.1397)
		(layer "In5.Cu")
		(net "PCIE_IOM_TO_COMP_15_DN")
	)
	(segment
		(start 145.144744 -21.3614)
		(end 136.861296 -21.3614)
		(width 0.1397)
		(layer "In5.Cu")
		(net "PCIE_IOM_TO_COMP_15_DN")
	)
	(segment
		(start 164.527484 -135.734298)
		(end 163.94938 -132.757926)
		(width 0.1397)
		(layer "In5.Cu")
		(net "PCIE_IOM_TO_COMP_15_DN")
	)
	(segment
		(start 136.861296 -21.3614)
		(end 127.635 -30.587696)
		(width 0.1397)
		(layer "In5.Cu")
		(net "PCIE_IOM_TO_COMP_15_DN")
	)
	(segment
		(start 167.111934 -136.906)
		(end 167.201596 -136.995662)
		(width 0.1397)
		(layer "In5.Cu")
		(net "PCIE_IOM_TO_COMP_15_DN")
	)
	(segment
		(start 159.597852 -33.44291)
		(end 154.930602 -26.25598)
		(width 0.1397)
		(layer "In5.Cu")
		(net "PCIE_IOM_TO_COMP_15_DN")
	)
	(segment
		(start 169.317416 -79.161386)
		(end 159.597852 -33.44291)
		(width 0.1397)
		(layer "In5.Cu")
		(net "PCIE_IOM_TO_COMP_15_DN")
	)
	(segment
		(start 128.700022 -37.819076)
		(end 128.700022 -38.200076)
		(width 0.1397)
		(layer "In5.Cu")
		(net "PCIE_IOM_TO_COMP_15_DN")
	)
	(segment
		(start 167.80256 -86.288118)
		(end 169.317416 -79.161386)
		(width 0.1397)
		(layer "In5.Cu")
		(net "PCIE_IOM_TO_COMP_15_DN")
	)
	(segment
		(start 166.237666 -137.444226)
		(end 164.527484 -135.734298)
		(width 0.1397)
		(layer "In5.Cu")
		(net "PCIE_IOM_TO_COMP_15_DN")
	)
	(segment
		(start 127.635 -30.587696)
		(end 127.635 -37.102288)
		(width 0.1397)
		(layer "In5.Cu")
		(net "PCIE_IOM_TO_COMP_15_DN")
	)
	(segment
		(start 128.197864 -37.665152)
		(end 128.546098 -37.665152)
		(width 0.1397)
		(layer "In5.Cu")
		(net "PCIE_IOM_TO_COMP_15_DN")
	)
	(arc
		(start 128.546098 -37.665152)
		(mid 128.654939 -37.710235)
		(end 128.700022 -37.819076)
		(width 0.1397)
		(layer "In5.Cu")
		(net "PCIE_IOM_TO_COMP_15_DN")
	)
	(arc
		(start 166.967916 -137.444226)
		(mid 166.602828 -137.595413)
		(end 166.237666 -137.444226)
		(width 0.1397)
		(layer "In5.Cu")
		(net "PCIE_IOM_TO_COMP_15_DN")
	)
	(arc
		(start 167.201596 -136.995662)
		(mid 167.2461 -137.103104)
		(end 167.201596 -137.210546)
		(width 0.1397)
		(layer "In5.Cu")
		(net "PCIE_IOM_TO_COMP_15_DN")
	)
	(arc
		(start 127.635 -37.102288)
		(mid 127.799859 -37.500293)
		(end 128.197864 -37.665152)
		(width 0.1397)
		(layer "In5.Cu")
		(net "PCIE_IOM_TO_COMP_15_DN")
	)
	(segment
		(start 174.649892 -135.712708)
		(end 174.649892 -134.875016)
		(width 0.14605)
		(layer "F.Cu")
		(net "PCIE_IOM_TO_COMP_14_DP")
	)
	(segment
		(start 174.5488 -136.655048)
		(end 174.5488 -135.8138)
		(width 0.14605)
		(layer "F.Cu")
		(net "PCIE_IOM_TO_COMP_14_DP")
	)
	(segment
		(start 174.856648 -136.962896)
		(end 174.5488 -136.655048)
		(width 0.14605)
		(layer "F.Cu")
		(net "PCIE_IOM_TO_COMP_14_DP")
	)
	(segment
		(start 174.5488 -135.8138)
		(end 174.649892 -135.712708)
		(width 0.14605)
		(layer "F.Cu")
		(net "PCIE_IOM_TO_COMP_14_DP")
	)
	(segment
		(start 174.482506 -138.235182)
		(end 174.856648 -137.86104)
		(width 0.14605)
		(layer "F.Cu")
		(net "PCIE_IOM_TO_COMP_14_DP")
	)
	(segment
		(start 174.856648 -137.86104)
		(end 174.856648 -136.962896)
		(width 0.14605)
		(layer "F.Cu")
		(net "PCIE_IOM_TO_COMP_14_DP")
	)
	(segment
		(start 174.572168 -138.553444)
		(end 174.482506 -138.463782)
		(width 0.14605)
		(layer "F.Cu")
		(net "PCIE_IOM_TO_COMP_14_DP")
	)
	(arc
		(start 174.482506 -138.463782)
		(mid 174.435161 -138.349482)
		(end 174.482506 -138.235182)
		(width 0.14605)
		(layer "F.Cu")
		(net "PCIE_IOM_TO_COMP_14_DP")
	)
	(segment
		(start 165.800024 -85.839554)
		(end 167.300148 -78.782926)
		(width 0.1397)
		(layer "In5.Cu")
		(net "PCIE_IOM_TO_COMP_14_DP")
	)
	(segment
		(start 154.812238 -29.73324)
		(end 154.583892 -29.381704)
		(width 0.1397)
		(layer "In5.Cu")
		(net "PCIE_IOM_TO_COMP_14_DP")
	)
	(segment
		(start 171.345606 -140.773404)
		(end 167.118792 -139.951206)
		(width 0.1397)
		(layer "In5.Cu")
		(net "PCIE_IOM_TO_COMP_14_DP")
	)
	(segment
		(start 162.483038 -132.910072)
		(end 169.037508 -101.072442)
		(width 0.1397)
		(layer "In5.Cu")
		(net "PCIE_IOM_TO_COMP_14_DP")
	)
	(segment
		(start 167.053006 -139.938506)
		(end 166.997126 -139.900914)
		(width 0.1397)
		(layer "In5.Cu")
		(net "PCIE_IOM_TO_COMP_14_DP")
	)
	(segment
		(start 153.204418 -27.257248)
		(end 147.715478 -23.692866)
		(width 0.1397)
		(layer "In5.Cu")
		(net "PCIE_IOM_TO_COMP_14_DP")
	)
	(segment
		(start 174.266606 -138.463782)
		(end 174.098458 -138.63193)
		(width 0.1397)
		(layer "In5.Cu")
		(net "PCIE_IOM_TO_COMP_14_DP")
	)
	(segment
		(start 129.765044 -30.268418)
		(end 129.765044 -35.915854)
		(width 0.1397)
		(layer "In5.Cu")
		(net "PCIE_IOM_TO_COMP_14_DP")
	)
	(segment
		(start 156.06014 -31.981648)
		(end 156.112464 -31.735776)
		(width 0.1397)
		(layer "In5.Cu")
		(net "PCIE_IOM_TO_COMP_14_DP")
	)
	(segment
		(start 154.109674 -28.977844)
		(end 154.161998 -28.731972)
		(width 0.1397)
		(layer "In5.Cu")
		(net "PCIE_IOM_TO_COMP_14_DP")
	)
	(segment
		(start 166.997126 -139.900914)
		(end 164.430456 -138.16965)
		(width 0.1397)
		(layer "In5.Cu")
		(net "PCIE_IOM_TO_COMP_14_DP")
	)
	(segment
		(start 155.884118 -31.38424)
		(end 155.638246 -31.331916)
		(width 0.1397)
		(layer "In5.Cu")
		(net "PCIE_IOM_TO_COMP_14_DP")
	)
	(segment
		(start 155.638246 -31.331916)
		(end 155.4099 -30.98038)
		(width 0.1397)
		(layer "In5.Cu")
		(net "PCIE_IOM_TO_COMP_14_DP")
	)
	(segment
		(start 167.300148 -78.782926)
		(end 157.880558 -34.458656)
		(width 0.1397)
		(layer "In5.Cu")
		(net "PCIE_IOM_TO_COMP_14_DP")
	)
	(segment
		(start 163.130992 -136.24306)
		(end 162.483038 -132.910072)
		(width 0.1397)
		(layer "In5.Cu")
		(net "PCIE_IOM_TO_COMP_14_DP")
	)
	(segment
		(start 155.234132 -30.382972)
		(end 154.988006 -30.330648)
		(width 0.1397)
		(layer "In5.Cu")
		(net "PCIE_IOM_TO_COMP_14_DP")
	)
	(segment
		(start 164.430456 -138.16965)
		(end 163.130992 -136.24306)
		(width 0.1397)
		(layer "In5.Cu")
		(net "PCIE_IOM_TO_COMP_14_DP")
	)
	(segment
		(start 156.112464 -31.735776)
		(end 155.884118 -31.38424)
		(width 0.1397)
		(layer "In5.Cu")
		(net "PCIE_IOM_TO_COMP_14_DP")
	)
	(segment
		(start 154.33802 -29.32938)
		(end 154.109674 -28.977844)
		(width 0.1397)
		(layer "In5.Cu")
		(net "PCIE_IOM_TO_COMP_14_DP")
	)
	(segment
		(start 130.499866 -35.981132)
		(end 130.499866 -35.600132)
		(width 0.1397)
		(layer "In5.Cu")
		(net "PCIE_IOM_TO_COMP_14_DP")
	)
	(segment
		(start 174.572168 -138.553444)
		(end 174.482506 -138.463782)
		(width 0.1397)
		(layer "In5.Cu")
		(net "PCIE_IOM_TO_COMP_14_DP")
	)
	(segment
		(start 144.343882 -22.9616)
		(end 137.071862 -22.9616)
		(width 0.1397)
		(layer "In5.Cu")
		(net "PCIE_IOM_TO_COMP_14_DP")
	)
	(segment
		(start 167.118792 -139.95146)
		(end 167.053006 -139.938506)
		(width 0.1397)
		(layer "In5.Cu")
		(net "PCIE_IOM_TO_COMP_14_DP")
	)
	(segment
		(start 154.583892 -29.381704)
		(end 154.33802 -29.32938)
		(width 0.1397)
		(layer "In5.Cu")
		(net "PCIE_IOM_TO_COMP_14_DP")
	)
	(segment
		(start 147.715478 -23.692866)
		(end 144.343882 -22.9616)
		(width 0.1397)
		(layer "In5.Cu")
		(net "PCIE_IOM_TO_COMP_14_DP")
	)
	(segment
		(start 129.984246 -36.135056)
		(end 130.345942 -36.135056)
		(width 0.1397)
		(layer "In5.Cu")
		(net "PCIE_IOM_TO_COMP_14_DP")
	)
	(segment
		(start 155.4099 -30.98038)
		(end 155.462224 -30.734508)
		(width 0.1397)
		(layer "In5.Cu")
		(net "PCIE_IOM_TO_COMP_14_DP")
	)
	(segment
		(start 156.534358 -32.385508)
		(end 156.288486 -32.333184)
		(width 0.1397)
		(layer "In5.Cu")
		(net "PCIE_IOM_TO_COMP_14_DP")
	)
	(segment
		(start 167.118792 -139.951206)
		(end 167.118792 -139.95146)
		(width 0.1397)
		(layer "In5.Cu")
		(net "PCIE_IOM_TO_COMP_14_DP")
	)
	(segment
		(start 173.206664 -138.950446)
		(end 173.063154 -139.093956)
		(width 0.1397)
		(layer "In5.Cu")
		(net "PCIE_IOM_TO_COMP_14_DP")
	)
	(segment
		(start 172.894752 -139.413742)
		(end 172.894752 -139.698476)
		(width 0.1397)
		(layer "In5.Cu")
		(net "PCIE_IOM_TO_COMP_14_DP")
	)
	(segment
		(start 154.988006 -30.330648)
		(end 154.759914 -29.979112)
		(width 0.1397)
		(layer "In5.Cu")
		(net "PCIE_IOM_TO_COMP_14_DP")
	)
	(segment
		(start 157.880558 -34.458656)
		(end 156.534358 -32.385508)
		(width 0.1397)
		(layer "In5.Cu")
		(net "PCIE_IOM_TO_COMP_14_DP")
	)
	(segment
		(start 155.462224 -30.734508)
		(end 155.234132 -30.382972)
		(width 0.1397)
		(layer "In5.Cu")
		(net "PCIE_IOM_TO_COMP_14_DP")
	)
	(segment
		(start 154.161998 -28.731972)
		(end 153.204418 -27.257248)
		(width 0.1397)
		(layer "In5.Cu")
		(net "PCIE_IOM_TO_COMP_14_DP")
	)
	(segment
		(start 172.260514 -140.595096)
		(end 171.345606 -140.773404)
		(width 0.1397)
		(layer "In5.Cu")
		(net "PCIE_IOM_TO_COMP_14_DP")
	)
	(segment
		(start 156.288486 -32.333184)
		(end 156.06014 -31.981648)
		(width 0.1397)
		(layer "In5.Cu")
		(net "PCIE_IOM_TO_COMP_14_DP")
	)
	(segment
		(start 137.071862 -22.9616)
		(end 129.765044 -30.268418)
		(width 0.1397)
		(layer "In5.Cu")
		(net "PCIE_IOM_TO_COMP_14_DP")
	)
	(segment
		(start 169.037508 -101.072442)
		(end 165.800024 -85.839554)
		(width 0.1397)
		(layer "In5.Cu")
		(net "PCIE_IOM_TO_COMP_14_DP")
	)
	(segment
		(start 154.759914 -29.979112)
		(end 154.812238 -29.73324)
		(width 0.1397)
		(layer "In5.Cu")
		(net "PCIE_IOM_TO_COMP_14_DP")
	)
	(arc
		(start 172.283628 -140.585698)
		(mid 172.27202 -140.590271)
		(end 172.260514 -140.595096)
		(width 0.1397)
		(layer "In5.Cu")
		(net "PCIE_IOM_TO_COMP_14_DP")
	)
	(arc
		(start 173.61916 -138.790172)
		(mid 173.397895 -138.831653)
		(end 173.206664 -138.950446)
		(width 0.1397)
		(layer "In5.Cu")
		(net "PCIE_IOM_TO_COMP_14_DP")
	)
	(arc
		(start 174.098458 -138.63193)
		(mid 174.068668 -138.656828)
		(end 174.036228 -138.678158)
		(width 0.1397)
		(layer "In5.Cu")
		(net "PCIE_IOM_TO_COMP_14_DP")
	)
	(arc
		(start 174.036228 -138.678158)
		(mid 173.835087 -138.761679)
		(end 173.61916 -138.790172)
		(width 0.1397)
		(layer "In5.Cu")
		(net "PCIE_IOM_TO_COMP_14_DP")
	)
	(arc
		(start 174.482506 -138.463782)
		(mid 174.374556 -138.419068)
		(end 174.266606 -138.463782)
		(width 0.1397)
		(layer "In5.Cu")
		(net "PCIE_IOM_TO_COMP_14_DP")
	)
	(arc
		(start 173.063154 -139.093956)
		(mid 172.97258 -139.206668)
		(end 172.908468 -139.336272)
		(width 0.1397)
		(layer "In5.Cu")
		(net "PCIE_IOM_TO_COMP_14_DP")
	)
	(arc
		(start 172.908468 -139.336272)
		(mid 172.898204 -139.374404)
		(end 172.894752 -139.413742)
		(width 0.1397)
		(layer "In5.Cu")
		(net "PCIE_IOM_TO_COMP_14_DP")
	)
	(arc
		(start 129.765044 -35.915854)
		(mid 129.829247 -36.070853)
		(end 129.984246 -36.135056)
		(width 0.1397)
		(layer "In5.Cu")
		(net "PCIE_IOM_TO_COMP_14_DP")
	)
	(arc
		(start 172.894752 -139.698476)
		(mid 172.727197 -140.237161)
		(end 172.283628 -140.585698)
		(width 0.1397)
		(layer "In5.Cu")
		(net "PCIE_IOM_TO_COMP_14_DP")
	)
	(arc
		(start 130.345942 -36.135056)
		(mid 130.454783 -36.089973)
		(end 130.499866 -35.981132)
		(width 0.1397)
		(layer "In5.Cu")
		(net "PCIE_IOM_TO_COMP_14_DP")
	)
	(segment
		(start 174.23765 -136.78408)
		(end 174.23765 -135.80745)
		(width 0.14605)
		(layer "F.Cu")
		(net "PCIE_IOM_TO_COMP_14_DN")
	)
	(segment
		(start 174.15002 -135.71982)
		(end 174.15002 -134.875016)
		(width 0.14605)
		(layer "F.Cu")
		(net "PCIE_IOM_TO_COMP_14_DN")
	)
	(segment
		(start 174.262542 -138.01471)
		(end 174.545498 -137.731754)
		(width 0.14605)
		(layer "F.Cu")
		(net "PCIE_IOM_TO_COMP_14_DN")
	)
	(segment
		(start 174.545498 -137.091928)
		(end 174.23765 -136.78408)
		(width 0.14605)
		(layer "F.Cu")
		(net "PCIE_IOM_TO_COMP_14_DN")
	)
	(segment
		(start 173.943772 -137.925048)
		(end 174.033434 -138.01471)
		(width 0.14605)
		(layer "F.Cu")
		(net "PCIE_IOM_TO_COMP_14_DN")
	)
	(segment
		(start 174.23765 -135.80745)
		(end 174.15002 -135.71982)
		(width 0.14605)
		(layer "F.Cu")
		(net "PCIE_IOM_TO_COMP_14_DN")
	)
	(segment
		(start 174.545498 -137.731754)
		(end 174.545498 -137.091928)
		(width 0.14605)
		(layer "F.Cu")
		(net "PCIE_IOM_TO_COMP_14_DN")
	)
	(arc
		(start 174.033434 -138.01471)
		(mid 174.147988 -138.06216)
		(end 174.262542 -138.01471)
		(width 0.14605)
		(layer "F.Cu")
		(net "PCIE_IOM_TO_COMP_14_DN")
	)
	(segment
		(start 172.977556 -138.712194)
		(end 172.829474 -138.860276)
		(width 0.1397)
		(layer "In5.Cu")
		(net "PCIE_IOM_TO_COMP_14_DN")
	)
	(segment
		(start 164.668454 -137.931652)
		(end 163.442396 -136.114028)
		(width 0.1397)
		(layer "In5.Cu")
		(net "PCIE_IOM_TO_COMP_14_DN")
	)
	(segment
		(start 171.345606 -140.436854)
		(end 167.182038 -139.627102)
		(width 0.1397)
		(layer "In5.Cu")
		(net "PCIE_IOM_TO_COMP_14_DN")
	)
	(segment
		(start 129.434844 -30.131512)
		(end 129.434844 -35.915854)
		(width 0.1397)
		(layer "In5.Cu")
		(net "PCIE_IOM_TO_COMP_14_DN")
	)
	(segment
		(start 167.637968 -78.782926)
		(end 158.190946 -34.330132)
		(width 0.1397)
		(layer "In5.Cu")
		(net "PCIE_IOM_TO_COMP_14_DN")
	)
	(segment
		(start 129.984246 -36.465256)
		(end 130.345942 -36.465256)
		(width 0.1397)
		(layer "In5.Cu")
		(net "PCIE_IOM_TO_COMP_14_DN")
	)
	(segment
		(start 147.844764 -23.382732)
		(end 144.379442 -22.6314)
		(width 0.1397)
		(layer "In5.Cu")
		(net "PCIE_IOM_TO_COMP_14_DN")
	)
	(segment
		(start 130.499866 -36.61918)
		(end 130.499866 -37.00018)
		(width 0.1397)
		(layer "In5.Cu")
		(net "PCIE_IOM_TO_COMP_14_DN")
	)
	(segment
		(start 162.819842 -132.91185)
		(end 169.375074 -101.071426)
		(width 0.1397)
		(layer "In5.Cu")
		(net "PCIE_IOM_TO_COMP_14_DN")
	)
	(segment
		(start 172.564552 -139.413742)
		(end 172.564552 -139.698476)
		(width 0.1397)
		(layer "In5.Cu")
		(net "PCIE_IOM_TO_COMP_14_DN")
	)
	(segment
		(start 153.443178 -27.018488)
		(end 147.844764 -23.382732)
		(width 0.1397)
		(layer "In5.Cu")
		(net "PCIE_IOM_TO_COMP_14_DN")
	)
	(segment
		(start 163.442396 -136.114028)
		(end 162.819842 -132.91185)
		(width 0.1397)
		(layer "In5.Cu")
		(net "PCIE_IOM_TO_COMP_14_DN")
	)
	(segment
		(start 167.182038 -139.627102)
		(end 164.668454 -137.931652)
		(width 0.1397)
		(layer "In5.Cu")
		(net "PCIE_IOM_TO_COMP_14_DN")
	)
	(segment
		(start 174.033434 -138.229594)
		(end 173.87062 -138.392408)
		(width 0.1397)
		(layer "In5.Cu")
		(net "PCIE_IOM_TO_COMP_14_DN")
	)
	(segment
		(start 171.831 -140.342366)
		(end 171.345606 -140.436854)
		(width 0.1397)
		(layer "In5.Cu")
		(net "PCIE_IOM_TO_COMP_14_DN")
	)
	(segment
		(start 173.943772 -137.925048)
		(end 174.033434 -138.01471)
		(width 0.1397)
		(layer "In5.Cu")
		(net "PCIE_IOM_TO_COMP_14_DN")
	)
	(segment
		(start 169.375074 -101.071426)
		(end 166.137844 -85.839554)
		(width 0.1397)
		(layer "In5.Cu")
		(net "PCIE_IOM_TO_COMP_14_DN")
	)
	(segment
		(start 166.137844 -85.839554)
		(end 167.637968 -78.782926)
		(width 0.1397)
		(layer "In5.Cu")
		(net "PCIE_IOM_TO_COMP_14_DN")
	)
	(segment
		(start 172.166026 -140.277088)
		(end 171.831 -140.342366)
		(width 0.1397)
		(layer "In5.Cu")
		(net "PCIE_IOM_TO_COMP_14_DN")
	)
	(segment
		(start 158.190946 -34.330132)
		(end 153.443178 -27.018488)
		(width 0.1397)
		(layer "In5.Cu")
		(net "PCIE_IOM_TO_COMP_14_DN")
	)
	(segment
		(start 144.379442 -22.6314)
		(end 136.934956 -22.6314)
		(width 0.1397)
		(layer "In5.Cu")
		(net "PCIE_IOM_TO_COMP_14_DN")
	)
	(segment
		(start 136.934956 -22.6314)
		(end 129.434844 -30.131512)
		(width 0.1397)
		(layer "In5.Cu")
		(net "PCIE_IOM_TO_COMP_14_DN")
	)
	(arc
		(start 173.87062 -138.392408)
		(mid 173.749351 -138.442794)
		(end 173.61916 -138.459972)
		(width 0.1397)
		(layer "In5.Cu")
		(net "PCIE_IOM_TO_COMP_14_DN")
	)
	(arc
		(start 173.61916 -138.459972)
		(mid 173.274452 -138.525258)
		(end 172.977556 -138.712194)
		(width 0.1397)
		(layer "In5.Cu")
		(net "PCIE_IOM_TO_COMP_14_DN")
	)
	(arc
		(start 129.434844 -35.915854)
		(mid 129.59576 -36.30434)
		(end 129.984246 -36.465256)
		(width 0.1397)
		(layer "In5.Cu")
		(net "PCIE_IOM_TO_COMP_14_DN")
	)
	(arc
		(start 174.033434 -138.01471)
		(mid 174.077938 -138.122152)
		(end 174.033434 -138.229594)
		(width 0.1397)
		(layer "In5.Cu")
		(net "PCIE_IOM_TO_COMP_14_DN")
	)
	(arc
		(start 172.564552 -139.698476)
		(mid 172.455276 -140.049756)
		(end 172.166026 -140.277088)
		(width 0.1397)
		(layer "In5.Cu")
		(net "PCIE_IOM_TO_COMP_14_DN")
	)
	(arc
		(start 172.59808 -139.222734)
		(mid 172.572909 -139.316764)
		(end 172.564552 -139.413742)
		(width 0.1397)
		(layer "In5.Cu")
		(net "PCIE_IOM_TO_COMP_14_DN")
	)
	(arc
		(start 172.829474 -138.860276)
		(mid 172.694004 -139.028881)
		(end 172.59808 -139.222734)
		(width 0.1397)
		(layer "In5.Cu")
		(net "PCIE_IOM_TO_COMP_14_DN")
	)
	(arc
		(start 130.345942 -36.465256)
		(mid 130.454783 -36.510339)
		(end 130.499866 -36.61918)
		(width 0.1397)
		(layer "In5.Cu")
		(net "PCIE_IOM_TO_COMP_14_DN")
	)
	(segment
		(start 178.40579 -138.982196)
		(end 178.115722 -138.692128)
		(width 0.14605)
		(layer "F.Cu")
		(net "PCIE_IOM_TO_COMP_13_DP")
	)
	(segment
		(start 178.289458 -140.602208)
		(end 178.199796 -140.512546)
		(width 0.14605)
		(layer "F.Cu")
		(net "PCIE_IOM_TO_COMP_13_DP")
	)
	(segment
		(start 178.115722 -138.692128)
		(end 178.115468 -138.692128)
		(width 0.14605)
		(layer "F.Cu")
		(net "PCIE_IOM_TO_COMP_13_DP")
	)
	(segment
		(start 177.649886 -135.712708)
		(end 177.649886 -134.875016)
		(width 0.14605)
		(layer "F.Cu")
		(net "PCIE_IOM_TO_COMP_13_DP")
	)
	(segment
		(start 178.115468 -138.692128)
		(end 177.548794 -138.125454)
		(width 0.14605)
		(layer "F.Cu")
		(net "PCIE_IOM_TO_COMP_13_DP")
	)
	(segment
		(start 177.548794 -135.8138)
		(end 177.649886 -135.712708)
		(width 0.14605)
		(layer "F.Cu")
		(net "PCIE_IOM_TO_COMP_13_DP")
	)
	(segment
		(start 178.199796 -140.283946)
		(end 178.40579 -140.077952)
		(width 0.14605)
		(layer "F.Cu")
		(net "PCIE_IOM_TO_COMP_13_DP")
	)
	(segment
		(start 177.548794 -138.125454)
		(end 177.548794 -135.8138)
		(width 0.14605)
		(layer "F.Cu")
		(net "PCIE_IOM_TO_COMP_13_DP")
	)
	(arc
		(start 178.199796 -140.512546)
		(mid 178.152451 -140.398246)
		(end 178.199796 -140.283946)
		(width 0.14605)
		(layer "F.Cu")
		(net "PCIE_IOM_TO_COMP_13_DP")
	)
	(arc
		(start 178.40579 -140.077952)
		(mid 178.632728 -139.530074)
		(end 178.40579 -138.982196)
		(width 0.14605)
		(layer "F.Cu")
		(net "PCIE_IOM_TO_COMP_13_DP")
	)
	(segment
		(start 167.5384 -101.985064)
		(end 164.04844 -85.565742)
		(width 0.1397)
		(layer "In5.Cu")
		(net "PCIE_IOM_TO_COMP_13_DP")
	)
	(segment
		(start 153.720038 -31.48711)
		(end 153.491692 -31.135828)
		(width 0.1397)
		(layer "In5.Cu")
		(net "PCIE_IOM_TO_COMP_13_DP")
	)
	(segment
		(start 152.893776 -29.888434)
		(end 151.718518 -28.078684)
		(width 0.1397)
		(layer "In5.Cu")
		(net "PCIE_IOM_TO_COMP_13_DP")
	)
	(segment
		(start 154.141932 -32.136842)
		(end 154.194256 -31.89097)
		(width 0.1397)
		(layer "In5.Cu")
		(net "PCIE_IOM_TO_COMP_13_DP")
	)
	(segment
		(start 131.565142 -29.851858)
		(end 131.565142 -37.102288)
		(width 0.1397)
		(layer "In5.Cu")
		(net "PCIE_IOM_TO_COMP_13_DP")
	)
	(segment
		(start 154.370278 -32.488378)
		(end 154.141932 -32.136842)
		(width 0.1397)
		(layer "In5.Cu")
		(net "PCIE_IOM_TO_COMP_13_DP")
	)
	(segment
		(start 178.289458 -140.602208)
		(end 178.199796 -140.512546)
		(width 0.1397)
		(layer "In5.Cu")
		(net "PCIE_IOM_TO_COMP_13_DP")
	)
	(segment
		(start 156.50337 -35.446716)
		(end 154.61615 -32.540702)
		(width 0.1397)
		(layer "In5.Cu")
		(net "PCIE_IOM_TO_COMP_13_DP")
	)
	(segment
		(start 177.983896 -140.512546)
		(end 177.571654 -140.924788)
		(width 0.1397)
		(layer "In5.Cu")
		(net "PCIE_IOM_TO_COMP_13_DP")
	)
	(segment
		(start 153.31567 -30.538166)
		(end 153.069798 -30.486096)
		(width 0.1397)
		(layer "In5.Cu")
		(net "PCIE_IOM_TO_COMP_13_DP")
	)
	(segment
		(start 175.719486 -142.602966)
		(end 166.260018 -140.718794)
		(width 0.1397)
		(layer "In5.Cu")
		(net "PCIE_IOM_TO_COMP_13_DP")
	)
	(segment
		(start 152.841706 -30.13456)
		(end 152.893776 -29.888434)
		(width 0.1397)
		(layer "In5.Cu")
		(net "PCIE_IOM_TO_COMP_13_DP")
	)
	(segment
		(start 164.04844 -85.565742)
		(end 165.602158 -78.253082)
		(width 0.1397)
		(layer "In5.Cu")
		(net "PCIE_IOM_TO_COMP_13_DP")
	)
	(segment
		(start 153.544016 -30.889702)
		(end 153.31567 -30.538166)
		(width 0.1397)
		(layer "In5.Cu")
		(net "PCIE_IOM_TO_COMP_13_DP")
	)
	(segment
		(start 165.602158 -78.253082)
		(end 156.50337 -35.446716)
		(width 0.1397)
		(layer "In5.Cu")
		(net "PCIE_IOM_TO_COMP_13_DP")
	)
	(segment
		(start 162.10661 -136.799066)
		(end 161.2773 -132.545074)
		(width 0.1397)
		(layer "In5.Cu")
		(net "PCIE_IOM_TO_COMP_13_DP")
	)
	(segment
		(start 176.681892 -142.24508)
		(end 176.163732 -142.516606)
		(width 0.1397)
		(layer "In5.Cu")
		(net "PCIE_IOM_TO_COMP_13_DP")
	)
	(segment
		(start 153.491692 -31.135828)
		(end 153.544016 -30.889702)
		(width 0.1397)
		(layer "In5.Cu")
		(net "PCIE_IOM_TO_COMP_13_DP")
	)
	(segment
		(start 177.571654 -140.924788)
		(end 176.681892 -142.24508)
		(width 0.1397)
		(layer "In5.Cu")
		(net "PCIE_IOM_TO_COMP_13_DP")
	)
	(segment
		(start 151.718518 -28.078684)
		(end 147.013168 -25.00503)
		(width 0.1397)
		(layer "In5.Cu")
		(net "PCIE_IOM_TO_COMP_13_DP")
	)
	(segment
		(start 144.140682 -24.430228)
		(end 136.986772 -24.430228)
		(width 0.1397)
		(layer "In5.Cu")
		(net "PCIE_IOM_TO_COMP_13_DP")
	)
	(segment
		(start 154.194256 -31.89097)
		(end 153.96591 -31.539434)
		(width 0.1397)
		(layer "In5.Cu")
		(net "PCIE_IOM_TO_COMP_13_DP")
	)
	(segment
		(start 132.299964 -37.181028)
		(end 132.299964 -36.800028)
		(width 0.1397)
		(layer "In5.Cu")
		(net "PCIE_IOM_TO_COMP_13_DP")
	)
	(segment
		(start 131.797806 -37.334952)
		(end 132.14604 -37.334952)
		(width 0.1397)
		(layer "In5.Cu")
		(net "PCIE_IOM_TO_COMP_13_DP")
	)
	(segment
		(start 153.96591 -31.539434)
		(end 153.720038 -31.48711)
		(width 0.1397)
		(layer "In5.Cu")
		(net "PCIE_IOM_TO_COMP_13_DP")
	)
	(segment
		(start 166.260018 -140.718794)
		(end 163.489386 -138.849608)
		(width 0.1397)
		(layer "In5.Cu")
		(net "PCIE_IOM_TO_COMP_13_DP")
	)
	(segment
		(start 147.013168 -25.00503)
		(end 144.140682 -24.430228)
		(width 0.1397)
		(layer "In5.Cu")
		(net "PCIE_IOM_TO_COMP_13_DP")
	)
	(segment
		(start 176.163732 -142.516606)
		(end 175.719486 -142.602966)
		(width 0.1397)
		(layer "In5.Cu")
		(net "PCIE_IOM_TO_COMP_13_DP")
	)
	(segment
		(start 154.61615 -32.540702)
		(end 154.370278 -32.488378)
		(width 0.1397)
		(layer "In5.Cu")
		(net "PCIE_IOM_TO_COMP_13_DP")
	)
	(segment
		(start 136.986772 -24.430228)
		(end 131.565142 -29.851858)
		(width 0.1397)
		(layer "In5.Cu")
		(net "PCIE_IOM_TO_COMP_13_DP")
	)
	(segment
		(start 153.069798 -30.486096)
		(end 152.841706 -30.13456)
		(width 0.1397)
		(layer "In5.Cu")
		(net "PCIE_IOM_TO_COMP_13_DP")
	)
	(segment
		(start 163.489386 -138.849608)
		(end 162.10661 -136.799066)
		(width 0.1397)
		(layer "In5.Cu")
		(net "PCIE_IOM_TO_COMP_13_DP")
	)
	(segment
		(start 161.2773 -132.545074)
		(end 167.5384 -101.985064)
		(width 0.1397)
		(layer "In5.Cu")
		(net "PCIE_IOM_TO_COMP_13_DP")
	)
	(arc
		(start 178.199796 -140.512546)
		(mid 178.091846 -140.467832)
		(end 177.983896 -140.512546)
		(width 0.1397)
		(layer "In5.Cu")
		(net "PCIE_IOM_TO_COMP_13_DP")
	)
	(arc
		(start 132.14604 -37.334952)
		(mid 132.254881 -37.289869)
		(end 132.299964 -37.181028)
		(width 0.1397)
		(layer "In5.Cu")
		(net "PCIE_IOM_TO_COMP_13_DP")
	)
	(arc
		(start 131.565142 -37.102288)
		(mid 131.633288 -37.266806)
		(end 131.797806 -37.334952)
		(width 0.1397)
		(layer "In5.Cu")
		(net "PCIE_IOM_TO_COMP_13_DP")
	)
	(segment
		(start 177.661062 -139.973812)
		(end 177.750724 -140.063474)
		(width 0.14605)
		(layer "F.Cu")
		(net "PCIE_IOM_TO_COMP_13_DN")
	)
	(segment
		(start 178.185572 -139.202414)
		(end 177.237644 -138.254486)
		(width 0.14605)
		(layer "F.Cu")
		(net "PCIE_IOM_TO_COMP_13_DN")
	)
	(segment
		(start 177.237644 -135.80745)
		(end 177.150014 -135.71982)
		(width 0.14605)
		(layer "F.Cu")
		(net "PCIE_IOM_TO_COMP_13_DN")
	)
	(segment
		(start 177.979832 -140.063474)
		(end 178.185572 -139.857734)
		(width 0.14605)
		(layer "F.Cu")
		(net "PCIE_IOM_TO_COMP_13_DN")
	)
	(segment
		(start 177.237644 -138.254486)
		(end 177.237644 -135.80745)
		(width 0.14605)
		(layer "F.Cu")
		(net "PCIE_IOM_TO_COMP_13_DN")
	)
	(segment
		(start 177.150014 -135.71982)
		(end 177.150014 -134.875016)
		(width 0.14605)
		(layer "F.Cu")
		(net "PCIE_IOM_TO_COMP_13_DN")
	)
	(arc
		(start 177.750724 -140.063474)
		(mid 177.865278 -140.110924)
		(end 177.979832 -140.063474)
		(width 0.14605)
		(layer "F.Cu")
		(net "PCIE_IOM_TO_COMP_13_DN")
	)
	(arc
		(start 178.185572 -139.857734)
		(mid 178.321293 -139.530074)
		(end 178.185572 -139.202414)
		(width 0.14605)
		(layer "F.Cu")
		(net "PCIE_IOM_TO_COMP_13_DN")
	)
	(segment
		(start 162.418014 -136.670034)
		(end 161.614104 -132.546598)
		(width 0.1397)
		(layer "In5.Cu")
		(net "PCIE_IOM_TO_COMP_13_DN")
	)
	(segment
		(start 163.727384 -138.61161)
		(end 162.418014 -136.670034)
		(width 0.1397)
		(layer "In5.Cu")
		(net "PCIE_IOM_TO_COMP_13_DN")
	)
	(segment
		(start 156.813758 -35.318192)
		(end 151.957532 -27.840178)
		(width 0.1397)
		(layer "In5.Cu")
		(net "PCIE_IOM_TO_COMP_13_DN")
	)
	(segment
		(start 132.299964 -37.819076)
		(end 132.299964 -38.200076)
		(width 0.1397)
		(layer "In5.Cu")
		(net "PCIE_IOM_TO_COMP_13_DN")
	)
	(segment
		(start 151.957532 -27.840178)
		(end 147.140422 -24.693626)
		(width 0.1397)
		(layer "In5.Cu")
		(net "PCIE_IOM_TO_COMP_13_DN")
	)
	(segment
		(start 177.661062 -139.973812)
		(end 177.750724 -140.063474)
		(width 0.1397)
		(layer "In5.Cu")
		(net "PCIE_IOM_TO_COMP_13_DN")
	)
	(segment
		(start 165.939978 -78.253082)
		(end 156.813758 -35.318192)
		(width 0.1397)
		(layer "In5.Cu")
		(net "PCIE_IOM_TO_COMP_13_DN")
	)
	(segment
		(start 144.173448 -24.100028)
		(end 136.849866 -24.100028)
		(width 0.1397)
		(layer "In5.Cu")
		(net "PCIE_IOM_TO_COMP_13_DN")
	)
	(segment
		(start 177.315622 -140.713714)
		(end 176.454562 -141.99108)
		(width 0.1397)
		(layer "In5.Cu")
		(net "PCIE_IOM_TO_COMP_13_DN")
	)
	(segment
		(start 176.053242 -142.201646)
		(end 175.720248 -142.266416)
		(width 0.1397)
		(layer "In5.Cu")
		(net "PCIE_IOM_TO_COMP_13_DN")
	)
	(segment
		(start 136.849866 -24.100028)
		(end 131.234942 -29.714952)
		(width 0.1397)
		(layer "In5.Cu")
		(net "PCIE_IOM_TO_COMP_13_DN")
	)
	(segment
		(start 177.750216 -140.278866)
		(end 177.315622 -140.713714)
		(width 0.1397)
		(layer "In5.Cu")
		(net "PCIE_IOM_TO_COMP_13_DN")
	)
	(segment
		(start 131.797806 -37.665152)
		(end 132.14604 -37.665152)
		(width 0.1397)
		(layer "In5.Cu")
		(net "PCIE_IOM_TO_COMP_13_DN")
	)
	(segment
		(start 171.054776 -141.33703)
		(end 166.389812 -140.407644)
		(width 0.1397)
		(layer "In5.Cu")
		(net "PCIE_IOM_TO_COMP_13_DN")
	)
	(segment
		(start 131.234942 -29.714952)
		(end 131.234942 -37.102288)
		(width 0.1397)
		(layer "In5.Cu")
		(net "PCIE_IOM_TO_COMP_13_DN")
	)
	(segment
		(start 175.720248 -142.266416)
		(end 173.387258 -141.801596)
		(width 0.1397)
		(layer "In5.Cu")
		(net "PCIE_IOM_TO_COMP_13_DN")
	)
	(segment
		(start 166.389812 -140.407644)
		(end 163.727384 -138.61161)
		(width 0.1397)
		(layer "In5.Cu")
		(net "PCIE_IOM_TO_COMP_13_DN")
	)
	(segment
		(start 147.140422 -24.693626)
		(end 144.173448 -24.100028)
		(width 0.1397)
		(layer "In5.Cu")
		(net "PCIE_IOM_TO_COMP_13_DN")
	)
	(segment
		(start 167.875966 -101.983794)
		(end 164.38626 -85.565742)
		(width 0.1397)
		(layer "In5.Cu")
		(net "PCIE_IOM_TO_COMP_13_DN")
	)
	(segment
		(start 161.614104 -132.546598)
		(end 167.875966 -101.983794)
		(width 0.1397)
		(layer "In5.Cu")
		(net "PCIE_IOM_TO_COMP_13_DN")
	)
	(segment
		(start 173.387258 -141.801596)
		(end 171.054776 -141.33703)
		(width 0.1397)
		(layer "In5.Cu")
		(net "PCIE_IOM_TO_COMP_13_DN")
	)
	(segment
		(start 176.454562 -141.99108)
		(end 176.053242 -142.201646)
		(width 0.1397)
		(layer "In5.Cu")
		(net "PCIE_IOM_TO_COMP_13_DN")
	)
	(segment
		(start 164.38626 -85.565742)
		(end 165.939978 -78.253082)
		(width 0.1397)
		(layer "In5.Cu")
		(net "PCIE_IOM_TO_COMP_13_DN")
	)
	(arc
		(start 131.234942 -37.102288)
		(mid 131.399801 -37.500293)
		(end 131.797806 -37.665152)
		(width 0.1397)
		(layer "In5.Cu")
		(net "PCIE_IOM_TO_COMP_13_DN")
	)
	(arc
		(start 132.14604 -37.665152)
		(mid 132.254881 -37.710235)
		(end 132.299964 -37.819076)
		(width 0.1397)
		(layer "In5.Cu")
		(net "PCIE_IOM_TO_COMP_13_DN")
	)
	(arc
		(start 177.750724 -140.063474)
		(mid 177.795228 -140.170916)
		(end 177.750724 -140.278358)
		(width 0.1397)
		(layer "In5.Cu")
		(net "PCIE_IOM_TO_COMP_13_DN")
	)
	(arc
		(start 177.750724 -140.278358)
		(mid 177.75047 -140.278612)
		(end 177.750216 -140.278866)
		(width 0.1397)
		(layer "In5.Cu")
		(net "PCIE_IOM_TO_COMP_13_DN")
	)
	(segment
		(start 180.548788 -135.8138)
		(end 180.64988 -135.712708)
		(width 0.14605)
		(layer "F.Cu")
		(net "PCIE_IOM_TO_COMP_12_DP")
	)
	(segment
		(start 183.124094 -138.94435)
		(end 182.22976 -138.050016)
		(width 0.14605)
		(layer "F.Cu")
		(net "PCIE_IOM_TO_COMP_12_DP")
	)
	(segment
		(start 180.64988 -135.712708)
		(end 180.64988 -134.875016)
		(width 0.14605)
		(layer "F.Cu")
		(net "PCIE_IOM_TO_COMP_12_DP")
	)
	(segment
		(start 182.867554 -139.97305)
		(end 183.043068 -139.797536)
		(width 0.14605)
		(layer "F.Cu")
		(net "PCIE_IOM_TO_COMP_12_DP")
	)
	(segment
		(start 182.956962 -140.29182)
		(end 182.8673 -140.202158)
		(width 0.14605)
		(layer "F.Cu")
		(net "PCIE_IOM_TO_COMP_12_DP")
	)
	(segment
		(start 182.867554 -139.973304)
		(end 182.867554 -139.97305)
		(width 0.14605)
		(layer "F.Cu")
		(net "PCIE_IOM_TO_COMP_12_DP")
	)
	(segment
		(start 182.22976 -138.050016)
		(end 181.575456 -138.050016)
		(width 0.14605)
		(layer "F.Cu")
		(net "PCIE_IOM_TO_COMP_12_DP")
	)
	(segment
		(start 182.8673 -139.973558)
		(end 182.867554 -139.973304)
		(width 0.14605)
		(layer "F.Cu")
		(net "PCIE_IOM_TO_COMP_12_DP")
	)
	(segment
		(start 181.575456 -138.050016)
		(end 180.548788 -137.023348)
		(width 0.14605)
		(layer "F.Cu")
		(net "PCIE_IOM_TO_COMP_12_DP")
	)
	(segment
		(start 183.043068 -139.797536)
		(end 183.124094 -139.716256)
		(width 0.14605)
		(layer "F.Cu")
		(net "PCIE_IOM_TO_COMP_12_DP")
	)
	(segment
		(start 180.548788 -137.023348)
		(end 180.548788 -135.8138)
		(width 0.14605)
		(layer "F.Cu")
		(net "PCIE_IOM_TO_COMP_12_DP")
	)
	(arc
		(start 182.8673 -140.202158)
		(mid 182.819955 -140.087858)
		(end 182.8673 -139.973558)
		(width 0.14605)
		(layer "F.Cu")
		(net "PCIE_IOM_TO_COMP_12_DP")
	)
	(arc
		(start 183.124094 -139.716256)
		(mid 183.283834 -139.33034)
		(end 183.124094 -138.94435)
		(width 0.14605)
		(layer "F.Cu")
		(net "PCIE_IOM_TO_COMP_12_DP")
	)
	(segment
		(start 152.244298 -32.00527)
		(end 150.26132 -28.951682)
		(width 0.1397)
		(layer "In5.Cu")
		(net "PCIE_IOM_TO_COMP_12_DP")
	)
	(segment
		(start 152.191974 -32.251396)
		(end 152.244298 -32.00527)
		(width 0.1397)
		(layer "In5.Cu")
		(net "PCIE_IOM_TO_COMP_12_DP")
	)
	(segment
		(start 153.07056 -33.603946)
		(end 152.842214 -33.252664)
		(width 0.1397)
		(layer "In5.Cu")
		(net "PCIE_IOM_TO_COMP_12_DP")
	)
	(segment
		(start 145.604992 -25.90165)
		(end 143.263366 -25.433782)
		(width 0.1397)
		(layer "In5.Cu")
		(net "PCIE_IOM_TO_COMP_12_DP")
	)
	(segment
		(start 162.257486 -84.853526)
		(end 163.770564 -77.73543)
		(width 0.1397)
		(layer "In5.Cu")
		(net "PCIE_IOM_TO_COMP_12_DP")
	)
	(segment
		(start 161.04362 -137.47115)
		(end 160.212532 -133.195822)
		(width 0.1397)
		(layer "In5.Cu")
		(net "PCIE_IOM_TO_COMP_12_DP")
	)
	(segment
		(start 150.26132 -28.951682)
		(end 145.604992 -25.90165)
		(width 0.1397)
		(layer "In5.Cu")
		(net "PCIE_IOM_TO_COMP_12_DP")
	)
	(segment
		(start 152.42032 -32.602678)
		(end 152.191974 -32.251396)
		(width 0.1397)
		(layer "In5.Cu")
		(net "PCIE_IOM_TO_COMP_12_DP")
	)
	(segment
		(start 162.483038 -139.605512)
		(end 161.04362 -137.47115)
		(width 0.1397)
		(layer "In5.Cu")
		(net "PCIE_IOM_TO_COMP_12_DP")
	)
	(segment
		(start 181.382924 -142.724632)
		(end 176.073054 -143.78686)
		(width 0.1397)
		(layer "In5.Cu")
		(net "PCIE_IOM_TO_COMP_12_DP")
	)
	(segment
		(start 133.36524 -29.712666)
		(end 133.36524 -35.915854)
		(width 0.1397)
		(layer "In5.Cu")
		(net "PCIE_IOM_TO_COMP_12_DP")
	)
	(segment
		(start 153.7208 -34.605214)
		(end 153.492708 -34.253932)
		(width 0.1397)
		(layer "In5.Cu")
		(net "PCIE_IOM_TO_COMP_12_DP")
	)
	(segment
		(start 153.966672 -34.657538)
		(end 153.7208 -34.605214)
		(width 0.1397)
		(layer "In5.Cu")
		(net "PCIE_IOM_TO_COMP_12_DP")
	)
	(segment
		(start 152.894538 -33.006538)
		(end 152.666192 -32.655002)
		(width 0.1397)
		(layer "In5.Cu")
		(net "PCIE_IOM_TO_COMP_12_DP")
	)
	(segment
		(start 154.92857 -36.138612)
		(end 153.966672 -34.657538)
		(width 0.1397)
		(layer "In5.Cu")
		(net "PCIE_IOM_TO_COMP_12_DP")
	)
	(segment
		(start 152.666192 -32.655002)
		(end 152.42032 -32.602678)
		(width 0.1397)
		(layer "In5.Cu")
		(net "PCIE_IOM_TO_COMP_12_DP")
	)
	(segment
		(start 133.584442 -36.135056)
		(end 133.946138 -36.135056)
		(width 0.1397)
		(layer "In5.Cu")
		(net "PCIE_IOM_TO_COMP_12_DP")
	)
	(segment
		(start 153.316432 -33.65627)
		(end 153.07056 -33.603946)
		(width 0.1397)
		(layer "In5.Cu")
		(net "PCIE_IOM_TO_COMP_12_DP")
	)
	(segment
		(start 153.492708 -34.253932)
		(end 153.544778 -34.007806)
		(width 0.1397)
		(layer "In5.Cu")
		(net "PCIE_IOM_TO_COMP_12_DP")
	)
	(segment
		(start 160.212532 -133.195822)
		(end 166.097458 -102.921054)
		(width 0.1397)
		(layer "In5.Cu")
		(net "PCIE_IOM_TO_COMP_12_DP")
	)
	(segment
		(start 176.073054 -143.78686)
		(end 165.38194 -141.560804)
		(width 0.1397)
		(layer "In5.Cu")
		(net "PCIE_IOM_TO_COMP_12_DP")
	)
	(segment
		(start 182.36184 -140.61313)
		(end 182.36184 -141.88059)
		(width 0.1397)
		(layer "In5.Cu")
		(net "PCIE_IOM_TO_COMP_12_DP")
	)
	(segment
		(start 134.100062 -35.981132)
		(end 134.100062 -35.600132)
		(width 0.1397)
		(layer "In5.Cu")
		(net "PCIE_IOM_TO_COMP_12_DP")
	)
	(segment
		(start 166.097458 -102.921054)
		(end 162.257486 -84.853526)
		(width 0.1397)
		(layer "In5.Cu")
		(net "PCIE_IOM_TO_COMP_12_DP")
	)
	(segment
		(start 182.132732 -142.225014)
		(end 181.382924 -142.724632)
		(width 0.1397)
		(layer "In5.Cu")
		(net "PCIE_IOM_TO_COMP_12_DP")
	)
	(segment
		(start 143.263366 -25.433782)
		(end 137.644124 -25.433782)
		(width 0.1397)
		(layer "In5.Cu")
		(net "PCIE_IOM_TO_COMP_12_DP")
	)
	(segment
		(start 182.956962 -140.29182)
		(end 182.8673 -140.202158)
		(width 0.1397)
		(layer "In5.Cu")
		(net "PCIE_IOM_TO_COMP_12_DP")
	)
	(segment
		(start 137.644124 -25.433782)
		(end 133.36524 -29.712666)
		(width 0.1397)
		(layer "In5.Cu")
		(net "PCIE_IOM_TO_COMP_12_DP")
	)
	(segment
		(start 182.36184 -141.88059)
		(end 182.132732 -142.225014)
		(width 0.1397)
		(layer "In5.Cu")
		(net "PCIE_IOM_TO_COMP_12_DP")
	)
	(segment
		(start 163.770564 -77.73543)
		(end 154.92857 -36.138612)
		(width 0.1397)
		(layer "In5.Cu")
		(net "PCIE_IOM_TO_COMP_12_DP")
	)
	(segment
		(start 182.6514 -140.202158)
		(end 182.447692 -140.405866)
		(width 0.1397)
		(layer "In5.Cu")
		(net "PCIE_IOM_TO_COMP_12_DP")
	)
	(segment
		(start 153.544778 -34.007806)
		(end 153.316432 -33.65627)
		(width 0.1397)
		(layer "In5.Cu")
		(net "PCIE_IOM_TO_COMP_12_DP")
	)
	(segment
		(start 165.38194 -141.560804)
		(end 162.483038 -139.605512)
		(width 0.1397)
		(layer "In5.Cu")
		(net "PCIE_IOM_TO_COMP_12_DP")
	)
	(segment
		(start 152.842214 -33.252664)
		(end 152.894538 -33.006538)
		(width 0.1397)
		(layer "In5.Cu")
		(net "PCIE_IOM_TO_COMP_12_DP")
	)
	(arc
		(start 182.8673 -140.202158)
		(mid 182.75935 -140.157444)
		(end 182.6514 -140.202158)
		(width 0.1397)
		(layer "In5.Cu")
		(net "PCIE_IOM_TO_COMP_12_DP")
	)
	(arc
		(start 133.946138 -36.135056)
		(mid 134.054979 -36.089973)
		(end 134.100062 -35.981132)
		(width 0.1397)
		(layer "In5.Cu")
		(net "PCIE_IOM_TO_COMP_12_DP")
	)
	(arc
		(start 133.36524 -35.915854)
		(mid 133.429443 -36.070853)
		(end 133.584442 -36.135056)
		(width 0.1397)
		(layer "In5.Cu")
		(net "PCIE_IOM_TO_COMP_12_DP")
	)
	(arc
		(start 182.447692 -140.405866)
		(mid 182.384153 -140.50096)
		(end 182.36184 -140.61313)
		(width 0.1397)
		(layer "In5.Cu")
		(net "PCIE_IOM_TO_COMP_12_DP")
	)
	(segment
		(start 182.647336 -139.753086)
		(end 182.903876 -139.496292)
		(width 0.14605)
		(layer "F.Cu")
		(net "PCIE_IOM_TO_COMP_12_DN")
	)
	(segment
		(start 180.237638 -135.80745)
		(end 180.150008 -135.71982)
		(width 0.14605)
		(layer "F.Cu")
		(net "PCIE_IOM_TO_COMP_12_DN")
	)
	(segment
		(start 180.237638 -137.15238)
		(end 180.237638 -135.80745)
		(width 0.14605)
		(layer "F.Cu")
		(net "PCIE_IOM_TO_COMP_12_DN")
	)
	(segment
		(start 182.328566 -139.663424)
		(end 182.418228 -139.753086)
		(width 0.14605)
		(layer "F.Cu")
		(net "PCIE_IOM_TO_COMP_12_DN")
	)
	(segment
		(start 182.903876 -139.164568)
		(end 182.100474 -138.361166)
		(width 0.14605)
		(layer "F.Cu")
		(net "PCIE_IOM_TO_COMP_12_DN")
	)
	(segment
		(start 182.100474 -138.361166)
		(end 181.446424 -138.361166)
		(width 0.14605)
		(layer "F.Cu")
		(net "PCIE_IOM_TO_COMP_12_DN")
	)
	(segment
		(start 180.150008 -135.71982)
		(end 180.150008 -134.875016)
		(width 0.14605)
		(layer "F.Cu")
		(net "PCIE_IOM_TO_COMP_12_DN")
	)
	(segment
		(start 181.446424 -138.361166)
		(end 180.237638 -137.15238)
		(width 0.14605)
		(layer "F.Cu")
		(net "PCIE_IOM_TO_COMP_12_DN")
	)
	(arc
		(start 182.418228 -139.753086)
		(mid 182.532782 -139.800536)
		(end 182.647336 -139.753086)
		(width 0.14605)
		(layer "F.Cu")
		(net "PCIE_IOM_TO_COMP_12_DN")
	)
	(arc
		(start 182.903876 -139.496292)
		(mid 182.972578 -139.33043)
		(end 182.903876 -139.164568)
		(width 0.14605)
		(layer "F.Cu")
		(net "PCIE_IOM_TO_COMP_12_DN")
	)
	(segment
		(start 155.251658 -36.069778)
		(end 155.238958 -36.010088)
		(width 0.1397)
		(layer "In5.Cu")
		(net "PCIE_IOM_TO_COMP_12_DN")
	)
	(segment
		(start 182.03164 -140.612876)
		(end 182.03164 -141.780768)
		(width 0.1397)
		(layer "In5.Cu")
		(net "PCIE_IOM_TO_COMP_12_DN")
	)
	(segment
		(start 133.03504 -29.57576)
		(end 133.03504 -35.915854)
		(width 0.1397)
		(layer "In5.Cu")
		(net "PCIE_IOM_TO_COMP_12_DN")
	)
	(segment
		(start 166.434516 -102.918006)
		(end 162.595306 -84.853526)
		(width 0.1397)
		(layer "In5.Cu")
		(net "PCIE_IOM_TO_COMP_12_DN")
	)
	(segment
		(start 181.254146 -142.413482)
		(end 176.074324 -143.449802)
		(width 0.1397)
		(layer "In5.Cu")
		(net "PCIE_IOM_TO_COMP_12_DN")
	)
	(segment
		(start 155.238958 -36.010088)
		(end 150.500334 -28.71343)
		(width 0.1397)
		(layer "In5.Cu")
		(net "PCIE_IOM_TO_COMP_12_DN")
	)
	(segment
		(start 165.51275 -141.25067)
		(end 162.721036 -139.367514)
		(width 0.1397)
		(layer "In5.Cu")
		(net "PCIE_IOM_TO_COMP_12_DN")
	)
	(segment
		(start 160.549082 -133.195822)
		(end 166.434516 -102.918006)
		(width 0.1397)
		(layer "In5.Cu")
		(net "PCIE_IOM_TO_COMP_12_DN")
	)
	(segment
		(start 182.214012 -140.172186)
		(end 182.214012 -140.17244)
		(width 0.1397)
		(layer "In5.Cu")
		(net "PCIE_IOM_TO_COMP_12_DN")
	)
	(segment
		(start 176.074324 -143.449802)
		(end 165.51275 -141.25067)
		(width 0.1397)
		(layer "In5.Cu")
		(net "PCIE_IOM_TO_COMP_12_DN")
	)
	(segment
		(start 182.03164 -141.780768)
		(end 181.894226 -141.986762)
		(width 0.1397)
		(layer "In5.Cu")
		(net "PCIE_IOM_TO_COMP_12_DN")
	)
	(segment
		(start 162.595306 -84.853526)
		(end 164.108384 -77.73543)
		(width 0.1397)
		(layer "In5.Cu")
		(net "PCIE_IOM_TO_COMP_12_DN")
	)
	(segment
		(start 182.328566 -139.663424)
		(end 182.418228 -139.753086)
		(width 0.1397)
		(layer "In5.Cu")
		(net "PCIE_IOM_TO_COMP_12_DN")
	)
	(segment
		(start 145.7325 -25.590246)
		(end 143.296132 -25.103582)
		(width 0.1397)
		(layer "In5.Cu")
		(net "PCIE_IOM_TO_COMP_12_DN")
	)
	(segment
		(start 150.500334 -28.71343)
		(end 145.7325 -25.590246)
		(width 0.1397)
		(layer "In5.Cu")
		(net "PCIE_IOM_TO_COMP_12_DN")
	)
	(segment
		(start 137.507218 -25.103582)
		(end 133.03504 -29.57576)
		(width 0.1397)
		(layer "In5.Cu")
		(net "PCIE_IOM_TO_COMP_12_DN")
	)
	(segment
		(start 161.355024 -137.342118)
		(end 160.549082 -133.195822)
		(width 0.1397)
		(layer "In5.Cu")
		(net "PCIE_IOM_TO_COMP_12_DN")
	)
	(segment
		(start 181.894226 -141.986762)
		(end 181.254146 -142.413482)
		(width 0.1397)
		(layer "In5.Cu")
		(net "PCIE_IOM_TO_COMP_12_DN")
	)
	(segment
		(start 133.584442 -36.465256)
		(end 133.946138 -36.465256)
		(width 0.1397)
		(layer "In5.Cu")
		(net "PCIE_IOM_TO_COMP_12_DN")
	)
	(segment
		(start 143.296132 -25.103582)
		(end 137.507218 -25.103582)
		(width 0.1397)
		(layer "In5.Cu")
		(net "PCIE_IOM_TO_COMP_12_DN")
	)
	(segment
		(start 162.721036 -139.367514)
		(end 161.355024 -137.342118)
		(width 0.1397)
		(layer "In5.Cu")
		(net "PCIE_IOM_TO_COMP_12_DN")
	)
	(segment
		(start 134.100062 -36.61918)
		(end 134.100062 -37.00018)
		(width 0.1397)
		(layer "In5.Cu")
		(net "PCIE_IOM_TO_COMP_12_DN")
	)
	(segment
		(start 182.418228 -139.96797)
		(end 182.214012 -140.172186)
		(width 0.1397)
		(layer "In5.Cu")
		(net "PCIE_IOM_TO_COMP_12_DN")
	)
	(segment
		(start 164.108384 -77.73543)
		(end 155.251658 -36.069778)
		(width 0.1397)
		(layer "In5.Cu")
		(net "PCIE_IOM_TO_COMP_12_DN")
	)
	(arc
		(start 182.418228 -139.753086)
		(mid 182.462732 -139.860528)
		(end 182.418228 -139.96797)
		(width 0.1397)
		(layer "In5.Cu")
		(net "PCIE_IOM_TO_COMP_12_DN")
	)
	(arc
		(start 133.03504 -35.915854)
		(mid 133.195956 -36.30434)
		(end 133.584442 -36.465256)
		(width 0.1397)
		(layer "In5.Cu")
		(net "PCIE_IOM_TO_COMP_12_DN")
	)
	(arc
		(start 133.946138 -36.465256)
		(mid 134.054979 -36.510339)
		(end 134.100062 -36.61918)
		(width 0.1397)
		(layer "In5.Cu")
		(net "PCIE_IOM_TO_COMP_12_DN")
	)
	(arc
		(start 182.214012 -140.17244)
		(mid 182.079015 -140.374527)
		(end 182.03164 -140.612876)
		(width 0.1397)
		(layer "In5.Cu")
		(net "PCIE_IOM_TO_COMP_12_DN")
	)
	(segment
		(start 194.428872 -137.7696)
		(end 195.309236 -137.7696)
		(width 0.14605)
		(layer "F.Cu")
		(net "PCIE_IOM_TO_COMP_11_DP")
	)
	(segment
		(start 196.548756 -136.53008)
		(end 196.548756 -135.8138)
		(width 0.14605)
		(layer "F.Cu")
		(net "PCIE_IOM_TO_COMP_11_DP")
	)
	(segment
		(start 196.548756 -135.8138)
		(end 196.649848 -135.712708)
		(width 0.14605)
		(layer "F.Cu")
		(net "PCIE_IOM_TO_COMP_11_DP")
	)
	(segment
		(start 196.649848 -135.712708)
		(end 196.649848 -134.875016)
		(width 0.14605)
		(layer "F.Cu")
		(net "PCIE_IOM_TO_COMP_11_DP")
	)
	(segment
		(start 192.719198 -139.887198)
		(end 192.629536 -139.797536)
		(width 0.14605)
		(layer "F.Cu")
		(net "PCIE_IOM_TO_COMP_11_DP")
	)
	(segment
		(start 195.309236 -137.7696)
		(end 196.548756 -136.53008)
		(width 0.14605)
		(layer "F.Cu")
		(net "PCIE_IOM_TO_COMP_11_DP")
	)
	(segment
		(start 192.629536 -139.568936)
		(end 194.428872 -137.7696)
		(width 0.14605)
		(layer "F.Cu")
		(net "PCIE_IOM_TO_COMP_11_DP")
	)
	(arc
		(start 192.629536 -139.797536)
		(mid 192.582191 -139.683236)
		(end 192.629536 -139.568936)
		(width 0.14605)
		(layer "F.Cu")
		(net "PCIE_IOM_TO_COMP_11_DP")
	)
	(segment
		(start 160.532064 -84.686648)
		(end 161.967926 -77.931518)
		(width 0.1397)
		(layer "In5.Cu")
		(net "PCIE_IOM_TO_COMP_11_DP")
	)
	(segment
		(start 153.04008 -35.85083)
		(end 152.420066 -34.896298)
		(width 0.1397)
		(layer "In5.Cu")
		(net "PCIE_IOM_TO_COMP_11_DP")
	)
	(segment
		(start 151.347932 -33.245298)
		(end 151.119586 -32.893762)
		(width 0.1397)
		(layer "In5.Cu")
		(net "PCIE_IOM_TO_COMP_11_DP")
	)
	(segment
		(start 135.165084 -29.553916)
		(end 135.165084 -37.102288)
		(width 0.1397)
		(layer "In5.Cu")
		(net "PCIE_IOM_TO_COMP_11_DP")
	)
	(segment
		(start 151.945848 -34.492438)
		(end 151.998172 -34.246566)
		(width 0.1397)
		(layer "In5.Cu")
		(net "PCIE_IOM_TO_COMP_11_DP")
	)
	(segment
		(start 135.397748 -37.334952)
		(end 135.745982 -37.334952)
		(width 0.1397)
		(layer "In5.Cu")
		(net "PCIE_IOM_TO_COMP_11_DP")
	)
	(segment
		(start 176.989486 -144.992598)
		(end 164.884862 -142.469362)
		(width 0.1397)
		(layer "In5.Cu")
		(net "PCIE_IOM_TO_COMP_11_DP")
	)
	(segment
		(start 151.523954 -33.842706)
		(end 151.295608 -33.49117)
		(width 0.1397)
		(layer "In5.Cu")
		(net "PCIE_IOM_TO_COMP_11_DP")
	)
	(segment
		(start 164.58438 -103.765096)
		(end 160.532064 -84.686648)
		(width 0.1397)
		(layer "In5.Cu")
		(net "PCIE_IOM_TO_COMP_11_DP")
	)
	(segment
		(start 151.119586 -32.893762)
		(end 150.873714 -32.841438)
		(width 0.1397)
		(layer "In5.Cu")
		(net "PCIE_IOM_TO_COMP_11_DP")
	)
	(segment
		(start 144.655032 -26.863294)
		(end 142.294864 -26.391362)
		(width 0.1397)
		(layer "In5.Cu")
		(net "PCIE_IOM_TO_COMP_11_DP")
	)
	(segment
		(start 150.873714 -32.841438)
		(end 150.645368 -32.490156)
		(width 0.1397)
		(layer "In5.Cu")
		(net "PCIE_IOM_TO_COMP_11_DP")
	)
	(segment
		(start 164.884862 -142.469362)
		(end 164.83076 -142.43304)
		(width 0.1397)
		(layer "In5.Cu")
		(net "PCIE_IOM_TO_COMP_11_DP")
	)
	(segment
		(start 158.938468 -132.380482)
		(end 164.58438 -103.765096)
		(width 0.1397)
		(layer "In5.Cu")
		(net "PCIE_IOM_TO_COMP_11_DP")
	)
	(segment
		(start 135.899906 -37.181028)
		(end 135.899906 -36.800028)
		(width 0.1397)
		(layer "In5.Cu")
		(net "PCIE_IOM_TO_COMP_11_DP")
	)
	(segment
		(start 151.769826 -33.89503)
		(end 151.523954 -33.842706)
		(width 0.1397)
		(layer "In5.Cu")
		(net "PCIE_IOM_TO_COMP_11_DP")
	)
	(segment
		(start 142.294864 -26.391362)
		(end 138.327638 -26.391362)
		(width 0.1397)
		(layer "In5.Cu")
		(net "PCIE_IOM_TO_COMP_11_DP")
	)
	(segment
		(start 161.967926 -77.931518)
		(end 153.04008 -35.85083)
		(width 0.1397)
		(layer "In5.Cu")
		(net "PCIE_IOM_TO_COMP_11_DP")
	)
	(segment
		(start 150.645368 -32.490156)
		(end 150.697692 -32.24403)
		(width 0.1397)
		(layer "In5.Cu")
		(net "PCIE_IOM_TO_COMP_11_DP")
	)
	(segment
		(start 152.174194 -34.843974)
		(end 151.945848 -34.492438)
		(width 0.1397)
		(layer "In5.Cu")
		(net "PCIE_IOM_TO_COMP_11_DP")
	)
	(segment
		(start 150.697692 -32.24403)
		(end 149.08657 -29.763212)
		(width 0.1397)
		(layer "In5.Cu")
		(net "PCIE_IOM_TO_COMP_11_DP")
	)
	(segment
		(start 152.420066 -34.896298)
		(end 152.174194 -34.843974)
		(width 0.1397)
		(layer "In5.Cu")
		(net "PCIE_IOM_TO_COMP_11_DP")
	)
	(segment
		(start 151.998172 -34.246566)
		(end 151.769826 -33.89503)
		(width 0.1397)
		(layer "In5.Cu")
		(net "PCIE_IOM_TO_COMP_11_DP")
	)
	(segment
		(start 192.413636 -139.797536)
		(end 191.51219 -140.698982)
		(width 0.1397)
		(layer "In5.Cu")
		(net "PCIE_IOM_TO_COMP_11_DP")
	)
	(segment
		(start 192.719198 -139.887198)
		(end 192.629536 -139.797536)
		(width 0.1397)
		(layer "In5.Cu")
		(net "PCIE_IOM_TO_COMP_11_DP")
	)
	(segment
		(start 160.016698 -137.92708)
		(end 158.938468 -132.380482)
		(width 0.1397)
		(layer "In5.Cu")
		(net "PCIE_IOM_TO_COMP_11_DP")
	)
	(segment
		(start 164.831014 -142.43304)
		(end 161.57448 -140.236702)
		(width 0.1397)
		(layer "In5.Cu")
		(net "PCIE_IOM_TO_COMP_11_DP")
	)
	(segment
		(start 164.83076 -142.43304)
		(end 164.831014 -142.43304)
		(width 0.1397)
		(layer "In5.Cu")
		(net "PCIE_IOM_TO_COMP_11_DP")
	)
	(segment
		(start 151.295608 -33.49117)
		(end 151.347932 -33.245298)
		(width 0.1397)
		(layer "In5.Cu")
		(net "PCIE_IOM_TO_COMP_11_DP")
	)
	(segment
		(start 138.327638 -26.391362)
		(end 135.165084 -29.553916)
		(width 0.1397)
		(layer "In5.Cu")
		(net "PCIE_IOM_TO_COMP_11_DP")
	)
	(segment
		(start 149.08657 -29.763212)
		(end 144.655032 -26.863294)
		(width 0.1397)
		(layer "In5.Cu")
		(net "PCIE_IOM_TO_COMP_11_DP")
	)
	(segment
		(start 188.533532 -142.6845)
		(end 176.989486 -144.992598)
		(width 0.1397)
		(layer "In5.Cu")
		(net "PCIE_IOM_TO_COMP_11_DP")
	)
	(segment
		(start 191.51219 -140.698982)
		(end 188.533532 -142.6845)
		(width 0.1397)
		(layer "In5.Cu")
		(net "PCIE_IOM_TO_COMP_11_DP")
	)
	(segment
		(start 161.57448 -140.236702)
		(end 160.016698 -137.92708)
		(width 0.1397)
		(layer "In5.Cu")
		(net "PCIE_IOM_TO_COMP_11_DP")
	)
	(arc
		(start 135.745982 -37.334952)
		(mid 135.854823 -37.289869)
		(end 135.899906 -37.181028)
		(width 0.1397)
		(layer "In5.Cu")
		(net "PCIE_IOM_TO_COMP_11_DP")
	)
	(arc
		(start 192.629536 -139.797536)
		(mid 192.521586 -139.752822)
		(end 192.413636 -139.797536)
		(width 0.1397)
		(layer "In5.Cu")
		(net "PCIE_IOM_TO_COMP_11_DP")
	)
	(arc
		(start 135.165084 -37.102288)
		(mid 135.23323 -37.266806)
		(end 135.397748 -37.334952)
		(width 0.1397)
		(layer "In5.Cu")
		(net "PCIE_IOM_TO_COMP_11_DP")
	)
	(segment
		(start 196.149976 -135.71982)
		(end 196.149976 -134.875016)
		(width 0.14605)
		(layer "F.Cu")
		(net "PCIE_IOM_TO_COMP_11_DN")
	)
	(segment
		(start 192.409572 -139.348718)
		(end 194.29984 -137.45845)
		(width 0.14605)
		(layer "F.Cu")
		(net "PCIE_IOM_TO_COMP_11_DN")
	)
	(segment
		(start 195.180204 -137.45845)
		(end 196.237606 -136.401048)
		(width 0.14605)
		(layer "F.Cu")
		(net "PCIE_IOM_TO_COMP_11_DN")
	)
	(segment
		(start 194.29984 -137.45845)
		(end 195.180204 -137.45845)
		(width 0.14605)
		(layer "F.Cu")
		(net "PCIE_IOM_TO_COMP_11_DN")
	)
	(segment
		(start 196.237606 -135.80745)
		(end 196.149976 -135.71982)
		(width 0.14605)
		(layer "F.Cu")
		(net "PCIE_IOM_TO_COMP_11_DN")
	)
	(segment
		(start 196.237606 -136.401048)
		(end 196.237606 -135.80745)
		(width 0.14605)
		(layer "F.Cu")
		(net "PCIE_IOM_TO_COMP_11_DN")
	)
	(segment
		(start 192.409572 -139.348464)
		(end 192.409572 -139.348718)
		(width 0.14605)
		(layer "F.Cu")
		(net "PCIE_IOM_TO_COMP_11_DN")
	)
	(segment
		(start 192.090802 -139.258802)
		(end 192.180464 -139.348464)
		(width 0.14605)
		(layer "F.Cu")
		(net "PCIE_IOM_TO_COMP_11_DN")
	)
	(arc
		(start 192.180464 -139.348464)
		(mid 192.295018 -139.395914)
		(end 192.409572 -139.348464)
		(width 0.14605)
		(layer "F.Cu")
		(net "PCIE_IOM_TO_COMP_11_DN")
	)
	(segment
		(start 192.180464 -139.563348)
		(end 191.301624 -140.442188)
		(width 0.1397)
		(layer "In5.Cu")
		(net "PCIE_IOM_TO_COMP_11_DN")
	)
	(segment
		(start 138.190732 -26.061162)
		(end 134.834884 -29.41701)
		(width 0.1397)
		(layer "In5.Cu")
		(net "PCIE_IOM_TO_COMP_11_DN")
	)
	(segment
		(start 164.921692 -103.762556)
		(end 160.869884 -84.686648)
		(width 0.1397)
		(layer "In5.Cu")
		(net "PCIE_IOM_TO_COMP_11_DN")
	)
	(segment
		(start 192.090802 -139.258802)
		(end 192.180464 -139.348464)
		(width 0.1397)
		(layer "In5.Cu")
		(net "PCIE_IOM_TO_COMP_11_DN")
	)
	(segment
		(start 161.812478 -139.998704)
		(end 160.328102 -137.798048)
		(width 0.1397)
		(layer "In5.Cu")
		(net "PCIE_IOM_TO_COMP_11_DN")
	)
	(segment
		(start 135.899906 -37.819076)
		(end 135.899906 -38.200076)
		(width 0.1397)
		(layer "In5.Cu")
		(net "PCIE_IOM_TO_COMP_11_DN")
	)
	(segment
		(start 165.015672 -142.159228)
		(end 161.812478 -139.998704)
		(width 0.1397)
		(layer "In5.Cu")
		(net "PCIE_IOM_TO_COMP_11_DN")
	)
	(segment
		(start 191.301624 -140.442188)
		(end 188.404754 -142.37335)
		(width 0.1397)
		(layer "In5.Cu")
		(net "PCIE_IOM_TO_COMP_11_DN")
	)
	(segment
		(start 162.305746 -77.931518)
		(end 153.350468 -35.722306)
		(width 0.1397)
		(layer "In5.Cu")
		(net "PCIE_IOM_TO_COMP_11_DN")
	)
	(segment
		(start 160.328102 -137.798048)
		(end 159.275018 -132.38099)
		(width 0.1397)
		(layer "In5.Cu")
		(net "PCIE_IOM_TO_COMP_11_DN")
	)
	(segment
		(start 176.990756 -144.65554)
		(end 165.015672 -142.159228)
		(width 0.1397)
		(layer "In5.Cu")
		(net "PCIE_IOM_TO_COMP_11_DN")
	)
	(segment
		(start 144.78254 -26.55189)
		(end 142.32763 -26.061162)
		(width 0.1397)
		(layer "In5.Cu")
		(net "PCIE_IOM_TO_COMP_11_DN")
	)
	(segment
		(start 188.404754 -142.37335)
		(end 176.990756 -144.65554)
		(width 0.1397)
		(layer "In5.Cu")
		(net "PCIE_IOM_TO_COMP_11_DN")
	)
	(segment
		(start 160.869884 -84.686648)
		(end 162.305746 -77.931518)
		(width 0.1397)
		(layer "In5.Cu")
		(net "PCIE_IOM_TO_COMP_11_DN")
	)
	(segment
		(start 159.275018 -132.38099)
		(end 164.921692 -103.762556)
		(width 0.1397)
		(layer "In5.Cu")
		(net "PCIE_IOM_TO_COMP_11_DN")
	)
	(segment
		(start 135.397748 -37.665152)
		(end 135.745982 -37.665152)
		(width 0.1397)
		(layer "In5.Cu")
		(net "PCIE_IOM_TO_COMP_11_DN")
	)
	(segment
		(start 142.32763 -26.061162)
		(end 138.190732 -26.061162)
		(width 0.1397)
		(layer "In5.Cu")
		(net "PCIE_IOM_TO_COMP_11_DN")
	)
	(segment
		(start 149.325584 -29.52496)
		(end 144.78254 -26.55189)
		(width 0.1397)
		(layer "In5.Cu")
		(net "PCIE_IOM_TO_COMP_11_DN")
	)
	(segment
		(start 153.350468 -35.722306)
		(end 149.325584 -29.52496)
		(width 0.1397)
		(layer "In5.Cu")
		(net "PCIE_IOM_TO_COMP_11_DN")
	)
	(segment
		(start 134.834884 -29.41701)
		(end 134.834884 -37.102288)
		(width 0.1397)
		(layer "In5.Cu")
		(net "PCIE_IOM_TO_COMP_11_DN")
	)
	(arc
		(start 135.745982 -37.665152)
		(mid 135.854823 -37.710235)
		(end 135.899906 -37.819076)
		(width 0.1397)
		(layer "In5.Cu")
		(net "PCIE_IOM_TO_COMP_11_DN")
	)
	(arc
		(start 192.180464 -139.348464)
		(mid 192.224968 -139.455906)
		(end 192.180464 -139.563348)
		(width 0.1397)
		(layer "In5.Cu")
		(net "PCIE_IOM_TO_COMP_11_DN")
	)
	(arc
		(start 134.834884 -37.102288)
		(mid 134.999743 -37.500293)
		(end 135.397748 -37.665152)
		(width 0.1397)
		(layer "In5.Cu")
		(net "PCIE_IOM_TO_COMP_11_DN")
	)
	(segment
		(start 199.649842 -135.712708)
		(end 199.649842 -134.875016)
		(width 0.14605)
		(layer "F.Cu")
		(net "PCIE_IOM_TO_COMP_10_DP")
	)
	(segment
		(start 198.434198 -141.284198)
		(end 198.344536 -141.194536)
		(width 0.14605)
		(layer "F.Cu")
		(net "PCIE_IOM_TO_COMP_10_DP")
	)
	(segment
		(start 199.54875 -135.8138)
		(end 199.649842 -135.712708)
		(width 0.14605)
		(layer "F.Cu")
		(net "PCIE_IOM_TO_COMP_10_DP")
	)
	(segment
		(start 198.693532 -140.424408)
		(end 198.693532 -138.262868)
		(width 0.14605)
		(layer "F.Cu")
		(net "PCIE_IOM_TO_COMP_10_DP")
	)
	(segment
		(start 199.54875 -137.40765)
		(end 199.54875 -135.8138)
		(width 0.14605)
		(layer "F.Cu")
		(net "PCIE_IOM_TO_COMP_10_DP")
	)
	(segment
		(start 198.344536 -140.965936)
		(end 198.557388 -140.753084)
		(width 0.14605)
		(layer "F.Cu")
		(net "PCIE_IOM_TO_COMP_10_DP")
	)
	(segment
		(start 198.693532 -138.262868)
		(end 199.54875 -137.40765)
		(width 0.14605)
		(layer "F.Cu")
		(net "PCIE_IOM_TO_COMP_10_DP")
	)
	(arc
		(start 198.557388 -140.753084)
		(mid 198.658148 -140.602286)
		(end 198.693532 -140.424408)
		(width 0.14605)
		(layer "F.Cu")
		(net "PCIE_IOM_TO_COMP_10_DP")
	)
	(arc
		(start 198.344536 -141.194536)
		(mid 198.297191 -141.080236)
		(end 198.344536 -140.965936)
		(width 0.14605)
		(layer "F.Cu")
		(net "PCIE_IOM_TO_COMP_10_DP")
	)
	(segment
		(start 149.287484 -33.312862)
		(end 149.059138 -32.961326)
		(width 0.1397)
		(layer "In5.Cu")
		(net "PCIE_IOM_TO_COMP_10_DP")
	)
	(segment
		(start 148.408898 -31.960312)
		(end 148.163026 -31.907988)
		(width 0.1397)
		(layer "In5.Cu")
		(net "PCIE_IOM_TO_COMP_10_DP")
	)
	(segment
		(start 149.23516 -33.558988)
		(end 149.287484 -33.312862)
		(width 0.1397)
		(layer "In5.Cu")
		(net "PCIE_IOM_TO_COMP_10_DP")
	)
	(segment
		(start 197.137782 -142.734792)
		(end 194.841114 -143.183356)
		(width 0.1397)
		(layer "In5.Cu")
		(net "PCIE_IOM_TO_COMP_10_DP")
	)
	(segment
		(start 136.965182 -30.518862)
		(end 136.965182 -35.915854)
		(width 0.1397)
		(layer "In5.Cu")
		(net "PCIE_IOM_TO_COMP_10_DP")
	)
	(segment
		(start 198.128636 -141.194536)
		(end 197.880986 -141.442186)
		(width 0.1397)
		(layer "In5.Cu")
		(net "PCIE_IOM_TO_COMP_10_DP")
	)
	(segment
		(start 163.065714 -104.6226)
		(end 161.301684 -96.323912)
		(width 0.1397)
		(layer "In5.Cu")
		(net "PCIE_IOM_TO_COMP_10_DP")
	)
	(segment
		(start 177.18151 -146.058636)
		(end 164.163756 -143.350996)
		(width 0.1397)
		(layer "In5.Cu")
		(net "PCIE_IOM_TO_COMP_10_DP")
	)
	(segment
		(start 197.79742 -141.643862)
		(end 197.79742 -141.79296)
		(width 0.1397)
		(layer "In5.Cu")
		(net "PCIE_IOM_TO_COMP_10_DP")
	)
	(segment
		(start 151.466042 -36.66744)
		(end 149.709378 -33.962594)
		(width 0.1397)
		(layer "In5.Cu")
		(net "PCIE_IOM_TO_COMP_10_DP")
	)
	(segment
		(start 143.661638 -27.865832)
		(end 142.00124 -27.5336)
		(width 0.1397)
		(layer "In5.Cu")
		(net "PCIE_IOM_TO_COMP_10_DP")
	)
	(segment
		(start 198.434198 -141.284198)
		(end 198.344536 -141.194536)
		(width 0.1397)
		(layer "In5.Cu")
		(net "PCIE_IOM_TO_COMP_10_DP")
	)
	(segment
		(start 164.163756 -143.350996)
		(end 160.675574 -140.998194)
		(width 0.1397)
		(layer "In5.Cu")
		(net "PCIE_IOM_TO_COMP_10_DP")
	)
	(segment
		(start 142.00124 -27.5336)
		(end 139.950444 -27.5336)
		(width 0.1397)
		(layer "In5.Cu")
		(net "PCIE_IOM_TO_COMP_10_DP")
	)
	(segment
		(start 148.637244 -32.311594)
		(end 148.408898 -31.960312)
		(width 0.1397)
		(layer "In5.Cu")
		(net "PCIE_IOM_TO_COMP_10_DP")
	)
	(segment
		(start 149.059138 -32.961326)
		(end 148.813266 -32.909256)
		(width 0.1397)
		(layer "In5.Cu")
		(net "PCIE_IOM_TO_COMP_10_DP")
	)
	(segment
		(start 194.841114 -143.183356)
		(end 193.406268 -142.90421)
		(width 0.1397)
		(layer "In5.Cu")
		(net "PCIE_IOM_TO_COMP_10_DP")
	)
	(segment
		(start 148.813266 -32.909256)
		(end 148.58492 -32.55772)
		(width 0.1397)
		(layer "In5.Cu")
		(net "PCIE_IOM_TO_COMP_10_DP")
	)
	(segment
		(start 147.305014 -30.26029)
		(end 143.661638 -27.865832)
		(width 0.1397)
		(layer "In5.Cu")
		(net "PCIE_IOM_TO_COMP_10_DP")
	)
	(segment
		(start 157.685486 -131.972304)
		(end 163.065714 -104.6226)
		(width 0.1397)
		(layer "In5.Cu")
		(net "PCIE_IOM_TO_COMP_10_DP")
	)
	(segment
		(start 147.987004 -31.31058)
		(end 147.305014 -30.26029)
		(width 0.1397)
		(layer "In5.Cu")
		(net "PCIE_IOM_TO_COMP_10_DP")
	)
	(segment
		(start 193.406268 -142.90421)
		(end 177.18151 -146.058636)
		(width 0.1397)
		(layer "In5.Cu")
		(net "PCIE_IOM_TO_COMP_10_DP")
	)
	(segment
		(start 148.163026 -31.907988)
		(end 147.93468 -31.556452)
		(width 0.1397)
		(layer "In5.Cu")
		(net "PCIE_IOM_TO_COMP_10_DP")
	)
	(segment
		(start 149.463506 -33.91027)
		(end 149.23516 -33.558988)
		(width 0.1397)
		(layer "In5.Cu")
		(net "PCIE_IOM_TO_COMP_10_DP")
	)
	(segment
		(start 147.93468 -31.556452)
		(end 147.987004 -31.31058)
		(width 0.1397)
		(layer "In5.Cu")
		(net "PCIE_IOM_TO_COMP_10_DP")
	)
	(segment
		(start 158.938976 -138.42365)
		(end 157.685486 -131.972304)
		(width 0.1397)
		(layer "In5.Cu")
		(net "PCIE_IOM_TO_COMP_10_DP")
	)
	(segment
		(start 148.58492 -32.55772)
		(end 148.637244 -32.311594)
		(width 0.1397)
		(layer "In5.Cu")
		(net "PCIE_IOM_TO_COMP_10_DP")
	)
	(segment
		(start 149.709378 -33.962594)
		(end 149.463506 -33.91027)
		(width 0.1397)
		(layer "In5.Cu")
		(net "PCIE_IOM_TO_COMP_10_DP")
	)
	(segment
		(start 160.672526 -93.365828)
		(end 158.77159 -84.423504)
		(width 0.1397)
		(layer "In5.Cu")
		(net "PCIE_IOM_TO_COMP_10_DP")
	)
	(segment
		(start 139.950444 -27.5336)
		(end 136.965182 -30.518862)
		(width 0.1397)
		(layer "In5.Cu")
		(net "PCIE_IOM_TO_COMP_10_DP")
	)
	(segment
		(start 160.675574 -140.998194)
		(end 159.80791 -139.711938)
		(width 0.1397)
		(layer "In5.Cu")
		(net "PCIE_IOM_TO_COMP_10_DP")
	)
	(segment
		(start 158.77159 -84.423504)
		(end 160.194498 -77.729334)
		(width 0.1397)
		(layer "In5.Cu")
		(net "PCIE_IOM_TO_COMP_10_DP")
	)
	(segment
		(start 161.301684 -96.323912)
		(end 160.672526 -93.365828)
		(width 0.1397)
		(layer "In5.Cu")
		(net "PCIE_IOM_TO_COMP_10_DP")
	)
	(segment
		(start 159.80791 -139.711938)
		(end 158.938976 -138.42365)
		(width 0.1397)
		(layer "In5.Cu")
		(net "PCIE_IOM_TO_COMP_10_DP")
	)
	(segment
		(start 197.408546 -142.464028)
		(end 197.137782 -142.734792)
		(width 0.1397)
		(layer "In5.Cu")
		(net "PCIE_IOM_TO_COMP_10_DP")
	)
	(segment
		(start 160.194498 -77.729334)
		(end 151.466042 -36.66744)
		(width 0.1397)
		(layer "In5.Cu")
		(net "PCIE_IOM_TO_COMP_10_DP")
	)
	(segment
		(start 137.700004 -35.981132)
		(end 137.700004 -35.600132)
		(width 0.1397)
		(layer "In5.Cu")
		(net "PCIE_IOM_TO_COMP_10_DP")
	)
	(segment
		(start 137.184384 -36.135056)
		(end 137.54608 -36.135056)
		(width 0.1397)
		(layer "In5.Cu")
		(net "PCIE_IOM_TO_COMP_10_DP")
	)
	(segment
		(start 197.597776 -142.275306)
		(end 197.408546 -142.464028)
		(width 0.1397)
		(layer "In5.Cu")
		(net "PCIE_IOM_TO_COMP_10_DP")
	)
	(arc
		(start 198.344536 -141.194536)
		(mid 198.236586 -141.149822)
		(end 198.128636 -141.194536)
		(width 0.1397)
		(layer "In5.Cu")
		(net "PCIE_IOM_TO_COMP_10_DP")
	)
	(arc
		(start 197.79742 -141.79296)
		(mid 197.74559 -142.054)
		(end 197.597776 -142.275306)
		(width 0.1397)
		(layer "In5.Cu")
		(net "PCIE_IOM_TO_COMP_10_DP")
	)
	(arc
		(start 197.880986 -141.442186)
		(mid 197.81916 -141.534716)
		(end 197.79742 -141.643862)
		(width 0.1397)
		(layer "In5.Cu")
		(net "PCIE_IOM_TO_COMP_10_DP")
	)
	(arc
		(start 136.965182 -35.915854)
		(mid 137.029385 -36.070853)
		(end 137.184384 -36.135056)
		(width 0.1397)
		(layer "In5.Cu")
		(net "PCIE_IOM_TO_COMP_10_DP")
	)
	(arc
		(start 137.54608 -36.135056)
		(mid 137.654921 -36.089973)
		(end 137.700004 -35.981132)
		(width 0.1397)
		(layer "In5.Cu")
		(net "PCIE_IOM_TO_COMP_10_DP")
	)
	(segment
		(start 197.805802 -140.655802)
		(end 197.895464 -140.745464)
		(width 0.14605)
		(layer "F.Cu")
		(net "PCIE_IOM_TO_COMP_10_DN")
	)
	(segment
		(start 199.2376 -137.278618)
		(end 199.2376 -135.80745)
		(width 0.14605)
		(layer "F.Cu")
		(net "PCIE_IOM_TO_COMP_10_DN")
	)
	(segment
		(start 198.124572 -140.745464)
		(end 198.124572 -140.745718)
		(width 0.14605)
		(layer "F.Cu")
		(net "PCIE_IOM_TO_COMP_10_DN")
	)
	(segment
		(start 199.14997 -135.71982)
		(end 199.14997 -134.875016)
		(width 0.14605)
		(layer "F.Cu")
		(net "PCIE_IOM_TO_COMP_10_DN")
	)
	(segment
		(start 198.124572 -140.745718)
		(end 198.33717 -140.532866)
		(width 0.14605)
		(layer "F.Cu")
		(net "PCIE_IOM_TO_COMP_10_DN")
	)
	(segment
		(start 198.382382 -140.424154)
		(end 198.382382 -138.133836)
		(width 0.14605)
		(layer "F.Cu")
		(net "PCIE_IOM_TO_COMP_10_DN")
	)
	(segment
		(start 199.2376 -135.80745)
		(end 199.14997 -135.71982)
		(width 0.14605)
		(layer "F.Cu")
		(net "PCIE_IOM_TO_COMP_10_DN")
	)
	(segment
		(start 198.382382 -138.133836)
		(end 199.2376 -137.278618)
		(width 0.14605)
		(layer "F.Cu")
		(net "PCIE_IOM_TO_COMP_10_DN")
	)
	(segment
		(start 198.33717 -140.532866)
		(end 198.33717 -140.53312)
		(width 0.14605)
		(layer "F.Cu")
		(net "PCIE_IOM_TO_COMP_10_DN")
	)
	(arc
		(start 198.33717 -140.53312)
		(mid 198.370683 -140.483155)
		(end 198.382382 -140.424154)
		(width 0.14605)
		(layer "F.Cu")
		(net "PCIE_IOM_TO_COMP_10_DN")
	)
	(arc
		(start 197.895464 -140.745464)
		(mid 198.010018 -140.792914)
		(end 198.124572 -140.745464)
		(width 0.14605)
		(layer "F.Cu")
		(net "PCIE_IOM_TO_COMP_10_DN")
	)
	(segment
		(start 197.175374 -142.230094)
		(end 196.975476 -142.429992)
		(width 0.1397)
		(layer "In5.Cu")
		(net "PCIE_IOM_TO_COMP_10_DN")
	)
	(segment
		(start 160.913572 -140.760196)
		(end 160.081722 -139.52728)
		(width 0.1397)
		(layer "In5.Cu")
		(net "PCIE_IOM_TO_COMP_10_DN")
	)
	(segment
		(start 160.081722 -139.52728)
		(end 159.25038 -138.294618)
		(width 0.1397)
		(layer "In5.Cu")
		(net "PCIE_IOM_TO_COMP_10_DN")
	)
	(segment
		(start 147.544282 -30.022292)
		(end 143.7894 -27.554428)
		(width 0.1397)
		(layer "In5.Cu")
		(net "PCIE_IOM_TO_COMP_10_DN")
	)
	(segment
		(start 160.532318 -77.729334)
		(end 151.77643 -36.538916)
		(width 0.1397)
		(layer "In5.Cu")
		(net "PCIE_IOM_TO_COMP_10_DN")
	)
	(segment
		(start 197.46722 -141.793214)
		(end 197.466966 -141.79296)
		(width 0.1397)
		(layer "In5.Cu")
		(net "PCIE_IOM_TO_COMP_10_DN")
	)
	(segment
		(start 158.022036 -131.972812)
		(end 163.402772 -104.62006)
		(width 0.1397)
		(layer "In5.Cu")
		(net "PCIE_IOM_TO_COMP_10_DN")
	)
	(segment
		(start 151.77643 -36.538916)
		(end 147.544282 -30.022292)
		(width 0.1397)
		(layer "In5.Cu")
		(net "PCIE_IOM_TO_COMP_10_DN")
	)
	(segment
		(start 160.366964 -90.339164)
		(end 159.10941 -84.423504)
		(width 0.1397)
		(layer "In5.Cu")
		(net "PCIE_IOM_TO_COMP_10_DN")
	)
	(segment
		(start 136.634982 -30.381956)
		(end 136.634982 -35.915854)
		(width 0.1397)
		(layer "In5.Cu")
		(net "PCIE_IOM_TO_COMP_10_DN")
	)
	(segment
		(start 142.034006 -27.2034)
		(end 139.813538 -27.2034)
		(width 0.1397)
		(layer "In5.Cu")
		(net "PCIE_IOM_TO_COMP_10_DN")
	)
	(segment
		(start 163.402772 -104.62006)
		(end 161.624772 -96.255332)
		(width 0.1397)
		(layer "In5.Cu")
		(net "PCIE_IOM_TO_COMP_10_DN")
	)
	(segment
		(start 137.700004 -36.61918)
		(end 137.700004 -37.00018)
		(width 0.1397)
		(layer "In5.Cu")
		(net "PCIE_IOM_TO_COMP_10_DN")
	)
	(segment
		(start 139.813538 -27.2034)
		(end 136.634982 -30.381956)
		(width 0.1397)
		(layer "In5.Cu")
		(net "PCIE_IOM_TO_COMP_10_DN")
	)
	(segment
		(start 143.7894 -27.554428)
		(end 142.034006 -27.2034)
		(width 0.1397)
		(layer "In5.Cu")
		(net "PCIE_IOM_TO_COMP_10_DN")
	)
	(segment
		(start 197.895464 -140.960348)
		(end 197.895464 -140.960602)
		(width 0.1397)
		(layer "In5.Cu")
		(net "PCIE_IOM_TO_COMP_10_DN")
	)
	(segment
		(start 159.25038 -138.294618)
		(end 158.022036 -131.972812)
		(width 0.1397)
		(layer "In5.Cu")
		(net "PCIE_IOM_TO_COMP_10_DN")
	)
	(segment
		(start 164.294566 -143.040862)
		(end 160.913572 -140.760196)
		(width 0.1397)
		(layer "In5.Cu")
		(net "PCIE_IOM_TO_COMP_10_DN")
	)
	(segment
		(start 177.183796 -145.721578)
		(end 164.294566 -143.040862)
		(width 0.1397)
		(layer "In5.Cu")
		(net "PCIE_IOM_TO_COMP_10_DN")
	)
	(segment
		(start 193.406268 -142.56766)
		(end 177.183796 -145.721578)
		(width 0.1397)
		(layer "In5.Cu")
		(net "PCIE_IOM_TO_COMP_10_DN")
	)
	(segment
		(start 159.10941 -84.423504)
		(end 160.532318 -77.729334)
		(width 0.1397)
		(layer "In5.Cu")
		(net "PCIE_IOM_TO_COMP_10_DN")
	)
	(segment
		(start 197.46722 -141.643608)
		(end 197.46722 -141.793214)
		(width 0.1397)
		(layer "In5.Cu")
		(net "PCIE_IOM_TO_COMP_10_DN")
	)
	(segment
		(start 137.184384 -36.465256)
		(end 137.54608 -36.465256)
		(width 0.1397)
		(layer "In5.Cu")
		(net "PCIE_IOM_TO_COMP_10_DN")
	)
	(segment
		(start 197.805802 -140.655802)
		(end 197.895464 -140.745464)
		(width 0.1397)
		(layer "In5.Cu")
		(net "PCIE_IOM_TO_COMP_10_DN")
	)
	(segment
		(start 197.36435 -142.041626)
		(end 197.175374 -142.230094)
		(width 0.1397)
		(layer "In5.Cu")
		(net "PCIE_IOM_TO_COMP_10_DN")
	)
	(segment
		(start 161.624772 -96.255332)
		(end 160.366964 -90.339164)
		(width 0.1397)
		(layer "In5.Cu")
		(net "PCIE_IOM_TO_COMP_10_DN")
	)
	(segment
		(start 194.841114 -142.846806)
		(end 193.406268 -142.56766)
		(width 0.1397)
		(layer "In5.Cu")
		(net "PCIE_IOM_TO_COMP_10_DN")
	)
	(segment
		(start 196.975476 -142.429992)
		(end 194.841114 -142.846806)
		(width 0.1397)
		(layer "In5.Cu")
		(net "PCIE_IOM_TO_COMP_10_DN")
	)
	(segment
		(start 197.895464 -140.960602)
		(end 197.647306 -141.208506)
		(width 0.1397)
		(layer "In5.Cu")
		(net "PCIE_IOM_TO_COMP_10_DN")
	)
	(arc
		(start 197.647306 -141.208506)
		(mid 197.514027 -141.408161)
		(end 197.46722 -141.643608)
		(width 0.1397)
		(layer "In5.Cu")
		(net "PCIE_IOM_TO_COMP_10_DN")
	)
	(arc
		(start 137.54608 -36.465256)
		(mid 137.654921 -36.510339)
		(end 137.700004 -36.61918)
		(width 0.1397)
		(layer "In5.Cu")
		(net "PCIE_IOM_TO_COMP_10_DN")
	)
	(arc
		(start 136.634982 -35.915854)
		(mid 136.795898 -36.30434)
		(end 137.184384 -36.465256)
		(width 0.1397)
		(layer "In5.Cu")
		(net "PCIE_IOM_TO_COMP_10_DN")
	)
	(arc
		(start 197.466966 -141.79296)
		(mid 197.440339 -141.927472)
		(end 197.36435 -142.041626)
		(width 0.1397)
		(layer "In5.Cu")
		(net "PCIE_IOM_TO_COMP_10_DN")
	)
	(arc
		(start 197.895464 -140.745464)
		(mid 197.939968 -140.852906)
		(end 197.895464 -140.960348)
		(width 0.1397)
		(layer "In5.Cu")
		(net "PCIE_IOM_TO_COMP_10_DN")
	)
	(segment
		(start 87.817706 -63.755016)
		(end 86.925912 -62.863222)
		(width 0.127)
		(layer "F.Cu")
		(net "PCIE_COMP_TO_IOM_RST_4_R")
	)
	(segment
		(start 84.187538 -61.649356)
		(end 85.712046 -61.649356)
		(width 0.127)
		(layer "F.Cu")
		(net "PCIE_COMP_TO_IOM_RST_4_R")
	)
	(segment
		(start 79.925164 -61.74994)
		(end 84.086954 -61.74994)
		(width 0.127)
		(layer "F.Cu")
		(net "PCIE_COMP_TO_IOM_RST_4_R")
	)
	(segment
		(start 84.086954 -61.74994)
		(end 84.187538 -61.649356)
		(width 0.127)
		(layer "F.Cu")
		(net "PCIE_COMP_TO_IOM_RST_4_R")
	)
	(segment
		(start 85.712046 -61.649356)
		(end 86.925912 -62.863222)
		(width 0.127)
		(layer "F.Cu")
		(net "PCIE_COMP_TO_IOM_RST_4_R")
	)
	(segment
		(start 88.369394 -63.755016)
		(end 87.817706 -63.755016)
		(width 0.127)
		(layer "F.Cu")
		(net "PCIE_COMP_TO_IOM_RST_4_R")
	)
	(via
		(at 86.925912 -62.863222)
		(size 0.6604)
		(drill 0.3302)
		(layers "F.Cu" "B.Cu")
		(net "PCIE_COMP_TO_IOM_RST_4_R")
	)
	(segment
		(start 90.9447 -64.530224)
		(end 90.9447 -64.532256)
		(width 0.127)
		(layer "F.Cu")
		(net "PCIE_COMP_TO_IOM_RST_4")
	)
	(segment
		(start 92.140786 -89.389458)
		(end 95.73514 -92.983812)
		(width 0.127)
		(layer "F.Cu")
		(net "PCIE_COMP_TO_IOM_RST_4")
	)
	(segment
		(start 92.140786 -65.728342)
		(end 92.140786 -89.389458)
		(width 0.127)
		(layer "F.Cu")
		(net "PCIE_COMP_TO_IOM_RST_4")
	)
	(segment
		(start 90.169492 -63.755016)
		(end 90.9447 -64.530224)
		(width 0.127)
		(layer "F.Cu")
		(net "PCIE_COMP_TO_IOM_RST_4")
	)
	(segment
		(start 44.2976 -129.5146)
		(end 44.3738 -129.4384)
		(width 0.127)
		(layer "F.Cu")
		(net "PCIE_COMP_TO_IOM_RST_4")
	)
	(segment
		(start 90.9447 -64.532256)
		(end 92.140786 -65.728342)
		(width 0.127)
		(layer "F.Cu")
		(net "PCIE_COMP_TO_IOM_RST_4")
	)
	(segment
		(start 44.2976 -130.2131)
		(end 44.2976 -129.5146)
		(width 0.127)
		(layer "F.Cu")
		(net "PCIE_COMP_TO_IOM_RST_4")
	)
	(segment
		(start 99.728274 -158.361126)
		(end 99.2124 -158.877)
		(width 0.127)
		(layer "F.Cu")
		(net "PCIE_COMP_TO_IOM_RST_4")
	)
	(segment
		(start 89.258394 -63.755016)
		(end 90.169492 -63.755016)
		(width 0.127)
		(layer "F.Cu")
		(net "PCIE_COMP_TO_IOM_RST_4")
	)
	(segment
		(start 99.728274 -158.05531)
		(end 99.728274 -158.361126)
		(width 0.127)
		(layer "F.Cu")
		(net "PCIE_COMP_TO_IOM_RST_4")
	)
	(via
		(at 95.73514 -92.983812)
		(size 0.508)
		(drill 0.254)
		(layers "F.Cu" "B.Cu")
		(net "PCIE_COMP_TO_IOM_RST_4")
	)
	(via
		(at 44.3738 -129.4384)
		(size 0.508)
		(drill 0.254)
		(layers "F.Cu" "B.Cu")
		(net "PCIE_COMP_TO_IOM_RST_4")
	)
	(via
		(at 91.926156 -172.765974)
		(size 0.508)
		(drill 0.254)
		(layers "F.Cu" "B.Cu")
		(net "PCIE_COMP_TO_IOM_RST_4")
	)
	(via
		(at 99.2124 -158.877)
		(size 0.508)
		(drill 0.254)
		(layers "F.Cu" "B.Cu")
		(net "PCIE_COMP_TO_IOM_RST_4")
	)
	(via
		(at 94.9198 -122.6058)
		(size 0.508)
		(drill 0.254)
		(layers "F.Cu" "B.Cu")
		(net "PCIE_COMP_TO_IOM_RST_4")
	)
	(via
		(at 90.9447 -64.530224)
		(size 0.6604)
		(drill 0.3302)
		(layers "F.Cu" "B.Cu")
		(net "PCIE_COMP_TO_IOM_RST_4")
	)
	(segment
		(start 94.9198 -122.6058)
		(end 94.79788 -122.48388)
		(width 0.127)
		(layer "B.Cu")
		(net "PCIE_COMP_TO_IOM_RST_4")
	)
	(segment
		(start 95.758 -92.983812)
		(end 95.73514 -92.983812)
		(width 0.127)
		(layer "B.Cu")
		(net "PCIE_COMP_TO_IOM_RST_4")
	)
	(segment
		(start 97.7646 -95.0722)
		(end 95.758 -93.0656)
		(width 0.127)
		(layer "B.Cu")
		(net "PCIE_COMP_TO_IOM_RST_4")
	)
	(segment
		(start 91.6686 -173.02353)
		(end 91.926156 -172.765974)
		(width 0.127)
		(layer "B.Cu")
		(net "PCIE_COMP_TO_IOM_RST_4")
	)
	(segment
		(start 90.84437 -173.02353)
		(end 91.6686 -173.02353)
		(width 0.127)
		(layer "B.Cu")
		(net "PCIE_COMP_TO_IOM_RST_4")
	)
	(segment
		(start 97.7646 -115.7732)
		(end 97.7646 -95.0722)
		(width 0.127)
		(layer "B.Cu")
		(net "PCIE_COMP_TO_IOM_RST_4")
	)
	(segment
		(start 96.0628 -117.475)
		(end 97.7646 -115.7732)
		(width 0.127)
		(layer "B.Cu")
		(net "PCIE_COMP_TO_IOM_RST_4")
	)
	(segment
		(start 94.79788 -122.48388)
		(end 94.79788 -121.40692)
		(width 0.127)
		(layer "B.Cu")
		(net "PCIE_COMP_TO_IOM_RST_4")
	)
	(segment
		(start 95.758 -93.0656)
		(end 95.758 -92.983812)
		(width 0.127)
		(layer "B.Cu")
		(net "PCIE_COMP_TO_IOM_RST_4")
	)
	(segment
		(start 96.0628 -120.142)
		(end 96.0628 -117.475)
		(width 0.127)
		(layer "B.Cu")
		(net "PCIE_COMP_TO_IOM_RST_4")
	)
	(segment
		(start 94.79788 -121.40692)
		(end 96.0628 -120.142)
		(width 0.127)
		(layer "B.Cu")
		(net "PCIE_COMP_TO_IOM_RST_4")
	)
	(segment
		(start 94.79788 -122.72772)
		(end 94.79788 -125.58268)
		(width 0.127)
		(layer "In2.Cu")
		(net "PCIE_COMP_TO_IOM_RST_4")
	)
	(segment
		(start 94.79788 -125.58268)
		(end 95.825818 -126.610618)
		(width 0.127)
		(layer "In2.Cu")
		(net "PCIE_COMP_TO_IOM_RST_4")
	)
	(segment
		(start 95.3516 -65.1764)
		(end 95.885 -64.643)
		(width 0.127)
		(layer "In2.Cu")
		(net "PCIE_COMP_TO_IOM_RST_4")
	)
	(segment
		(start 94.2086 -150.642066)
		(end 96.4819 -152.915366)
		(width 0.127)
		(layer "In2.Cu")
		(net "PCIE_COMP_TO_IOM_RST_4")
	)
	(segment
		(start 95.825818 -137.913618)
		(end 95.855536 -137.913618)
		(width 0.127)
		(layer "In2.Cu")
		(net "PCIE_COMP_TO_IOM_RST_4")
	)
	(segment
		(start 95.960692 -84.183474)
		(end 95.960692 -83.018884)
		(width 0.127)
		(layer "In2.Cu")
		(net "PCIE_COMP_TO_IOM_RST_4")
	)
	(segment
		(start 95.825818 -126.610618)
		(end 95.825818 -137.913618)
		(width 0.127)
		(layer "In2.Cu")
		(net "PCIE_COMP_TO_IOM_RST_4")
	)
	(segment
		(start 97.019364 -167.623744)
		(end 99.2124 -165.430708)
		(width 0.127)
		(layer "In2.Cu")
		(net "PCIE_COMP_TO_IOM_RST_4")
	)
	(segment
		(start 91.926156 -172.765974)
		(end 93.730572 -172.765974)
		(width 0.127)
		(layer "In2.Cu")
		(net "PCIE_COMP_TO_IOM_RST_4")
	)
	(segment
		(start 96.4819 -152.915366)
		(end 96.4819 -156.1465)
		(width 0.127)
		(layer "In2.Cu")
		(net "PCIE_COMP_TO_IOM_RST_4")
	)
	(segment
		(start 99.2124 -165.430708)
		(end 99.2124 -158.877)
		(width 0.127)
		(layer "In2.Cu")
		(net "PCIE_COMP_TO_IOM_RST_4")
	)
	(segment
		(start 96.130618 -138.1887)
		(end 96.130618 -138.578336)
		(width 0.127)
		(layer "In2.Cu")
		(net "PCIE_COMP_TO_IOM_RST_4")
	)
	(segment
		(start 95.73514 -92.745306)
		(end 95.3516 -92.361766)
		(width 0.127)
		(layer "In2.Cu")
		(net "PCIE_COMP_TO_IOM_RST_4")
	)
	(segment
		(start 95.948246 -144.522698)
		(end 94.2086 -146.262344)
		(width 0.127)
		(layer "In2.Cu")
		(net "PCIE_COMP_TO_IOM_RST_4")
	)
	(segment
		(start 95.73514 -92.983812)
		(end 95.73514 -92.745306)
		(width 0.127)
		(layer "In2.Cu")
		(net "PCIE_COMP_TO_IOM_RST_4")
	)
	(segment
		(start 94.2086 -146.262344)
		(end 94.2086 -150.642066)
		(width 0.127)
		(layer "In2.Cu")
		(net "PCIE_COMP_TO_IOM_RST_4")
	)
	(segment
		(start 95.3516 -82.409792)
		(end 95.3516 -65.1764)
		(width 0.127)
		(layer "In2.Cu")
		(net "PCIE_COMP_TO_IOM_RST_4")
	)
	(segment
		(start 95.885 -64.643)
		(end 95.885 -36.98621)
		(width 0.127)
		(layer "In2.Cu")
		(net "PCIE_COMP_TO_IOM_RST_4")
	)
	(segment
		(start 120.27154 -38.628574)
		(end 119.70004 -39.200074)
		(width 0.127)
		(layer "In2.Cu")
		(net "PCIE_COMP_TO_IOM_RST_4")
	)
	(segment
		(start 97.019364 -169.477182)
		(end 97.019364 -167.623744)
		(width 0.127)
		(layer "In2.Cu")
		(net "PCIE_COMP_TO_IOM_RST_4")
	)
	(segment
		(start 95.855536 -137.913618)
		(end 96.130618 -138.1887)
		(width 0.127)
		(layer "In2.Cu")
		(net "PCIE_COMP_TO_IOM_RST_4")
	)
	(segment
		(start 98.2218 -34.64941)
		(end 98.2218 -34.228786)
		(width 0.127)
		(layer "In2.Cu")
		(net "PCIE_COMP_TO_IOM_RST_4")
	)
	(segment
		(start 95.948246 -138.760708)
		(end 95.948246 -144.522698)
		(width 0.127)
		(layer "In2.Cu")
		(net "PCIE_COMP_TO_IOM_RST_4")
	)
	(segment
		(start 95.960692 -83.018884)
		(end 95.3516 -82.409792)
		(width 0.127)
		(layer "In2.Cu")
		(net "PCIE_COMP_TO_IOM_RST_4")
	)
	(segment
		(start 114.146584 -23.851616)
		(end 120.27154 -29.976572)
		(width 0.127)
		(layer "In2.Cu")
		(net "PCIE_COMP_TO_IOM_RST_4")
	)
	(segment
		(start 120.27154 -29.976572)
		(end 120.27154 -38.628574)
		(width 0.127)
		(layer "In2.Cu")
		(net "PCIE_COMP_TO_IOM_RST_4")
	)
	(segment
		(start 96.4819 -156.1465)
		(end 99.2124 -158.877)
		(width 0.127)
		(layer "In2.Cu")
		(net "PCIE_COMP_TO_IOM_RST_4")
	)
	(segment
		(start 98.221546 -34.228532)
		(end 98.221546 -29.930344)
		(width 0.127)
		(layer "In2.Cu")
		(net "PCIE_COMP_TO_IOM_RST_4")
	)
	(segment
		(start 94.9198 -122.6058)
		(end 94.79788 -122.72772)
		(width 0.127)
		(layer "In2.Cu")
		(net "PCIE_COMP_TO_IOM_RST_4")
	)
	(segment
		(start 95.3516 -92.361766)
		(end 95.3516 -84.792566)
		(width 0.127)
		(layer "In2.Cu")
		(net "PCIE_COMP_TO_IOM_RST_4")
	)
	(segment
		(start 95.885 -36.98621)
		(end 98.2218 -34.64941)
		(width 0.127)
		(layer "In2.Cu")
		(net "PCIE_COMP_TO_IOM_RST_4")
	)
	(segment
		(start 93.730572 -172.765974)
		(end 97.019364 -169.477182)
		(width 0.127)
		(layer "In2.Cu")
		(net "PCIE_COMP_TO_IOM_RST_4")
	)
	(segment
		(start 98.2218 -34.228786)
		(end 98.221546 -34.228532)
		(width 0.127)
		(layer "In2.Cu")
		(net "PCIE_COMP_TO_IOM_RST_4")
	)
	(segment
		(start 95.3516 -84.792566)
		(end 95.960692 -84.183474)
		(width 0.127)
		(layer "In2.Cu")
		(net "PCIE_COMP_TO_IOM_RST_4")
	)
	(segment
		(start 96.130618 -138.578336)
		(end 95.948246 -138.760708)
		(width 0.127)
		(layer "In2.Cu")
		(net "PCIE_COMP_TO_IOM_RST_4")
	)
	(segment
		(start 104.300274 -23.851616)
		(end 114.146584 -23.851616)
		(width 0.127)
		(layer "In2.Cu")
		(net "PCIE_COMP_TO_IOM_RST_4")
	)
	(segment
		(start 98.221546 -29.930344)
		(end 104.300274 -23.851616)
		(width 0.127)
		(layer "In2.Cu")
		(net "PCIE_COMP_TO_IOM_RST_4")
	)
	(segment
		(start 86.3346 -125.3998)
		(end 85.222588 -125.3998)
		(width 0.127)
		(layer "In5.Cu")
		(net "PCIE_COMP_TO_IOM_RST_4")
	)
	(segment
		(start 87.8332 -123.9012)
		(end 86.3346 -125.3998)
		(width 0.127)
		(layer "In5.Cu")
		(net "PCIE_COMP_TO_IOM_RST_4")
	)
	(segment
		(start 58.676032 -127.5969)
		(end 55.939182 -127.5969)
		(width 0.127)
		(layer "In5.Cu")
		(net "PCIE_COMP_TO_IOM_RST_4")
	)
	(segment
		(start 94.9198 -122.6058)
		(end 94.83598 -122.6058)
		(width 0.127)
		(layer "In5.Cu")
		(net "PCIE_COMP_TO_IOM_RST_4")
	)
	(segment
		(start 52.497482 -131.0386)
		(end 45.974 -131.0386)
		(width 0.127)
		(layer "In5.Cu")
		(net "PCIE_COMP_TO_IOM_RST_4")
	)
	(segment
		(start 70.88632 -126.6698)
		(end 70.25132 -127.3048)
		(width 0.127)
		(layer "In5.Cu")
		(net "PCIE_COMP_TO_IOM_RST_4")
	)
	(segment
		(start 65.473834 -127.3048)
		(end 65.245234 -127.0762)
		(width 0.127)
		(layer "In5.Cu")
		(net "PCIE_COMP_TO_IOM_RST_4")
	)
	(segment
		(start 94.83598 -122.6058)
		(end 93.54058 -123.9012)
		(width 0.127)
		(layer "In5.Cu")
		(net "PCIE_COMP_TO_IOM_RST_4")
	)
	(segment
		(start 74.8792 -126.6698)
		(end 70.88632 -126.6698)
		(width 0.127)
		(layer "In5.Cu")
		(net "PCIE_COMP_TO_IOM_RST_4")
	)
	(segment
		(start 70.25132 -127.3048)
		(end 65.473834 -127.3048)
		(width 0.127)
		(layer "In5.Cu")
		(net "PCIE_COMP_TO_IOM_RST_4")
	)
	(segment
		(start 65.245234 -127.0762)
		(end 59.196732 -127.0762)
		(width 0.127)
		(layer "In5.Cu")
		(net "PCIE_COMP_TO_IOM_RST_4")
	)
	(segment
		(start 85.222588 -125.3998)
		(end 83.088988 -127.5334)
		(width 0.127)
		(layer "In5.Cu")
		(net "PCIE_COMP_TO_IOM_RST_4")
	)
	(segment
		(start 55.939182 -127.5969)
		(end 52.497482 -131.0386)
		(width 0.127)
		(layer "In5.Cu")
		(net "PCIE_COMP_TO_IOM_RST_4")
	)
	(segment
		(start 45.974 -131.0386)
		(end 44.3738 -129.4384)
		(width 0.127)
		(layer "In5.Cu")
		(net "PCIE_COMP_TO_IOM_RST_4")
	)
	(segment
		(start 83.088988 -127.5334)
		(end 75.7428 -127.5334)
		(width 0.127)
		(layer "In5.Cu")
		(net "PCIE_COMP_TO_IOM_RST_4")
	)
	(segment
		(start 75.7428 -127.5334)
		(end 74.8792 -126.6698)
		(width 0.127)
		(layer "In5.Cu")
		(net "PCIE_COMP_TO_IOM_RST_4")
	)
	(segment
		(start 93.54058 -123.9012)
		(end 87.8332 -123.9012)
		(width 0.127)
		(layer "In5.Cu")
		(net "PCIE_COMP_TO_IOM_RST_4")
	)
	(segment
		(start 59.196732 -127.0762)
		(end 58.676032 -127.5969)
		(width 0.127)
		(layer "In5.Cu")
		(net "PCIE_COMP_TO_IOM_RST_4")
	)
	(segment
		(start 174.426118 -117.0432)
		(end 176.7078 -117.0432)
		(width 0.127)
		(layer "F.Cu")
		(net "PCIE_COMP_TO_IOM_RST_3")
	)
	(segment
		(start 129.954528 -30.132528)
		(end 131.294632 -30.132528)
		(width 0.127)
		(layer "F.Cu")
		(net "PCIE_COMP_TO_IOM_RST_3")
	)
	(segment
		(start 177.41519 -116.33581)
		(end 179.004976 -116.33581)
		(width 0.127)
		(layer "F.Cu")
		(net "PCIE_COMP_TO_IOM_RST_3")
	)
	(segment
		(start 133.196838 -32.034734)
		(end 133.196838 -38.29685)
		(width 0.127)
		(layer "F.Cu")
		(net "PCIE_COMP_TO_IOM_RST_3")
	)
	(segment
		(start 176.7078 -117.0432)
		(end 177.41519 -116.33581)
		(width 0.127)
		(layer "F.Cu")
		(net "PCIE_COMP_TO_IOM_RST_3")
	)
	(segment
		(start 181.880256 -119.21109)
		(end 180.500782 -117.831616)
		(width 0.127)
		(layer "F.Cu")
		(net "PCIE_COMP_TO_IOM_RST_3")
	)
	(segment
		(start 131.294632 -30.132528)
		(end 133.196838 -32.034734)
		(width 0.127)
		(layer "F.Cu")
		(net "PCIE_COMP_TO_IOM_RST_3")
	)
	(segment
		(start 181.880256 -125.265688)
		(end 181.880256 -119.21109)
		(width 0.127)
		(layer "F.Cu")
		(net "PCIE_COMP_TO_IOM_RST_3")
	)
	(segment
		(start 182.39994 -125.785372)
		(end 181.880256 -125.265688)
		(width 0.127)
		(layer "F.Cu")
		(net "PCIE_COMP_TO_IOM_RST_3")
	)
	(segment
		(start 172.7708 -114.173)
		(end 172.7708 -115.387882)
		(width 0.127)
		(layer "F.Cu")
		(net "PCIE_COMP_TO_IOM_RST_3")
	)
	(segment
		(start 133.196838 -38.29685)
		(end 134.100062 -39.200074)
		(width 0.127)
		(layer "F.Cu")
		(net "PCIE_COMP_TO_IOM_RST_3")
	)
	(segment
		(start 127.9398 -28.1178)
		(end 129.954528 -30.132528)
		(width 0.127)
		(layer "F.Cu")
		(net "PCIE_COMP_TO_IOM_RST_3")
	)
	(segment
		(start 172.7708 -115.387882)
		(end 174.426118 -117.0432)
		(width 0.127)
		(layer "F.Cu")
		(net "PCIE_COMP_TO_IOM_RST_3")
	)
	(segment
		(start 182.39994 -127.324866)
		(end 182.39994 -125.785372)
		(width 0.127)
		(layer "F.Cu")
		(net "PCIE_COMP_TO_IOM_RST_3")
	)
	(segment
		(start 127.9398 -27.3304)
		(end 127.9398 -28.1178)
		(width 0.127)
		(layer "F.Cu")
		(net "PCIE_COMP_TO_IOM_RST_3")
	)
	(segment
		(start 179.004976 -116.33581)
		(end 180.500782 -117.831616)
		(width 0.127)
		(layer "F.Cu")
		(net "PCIE_COMP_TO_IOM_RST_3")
	)
	(via
		(at 172.7708 -114.173)
		(size 0.508)
		(drill 0.254)
		(layers "F.Cu" "B.Cu")
		(net "PCIE_COMP_TO_IOM_RST_3")
	)
	(via
		(at 180.500782 -117.831616)
		(size 0.6604)
		(drill 0.3302)
		(layers "F.Cu" "B.Cu")
		(net "PCIE_COMP_TO_IOM_RST_3")
	)
	(via
		(at 127.9398 -27.3304)
		(size 0.508)
		(drill 0.254)
		(layers "F.Cu" "B.Cu")
		(net "PCIE_COMP_TO_IOM_RST_3")
	)
	(segment
		(start 150.832058 -16.994632)
		(end 151.501602 -17.664176)
		(width 0.127)
		(layer "In5.Cu")
		(net "PCIE_COMP_TO_IOM_RST_3")
	)
	(segment
		(start 132.5118 -19.33448)
		(end 133.0706 -18.77568)
		(width 0.127)
		(layer "In5.Cu")
		(net "PCIE_COMP_TO_IOM_RST_3")
	)
	(segment
		(start 151.501602 -18.653252)
		(end 172.687488 -39.839138)
		(width 0.127)
		(layer "In5.Cu")
		(net "PCIE_COMP_TO_IOM_RST_3")
	)
	(segment
		(start 143.815054 -18.77568)
		(end 145.596102 -16.994632)
		(width 0.127)
		(layer "In5.Cu")
		(net "PCIE_COMP_TO_IOM_RST_3")
	)
	(segment
		(start 127 -26.3906)
		(end 127 -25.8318)
		(width 0.127)
		(layer "In5.Cu")
		(net "PCIE_COMP_TO_IOM_RST_3")
	)
	(segment
		(start 127.9398 -27.3304)
		(end 127 -26.3906)
		(width 0.127)
		(layer "In5.Cu")
		(net "PCIE_COMP_TO_IOM_RST_3")
	)
	(segment
		(start 133.0706 -18.77568)
		(end 143.815054 -18.77568)
		(width 0.127)
		(layer "In5.Cu")
		(net "PCIE_COMP_TO_IOM_RST_3")
	)
	(segment
		(start 172.8724 -112.9538)
		(end 172.7708 -113.0554)
		(width 0.127)
		(layer "In5.Cu")
		(net "PCIE_COMP_TO_IOM_RST_3")
	)
	(segment
		(start 145.596102 -16.994632)
		(end 150.832058 -16.994632)
		(width 0.127)
		(layer "In5.Cu")
		(net "PCIE_COMP_TO_IOM_RST_3")
	)
	(segment
		(start 172.687488 -39.839138)
		(end 172.687488 -95.584518)
		(width 0.127)
		(layer "In5.Cu")
		(net "PCIE_COMP_TO_IOM_RST_3")
	)
	(segment
		(start 172.8724 -95.76943)
		(end 172.8724 -112.9538)
		(width 0.127)
		(layer "In5.Cu")
		(net "PCIE_COMP_TO_IOM_RST_3")
	)
	(segment
		(start 151.501602 -17.664176)
		(end 151.501602 -18.653252)
		(width 0.127)
		(layer "In5.Cu")
		(net "PCIE_COMP_TO_IOM_RST_3")
	)
	(segment
		(start 132.5118 -20.32)
		(end 132.5118 -19.33448)
		(width 0.127)
		(layer "In5.Cu")
		(net "PCIE_COMP_TO_IOM_RST_3")
	)
	(segment
		(start 172.687488 -95.584518)
		(end 172.8724 -95.76943)
		(width 0.127)
		(layer "In5.Cu")
		(net "PCIE_COMP_TO_IOM_RST_3")
	)
	(segment
		(start 172.7708 -113.0554)
		(end 172.7708 -114.173)
		(width 0.127)
		(layer "In5.Cu")
		(net "PCIE_COMP_TO_IOM_RST_3")
	)
	(segment
		(start 127 -25.8318)
		(end 132.5118 -20.32)
		(width 0.127)
		(layer "In5.Cu")
		(net "PCIE_COMP_TO_IOM_RST_3")
	)
	(segment
		(start 177.1142 -115.697)
		(end 176.47539 -116.33581)
		(width 0.127)
		(layer "F.Cu")
		(net "PCIE_COMP_TO_IOM_RST_2")
	)
	(segment
		(start 142.004542 -38.495478)
		(end 141.299946 -39.200074)
		(width 0.127)
		(layer "F.Cu")
		(net "PCIE_COMP_TO_IOM_RST_2")
	)
	(segment
		(start 137.739374 -23.192232)
		(end 142.004542 -27.4574)
		(width 0.127)
		(layer "F.Cu")
		(net "PCIE_COMP_TO_IOM_RST_2")
	)
	(segment
		(start 183.243982 -119.592852)
		(end 179.34813 -115.697)
		(width 0.127)
		(layer "F.Cu")
		(net "PCIE_COMP_TO_IOM_RST_2")
	)
	(segment
		(start 186.629294 -119.592852)
		(end 183.243982 -119.592852)
		(width 0.127)
		(layer "F.Cu")
		(net "PCIE_COMP_TO_IOM_RST_2")
	)
	(segment
		(start 132.183632 -23.192232)
		(end 137.739374 -23.192232)
		(width 0.127)
		(layer "F.Cu")
		(net "PCIE_COMP_TO_IOM_RST_2")
	)
	(segment
		(start 176.47539 -116.33581)
		(end 176.22901 -116.33581)
		(width 0.127)
		(layer "F.Cu")
		(net "PCIE_COMP_TO_IOM_RST_2")
	)
	(segment
		(start 142.004542 -27.4574)
		(end 142.004542 -38.495478)
		(width 0.127)
		(layer "F.Cu")
		(net "PCIE_COMP_TO_IOM_RST_2")
	)
	(segment
		(start 186.629294 -119.592852)
		(end 203.926948 -119.592852)
		(width 0.127)
		(layer "F.Cu")
		(net "PCIE_COMP_TO_IOM_RST_2")
	)
	(segment
		(start 176.22901 -116.33581)
		(end 173.482 -113.5888)
		(width 0.127)
		(layer "F.Cu")
		(net "PCIE_COMP_TO_IOM_RST_2")
	)
	(segment
		(start 203.926948 -119.592852)
		(end 204.8002 -118.7196)
		(width 0.127)
		(layer "F.Cu")
		(net "PCIE_COMP_TO_IOM_RST_2")
	)
	(segment
		(start 179.34813 -115.697)
		(end 177.1142 -115.697)
		(width 0.127)
		(layer "F.Cu")
		(net "PCIE_COMP_TO_IOM_RST_2")
	)
	(segment
		(start 206.756 -118.7196)
		(end 207.39989 -119.36349)
		(width 0.127)
		(layer "F.Cu")
		(net "PCIE_COMP_TO_IOM_RST_2")
	)
	(segment
		(start 130.3782 -21.082)
		(end 130.3782 -21.3868)
		(width 0.127)
		(layer "F.Cu")
		(net "PCIE_COMP_TO_IOM_RST_2")
	)
	(segment
		(start 207.39989 -119.36349)
		(end 207.39989 -127.324866)
		(width 0.127)
		(layer "F.Cu")
		(net "PCIE_COMP_TO_IOM_RST_2")
	)
	(segment
		(start 130.3782 -21.3868)
		(end 132.183632 -23.192232)
		(width 0.127)
		(layer "F.Cu")
		(net "PCIE_COMP_TO_IOM_RST_2")
	)
	(segment
		(start 204.8002 -118.7196)
		(end 206.756 -118.7196)
		(width 0.127)
		(layer "F.Cu")
		(net "PCIE_COMP_TO_IOM_RST_2")
	)
	(via
		(at 130.3782 -21.082)
		(size 0.508)
		(drill 0.254)
		(layers "F.Cu" "B.Cu")
		(net "PCIE_COMP_TO_IOM_RST_2")
	)
	(via
		(at 186.629294 -119.592852)
		(size 0.6604)
		(drill 0.3302)
		(layers "F.Cu" "B.Cu")
		(net "PCIE_COMP_TO_IOM_RST_2")
	)
	(via
		(at 173.482 -113.5888)
		(size 0.508)
		(drill 0.254)
		(layers "F.Cu" "B.Cu")
		(net "PCIE_COMP_TO_IOM_RST_2")
	)
	(segment
		(start 143.657066 -18.39468)
		(end 132.912612 -18.39468)
		(width 0.127)
		(layer "In5.Cu")
		(net "PCIE_COMP_TO_IOM_RST_2")
	)
	(segment
		(start 130.3782 -20.929092)
		(end 130.3782 -21.082)
		(width 0.127)
		(layer "In5.Cu")
		(net "PCIE_COMP_TO_IOM_RST_2")
	)
	(segment
		(start 173.068488 -39.68115)
		(end 152.033986 -18.646648)
		(width 0.127)
		(layer "In5.Cu")
		(net "PCIE_COMP_TO_IOM_RST_2")
	)
	(segment
		(start 173.482 -95.840042)
		(end 173.068488 -95.42653)
		(width 0.127)
		(layer "In5.Cu")
		(net "PCIE_COMP_TO_IOM_RST_2")
	)
	(segment
		(start 152.033986 -17.578324)
		(end 151.038306 -16.582644)
		(width 0.127)
		(layer "In5.Cu")
		(net "PCIE_COMP_TO_IOM_RST_2")
	)
	(segment
		(start 145.469102 -16.582644)
		(end 143.657066 -18.39468)
		(width 0.127)
		(layer "In5.Cu")
		(net "PCIE_COMP_TO_IOM_RST_2")
	)
	(segment
		(start 152.033986 -18.646648)
		(end 152.033986 -17.578324)
		(width 0.127)
		(layer "In5.Cu")
		(net "PCIE_COMP_TO_IOM_RST_2")
	)
	(segment
		(start 173.482 -113.5888)
		(end 173.482 -95.840042)
		(width 0.127)
		(layer "In5.Cu")
		(net "PCIE_COMP_TO_IOM_RST_2")
	)
	(segment
		(start 173.068488 -95.42653)
		(end 173.068488 -39.68115)
		(width 0.127)
		(layer "In5.Cu")
		(net "PCIE_COMP_TO_IOM_RST_2")
	)
	(segment
		(start 132.912612 -18.39468)
		(end 130.3782 -20.929092)
		(width 0.127)
		(layer "In5.Cu")
		(net "PCIE_COMP_TO_IOM_RST_2")
	)
	(segment
		(start 151.038306 -16.582644)
		(end 145.469102 -16.582644)
		(width 0.127)
		(layer "In5.Cu")
		(net "PCIE_COMP_TO_IOM_RST_2")
	)
	(segment
		(start 76.670154 -67.601084)
		(end 76.898754 -67.601084)
		(width 0.14605)
		(layer "F.Cu")
		(net "PCIE_COMP_TO_IOM_CLK_4_DP")
	)
	(segment
		(start 75.475084 -67.350132)
		(end 76.419202 -67.350132)
		(width 0.14605)
		(layer "F.Cu")
		(net "PCIE_COMP_TO_IOM_CLK_4_DP")
	)
	(segment
		(start 76.419202 -67.350132)
		(end 76.670154 -67.601084)
		(width 0.14605)
		(layer "F.Cu")
		(net "PCIE_COMP_TO_IOM_CLK_4_DP")
	)
	(arc
		(start 76.898754 -67.601084)
		(mid 77.168894 -67.522748)
		(end 77.355192 -67.312032)
		(width 0.14605)
		(layer "F.Cu")
		(net "PCIE_COMP_TO_IOM_CLK_4_DP")
	)
	(segment
		(start 87.415878 -61.43117)
		(end 87.235284 -61.548772)
		(width 0.14605)
		(layer "B.Cu")
		(net "PCIE_COMP_TO_IOM_CLK_4_DP")
	)
	(segment
		(start 109.59211 -22.927818)
		(end 109.43971 -22.775418)
		(width 0.14605)
		(layer "B.Cu")
		(net "PCIE_COMP_TO_IOM_CLK_4_DP")
	)
	(segment
		(start 89.038938 -36.416234)
		(end 88.947752 -36.844732)
		(width 0.14605)
		(layer "B.Cu")
		(net "PCIE_COMP_TO_IOM_CLK_4_DP")
	)
	(segment
		(start 89.530174 -34.10585)
		(end 89.439242 -34.534094)
		(width 0.14605)
		(layer "B.Cu")
		(net "PCIE_COMP_TO_IOM_CLK_4_DP")
	)
	(segment
		(start 101.391212 -22.775418)
		(end 101.023674 -23.013924)
		(width 0.14605)
		(layer "B.Cu")
		(net "PCIE_COMP_TO_IOM_CLK_4_DP")
	)
	(segment
		(start 100.033074 -23.657306)
		(end 99.98837 -23.868126)
		(width 0.14605)
		(layer "B.Cu")
		(net "PCIE_COMP_TO_IOM_CLK_4_DP")
	)
	(segment
		(start 119.863616 -43.344592)
		(end 120.3706 -43.344592)
		(width 0.14605)
		(layer "B.Cu")
		(net "PCIE_COMP_TO_IOM_CLK_4_DP")
	)
	(segment
		(start 99.98837 -23.868126)
		(end 99.620832 -24.106886)
		(width 0.14605)
		(layer "B.Cu")
		(net "PCIE_COMP_TO_IOM_CLK_4_DP")
	)
	(segment
		(start 97.639632 -25.393396)
		(end 97.428812 -25.348438)
		(width 0.14605)
		(layer "B.Cu")
		(net "PCIE_COMP_TO_IOM_CLK_4_DP")
	)
	(segment
		(start 88.149684 -57.964832)
		(end 87.96909 -58.082434)
		(width 0.14605)
		(layer "B.Cu")
		(net "PCIE_COMP_TO_IOM_CLK_4_DP")
	)
	(segment
		(start 111.80191 -22.775418)
		(end 111.36376 -22.775418)
		(width 0.14605)
		(layer "B.Cu")
		(net "PCIE_COMP_TO_IOM_CLK_4_DP")
	)
	(segment
		(start 111.36376 -22.775418)
		(end 111.21136 -22.927818)
		(width 0.14605)
		(layer "B.Cu")
		(net "PCIE_COMP_TO_IOM_CLK_4_DP")
	)
	(segment
		(start 87.63381 -59.666632)
		(end 87.751158 -59.847226)
		(width 0.14605)
		(layer "B.Cu")
		(net "PCIE_COMP_TO_IOM_CLK_4_DP")
	)
	(segment
		(start 89.284556 -35.261042)
		(end 89.19337 -35.68954)
		(width 0.14605)
		(layer "B.Cu")
		(net "PCIE_COMP_TO_IOM_CLK_4_DP")
	)
	(segment
		(start 88.702134 -37.999924)
		(end 88.819482 -38.180772)
		(width 0.14605)
		(layer "B.Cu")
		(net "PCIE_COMP_TO_IOM_CLK_4_DP")
	)
	(segment
		(start 119.70004 -42.800016)
		(end 119.70004 -43.181016)
		(width 0.14605)
		(layer "B.Cu")
		(net "PCIE_COMP_TO_IOM_CLK_4_DP")
	)
	(segment
		(start 96.736916 -25.797764)
		(end 94.483682 -29.266388)
		(width 0.14605)
		(layer "B.Cu")
		(net "PCIE_COMP_TO_IOM_CLK_4_DP")
	)
	(segment
		(start 88.973914 -37.454078)
		(end 88.79332 -37.571426)
		(width 0.14605)
		(layer "B.Cu")
		(net "PCIE_COMP_TO_IOM_CLK_4_DP")
	)
	(segment
		(start 108.41101 -22.927818)
		(end 108.25861 -22.775418)
		(width 0.14605)
		(layer "B.Cu")
		(net "PCIE_COMP_TO_IOM_CLK_4_DP")
	)
	(segment
		(start 76.92009 -67.601084)
		(end 77.06614 -67.601084)
		(width 0.14605)
		(layer "B.Cu")
		(net "PCIE_COMP_TO_IOM_CLK_4_DP")
	)
	(segment
		(start 110.77321 -22.927818)
		(end 110.62081 -22.775418)
		(width 0.14605)
		(layer "B.Cu")
		(net "PCIE_COMP_TO_IOM_CLK_4_DP")
	)
	(segment
		(start 88.240616 -57.536334)
		(end 88.149684 -57.964832)
		(width 0.14605)
		(layer "B.Cu")
		(net "PCIE_COMP_TO_IOM_CLK_4_DP")
	)
	(segment
		(start 87.878412 -58.511186)
		(end 87.99576 -58.69178)
		(width 0.14605)
		(layer "B.Cu")
		(net "PCIE_COMP_TO_IOM_CLK_4_DP")
	)
	(segment
		(start 89.556336 -34.715196)
		(end 89.46515 -35.143694)
		(width 0.14605)
		(layer "B.Cu")
		(net "PCIE_COMP_TO_IOM_CLK_4_DP")
	)
	(segment
		(start 89.310718 -35.870388)
		(end 89.219532 -36.298886)
		(width 0.14605)
		(layer "B.Cu")
		(net "PCIE_COMP_TO_IOM_CLK_4_DP")
	)
	(segment
		(start 88.216486 -56.91378)
		(end 88.123014 -57.355486)
		(width 0.14605)
		(layer "B.Cu")
		(net "PCIE_COMP_TO_IOM_CLK_4_DP")
	)
	(segment
		(start 76.730352 -67.411346)
		(end 76.92009 -67.601084)
		(width 0.14605)
		(layer "B.Cu")
		(net "PCIE_COMP_TO_IOM_CLK_4_DP")
	)
	(segment
		(start 88.79332 -37.571426)
		(end 88.702134 -37.999924)
		(width 0.14605)
		(layer "B.Cu")
		(net "PCIE_COMP_TO_IOM_CLK_4_DP")
	)
	(segment
		(start 120.71985 -42.995342)
		(end 120.71985 -29.110432)
		(width 0.14605)
		(layer "B.Cu")
		(net "PCIE_COMP_TO_IOM_CLK_4_DP")
	)
	(segment
		(start 99.042474 -24.300688)
		(end 98.99777 -24.511254)
		(width 0.14605)
		(layer "B.Cu")
		(net "PCIE_COMP_TO_IOM_CLK_4_DP")
	)
	(segment
		(start 112.39246 -22.927818)
		(end 111.95431 -22.927818)
		(width 0.14605)
		(layer "B.Cu")
		(net "PCIE_COMP_TO_IOM_CLK_4_DP")
	)
	(segment
		(start 87.389208 -60.822078)
		(end 87.506556 -61.002672)
		(width 0.14605)
		(layer "B.Cu")
		(net "PCIE_COMP_TO_IOM_CLK_4_DP")
	)
	(segment
		(start 87.479886 -60.393326)
		(end 87.389208 -60.822078)
		(width 0.14605)
		(layer "B.Cu")
		(net "PCIE_COMP_TO_IOM_CLK_4_DP")
	)
	(segment
		(start 88.947752 -36.844732)
		(end 89.0651 -37.02558)
		(width 0.14605)
		(layer "B.Cu")
		(net "PCIE_COMP_TO_IOM_CLK_4_DP")
	)
	(segment
		(start 94.483682 -29.266388)
		(end 91.354148 -31.298134)
		(width 0.14605)
		(layer "B.Cu")
		(net "PCIE_COMP_TO_IOM_CLK_4_DP")
	)
	(segment
		(start 78.661768 -66.35115)
		(end 78.122018 -65.8114)
		(width 0.14605)
		(layer "B.Cu")
		(net "PCIE_COMP_TO_IOM_CLK_4_DP")
	)
	(segment
		(start 87.99576 -58.69178)
		(end 87.905082 -59.120278)
		(width 0.14605)
		(layer "B.Cu")
		(net "PCIE_COMP_TO_IOM_CLK_4_DP")
	)
	(segment
		(start 89.19337 -35.68954)
		(end 89.310718 -35.870388)
		(width 0.14605)
		(layer "B.Cu")
		(net "PCIE_COMP_TO_IOM_CLK_4_DP")
	)
	(segment
		(start 78.122018 -65.8114)
		(end 77.1144 -65.8114)
		(width 0.14605)
		(layer "B.Cu")
		(net "PCIE_COMP_TO_IOM_CLK_4_DP")
	)
	(segment
		(start 98.99777 -24.511254)
		(end 98.630232 -24.750014)
		(width 0.14605)
		(layer "B.Cu")
		(net "PCIE_COMP_TO_IOM_CLK_4_DP")
	)
	(segment
		(start 120.71985 -29.110432)
		(end 117.650768 -26.04135)
		(width 0.14605)
		(layer "B.Cu")
		(net "PCIE_COMP_TO_IOM_CLK_4_DP")
	)
	(segment
		(start 91.354148 -31.298134)
		(end 89.530174 -34.10585)
		(width 0.14605)
		(layer "B.Cu")
		(net "PCIE_COMP_TO_IOM_CLK_4_DP")
	)
	(segment
		(start 98.051874 -24.943816)
		(end 98.00717 -25.154636)
		(width 0.14605)
		(layer "B.Cu")
		(net "PCIE_COMP_TO_IOM_CLK_4_DP")
	)
	(segment
		(start 84.965032 -66.35115)
		(end 78.661768 -66.35115)
		(width 0.14605)
		(layer "B.Cu")
		(net "PCIE_COMP_TO_IOM_CLK_4_DP")
	)
	(segment
		(start 98.419412 -24.70531)
		(end 98.051874 -24.943816)
		(width 0.14605)
		(layer "B.Cu")
		(net "PCIE_COMP_TO_IOM_CLK_4_DP")
	)
	(segment
		(start 98.630232 -24.750014)
		(end 98.419412 -24.70531)
		(width 0.14605)
		(layer "B.Cu")
		(net "PCIE_COMP_TO_IOM_CLK_4_DP")
	)
	(segment
		(start 110.03026 -22.927818)
		(end 109.59211 -22.927818)
		(width 0.14605)
		(layer "B.Cu")
		(net "PCIE_COMP_TO_IOM_CLK_4_DP")
	)
	(segment
		(start 88.728296 -38.60927)
		(end 88.547702 -38.726618)
		(width 0.14605)
		(layer "B.Cu")
		(net "PCIE_COMP_TO_IOM_CLK_4_DP")
	)
	(segment
		(start 87.905082 -59.120278)
		(end 87.724488 -59.23788)
		(width 0.14605)
		(layer "B.Cu")
		(net "PCIE_COMP_TO_IOM_CLK_4_DP")
	)
	(segment
		(start 88.547702 -38.726618)
		(end 87.219282 -44.972732)
		(width 0.14605)
		(layer "B.Cu")
		(net "PCIE_COMP_TO_IOM_CLK_4_DP")
	)
	(segment
		(start 86.555072 -64.761364)
		(end 84.965032 -66.35115)
		(width 0.14605)
		(layer "B.Cu")
		(net "PCIE_COMP_TO_IOM_CLK_4_DP")
	)
	(segment
		(start 88.819482 -38.180772)
		(end 88.728296 -38.60927)
		(width 0.14605)
		(layer "B.Cu")
		(net "PCIE_COMP_TO_IOM_CLK_4_DP")
	)
	(segment
		(start 111.21136 -22.927818)
		(end 110.77321 -22.927818)
		(width 0.14605)
		(layer "B.Cu")
		(net "PCIE_COMP_TO_IOM_CLK_4_DP")
	)
	(segment
		(start 89.438988 -34.534348)
		(end 89.556336 -34.715196)
		(width 0.14605)
		(layer "B.Cu")
		(net "PCIE_COMP_TO_IOM_CLK_4_DP")
	)
	(segment
		(start 87.235284 -61.548772)
		(end 86.555072 -64.761364)
		(width 0.14605)
		(layer "B.Cu")
		(net "PCIE_COMP_TO_IOM_CLK_4_DP")
	)
	(segment
		(start 108.25861 -22.775418)
		(end 101.391212 -22.775418)
		(width 0.14605)
		(layer "B.Cu")
		(net "PCIE_COMP_TO_IOM_CLK_4_DP")
	)
	(segment
		(start 109.43971 -22.775418)
		(end 109.00156 -22.775418)
		(width 0.14605)
		(layer "B.Cu")
		(net "PCIE_COMP_TO_IOM_CLK_4_DP")
	)
	(segment
		(start 101.023674 -23.013924)
		(end 100.97897 -23.224744)
		(width 0.14605)
		(layer "B.Cu")
		(net "PCIE_COMP_TO_IOM_CLK_4_DP")
	)
	(segment
		(start 87.219282 -44.972732)
		(end 88.099392 -49.110138)
		(width 0.14605)
		(layer "B.Cu")
		(net "PCIE_COMP_TO_IOM_CLK_4_DP")
	)
	(segment
		(start 100.400612 -23.4188)
		(end 100.033074 -23.657306)
		(width 0.14605)
		(layer "B.Cu")
		(net "PCIE_COMP_TO_IOM_CLK_4_DP")
	)
	(segment
		(start 77.1144 -65.8114)
		(end 76.730352 -66.195448)
		(width 0.14605)
		(layer "B.Cu")
		(net "PCIE_COMP_TO_IOM_CLK_4_DP")
	)
	(segment
		(start 110.18266 -22.775418)
		(end 110.03026 -22.927818)
		(width 0.14605)
		(layer "B.Cu")
		(net "PCIE_COMP_TO_IOM_CLK_4_DP")
	)
	(segment
		(start 108.84916 -22.927818)
		(end 108.41101 -22.927818)
		(width 0.14605)
		(layer "B.Cu")
		(net "PCIE_COMP_TO_IOM_CLK_4_DP")
	)
	(segment
		(start 112.54486 -22.775418)
		(end 112.39246 -22.927818)
		(width 0.14605)
		(layer "B.Cu")
		(net "PCIE_COMP_TO_IOM_CLK_4_DP")
	)
	(segment
		(start 88.123014 -57.355486)
		(end 88.240616 -57.536334)
		(width 0.14605)
		(layer "B.Cu")
		(net "PCIE_COMP_TO_IOM_CLK_4_DP")
	)
	(segment
		(start 76.730352 -66.195448)
		(end 76.730352 -67.411346)
		(width 0.14605)
		(layer "B.Cu")
		(net "PCIE_COMP_TO_IOM_CLK_4_DP")
	)
	(segment
		(start 87.66048 -60.275724)
		(end 87.479886 -60.393326)
		(width 0.14605)
		(layer "B.Cu")
		(net "PCIE_COMP_TO_IOM_CLK_4_DP")
	)
	(segment
		(start 89.46515 -35.143694)
		(end 89.284556 -35.261042)
		(width 0.14605)
		(layer "B.Cu")
		(net "PCIE_COMP_TO_IOM_CLK_4_DP")
	)
	(segment
		(start 87.751158 -59.847226)
		(end 87.66048 -60.275724)
		(width 0.14605)
		(layer "B.Cu")
		(net "PCIE_COMP_TO_IOM_CLK_4_DP")
	)
	(segment
		(start 113.368836 -22.775418)
		(end 112.54486 -22.775418)
		(width 0.14605)
		(layer "B.Cu")
		(net "PCIE_COMP_TO_IOM_CLK_4_DP")
	)
	(segment
		(start 88.099392 -49.110138)
		(end 87.328502 -52.734972)
		(width 0.14605)
		(layer "B.Cu")
		(net "PCIE_COMP_TO_IOM_CLK_4_DP")
	)
	(segment
		(start 117.650768 -26.04135)
		(end 116.634768 -26.04135)
		(width 0.14605)
		(layer "B.Cu")
		(net "PCIE_COMP_TO_IOM_CLK_4_DP")
	)
	(segment
		(start 87.328502 -52.734972)
		(end 88.216486 -56.91378)
		(width 0.14605)
		(layer "B.Cu")
		(net "PCIE_COMP_TO_IOM_CLK_4_DP")
	)
	(segment
		(start 99.410012 -24.061928)
		(end 99.042474 -24.300688)
		(width 0.14605)
		(layer "B.Cu")
		(net "PCIE_COMP_TO_IOM_CLK_4_DP")
	)
	(segment
		(start 99.620832 -24.106886)
		(end 99.410012 -24.061928)
		(width 0.14605)
		(layer "B.Cu")
		(net "PCIE_COMP_TO_IOM_CLK_4_DP")
	)
	(segment
		(start 98.00717 -25.154636)
		(end 97.639632 -25.393396)
		(width 0.14605)
		(layer "B.Cu")
		(net "PCIE_COMP_TO_IOM_CLK_4_DP")
	)
	(segment
		(start 109.00156 -22.775418)
		(end 108.84916 -22.927818)
		(width 0.14605)
		(layer "B.Cu")
		(net "PCIE_COMP_TO_IOM_CLK_4_DP")
	)
	(segment
		(start 89.0651 -37.02558)
		(end 88.973914 -37.454078)
		(width 0.14605)
		(layer "B.Cu")
		(net "PCIE_COMP_TO_IOM_CLK_4_DP")
	)
	(segment
		(start 89.439242 -34.534094)
		(end 89.438988 -34.534348)
		(width 0.14605)
		(layer "B.Cu")
		(net "PCIE_COMP_TO_IOM_CLK_4_DP")
	)
	(segment
		(start 100.97897 -23.224744)
		(end 100.611432 -23.463504)
		(width 0.14605)
		(layer "B.Cu")
		(net "PCIE_COMP_TO_IOM_CLK_4_DP")
	)
	(segment
		(start 116.634768 -26.04135)
		(end 113.368836 -22.775418)
		(width 0.14605)
		(layer "B.Cu")
		(net "PCIE_COMP_TO_IOM_CLK_4_DP")
	)
	(segment
		(start 100.611432 -23.463504)
		(end 100.400612 -23.4188)
		(width 0.14605)
		(layer "B.Cu")
		(net "PCIE_COMP_TO_IOM_CLK_4_DP")
	)
	(segment
		(start 87.96909 -58.082434)
		(end 87.878412 -58.511186)
		(width 0.14605)
		(layer "B.Cu")
		(net "PCIE_COMP_TO_IOM_CLK_4_DP")
	)
	(segment
		(start 111.95431 -22.927818)
		(end 111.80191 -22.775418)
		(width 0.14605)
		(layer "B.Cu")
		(net "PCIE_COMP_TO_IOM_CLK_4_DP")
	)
	(segment
		(start 87.724488 -59.23788)
		(end 87.63381 -59.666632)
		(width 0.14605)
		(layer "B.Cu")
		(net "PCIE_COMP_TO_IOM_CLK_4_DP")
	)
	(segment
		(start 89.219532 -36.298886)
		(end 89.038938 -36.416234)
		(width 0.14605)
		(layer "B.Cu")
		(net "PCIE_COMP_TO_IOM_CLK_4_DP")
	)
	(segment
		(start 87.506556 -61.002672)
		(end 87.415878 -61.43117)
		(width 0.14605)
		(layer "B.Cu")
		(net "PCIE_COMP_TO_IOM_CLK_4_DP")
	)
	(segment
		(start 97.428812 -25.348438)
		(end 96.736916 -25.797764)
		(width 0.14605)
		(layer "B.Cu")
		(net "PCIE_COMP_TO_IOM_CLK_4_DP")
	)
	(segment
		(start 77.06614 -67.601084)
		(end 77.355192 -67.312032)
		(width 0.14605)
		(layer "B.Cu")
		(net "PCIE_COMP_TO_IOM_CLK_4_DP")
	)
	(segment
		(start 110.62081 -22.775418)
		(end 110.18266 -22.775418)
		(width 0.14605)
		(layer "B.Cu")
		(net "PCIE_COMP_TO_IOM_CLK_4_DP")
	)
	(arc
		(start 119.70004 -43.181016)
		(mid 119.74795 -43.296682)
		(end 119.863616 -43.344592)
		(width 0.14605)
		(layer "B.Cu")
		(net "PCIE_COMP_TO_IOM_CLK_4_DP")
	)
	(arc
		(start 120.3706 -43.344592)
		(mid 120.617557 -43.242299)
		(end 120.71985 -42.995342)
		(width 0.14605)
		(layer "B.Cu")
		(net "PCIE_COMP_TO_IOM_CLK_4_DP")
	)
	(segment
		(start 76.646532 -67.912234)
		(end 76.408788 -68.149978)
		(width 0.14605)
		(layer "F.Cu")
		(net "PCIE_COMP_TO_IOM_CLK_4_DN")
	)
	(segment
		(start 76.898754 -67.912234)
		(end 76.646532 -67.912234)
		(width 0.14605)
		(layer "F.Cu")
		(net "PCIE_COMP_TO_IOM_CLK_4_DN")
	)
	(segment
		(start 76.408788 -68.149978)
		(end 75.475084 -68.149978)
		(width 0.14605)
		(layer "F.Cu")
		(net "PCIE_COMP_TO_IOM_CLK_4_DN")
	)
	(arc
		(start 77.355192 -68.201032)
		(mid 77.168802 -67.990541)
		(end 76.898754 -67.912234)
		(width 0.14605)
		(layer "F.Cu")
		(net "PCIE_COMP_TO_IOM_CLK_4_DN")
	)
	(segment
		(start 76.791058 -67.912234)
		(end 77.066394 -67.912234)
		(width 0.14605)
		(layer "B.Cu")
		(net "PCIE_COMP_TO_IOM_CLK_4_DN")
	)
	(segment
		(start 113.497868 -22.464268)
		(end 101.29901 -22.464268)
		(width 0.14605)
		(layer "B.Cu")
		(net "PCIE_COMP_TO_IOM_CLK_4_DN")
	)
	(segment
		(start 96.511872 -25.57272)
		(end 94.258638 -29.041344)
		(width 0.14605)
		(layer "B.Cu")
		(net "PCIE_COMP_TO_IOM_CLK_4_DN")
	)
	(segment
		(start 121.031 -42.995342)
		(end 121.031 -28.9814)
		(width 0.14605)
		(layer "B.Cu")
		(net "PCIE_COMP_TO_IOM_CLK_4_DN")
	)
	(segment
		(start 76.985368 -65.50025)
		(end 76.419202 -66.066416)
		(width 0.14605)
		(layer "B.Cu")
		(net "PCIE_COMP_TO_IOM_CLK_4_DN")
	)
	(segment
		(start 94.258638 -29.041344)
		(end 91.129104 -31.07309)
		(width 0.14605)
		(layer "B.Cu")
		(net "PCIE_COMP_TO_IOM_CLK_4_DN")
	)
	(segment
		(start 117.7798 -25.7302)
		(end 116.7638 -25.7302)
		(width 0.14605)
		(layer "B.Cu")
		(net "PCIE_COMP_TO_IOM_CLK_4_DN")
	)
	(segment
		(start 119.863362 -43.655742)
		(end 120.3706 -43.655742)
		(width 0.14605)
		(layer "B.Cu")
		(net "PCIE_COMP_TO_IOM_CLK_4_DN")
	)
	(segment
		(start 84.836 -66.04)
		(end 78.7908 -66.04)
		(width 0.14605)
		(layer "B.Cu")
		(net "PCIE_COMP_TO_IOM_CLK_4_DN")
	)
	(segment
		(start 86.90102 -44.972732)
		(end 87.78113 -49.110138)
		(width 0.14605)
		(layer "B.Cu")
		(net "PCIE_COMP_TO_IOM_CLK_4_DN")
	)
	(segment
		(start 116.7638 -25.7302)
		(end 113.497868 -22.464268)
		(width 0.14605)
		(layer "B.Cu")
		(net "PCIE_COMP_TO_IOM_CLK_4_DN")
	)
	(segment
		(start 77.066394 -67.912234)
		(end 77.355192 -68.201032)
		(width 0.14605)
		(layer "B.Cu")
		(net "PCIE_COMP_TO_IOM_CLK_4_DN")
	)
	(segment
		(start 87.78113 -49.110138)
		(end 87.01024 -52.734972)
		(width 0.14605)
		(layer "B.Cu")
		(net "PCIE_COMP_TO_IOM_CLK_4_DN")
	)
	(segment
		(start 89.23782 -33.984692)
		(end 88.243156 -38.662102)
		(width 0.14605)
		(layer "B.Cu")
		(net "PCIE_COMP_TO_IOM_CLK_4_DN")
	)
	(segment
		(start 78.7908 -66.04)
		(end 78.25105 -65.50025)
		(width 0.14605)
		(layer "B.Cu")
		(net "PCIE_COMP_TO_IOM_CLK_4_DN")
	)
	(segment
		(start 88.243156 -38.662102)
		(end 86.90102 -44.972732)
		(width 0.14605)
		(layer "B.Cu")
		(net "PCIE_COMP_TO_IOM_CLK_4_DN")
	)
	(segment
		(start 91.129104 -31.07309)
		(end 89.23782 -33.984692)
		(width 0.14605)
		(layer "B.Cu")
		(net "PCIE_COMP_TO_IOM_CLK_4_DN")
	)
	(segment
		(start 76.419202 -67.540378)
		(end 76.791058 -67.912234)
		(width 0.14605)
		(layer "B.Cu")
		(net "PCIE_COMP_TO_IOM_CLK_4_DN")
	)
	(segment
		(start 86.269576 -64.606424)
		(end 84.836 -66.04)
		(width 0.14605)
		(layer "B.Cu")
		(net "PCIE_COMP_TO_IOM_CLK_4_DN")
	)
	(segment
		(start 76.419202 -66.066416)
		(end 76.419202 -67.540378)
		(width 0.14605)
		(layer "B.Cu")
		(net "PCIE_COMP_TO_IOM_CLK_4_DN")
	)
	(segment
		(start 101.29901 -22.464268)
		(end 96.511872 -25.57272)
		(width 0.14605)
		(layer "B.Cu")
		(net "PCIE_COMP_TO_IOM_CLK_4_DN")
	)
	(segment
		(start 121.031 -28.9814)
		(end 117.7798 -25.7302)
		(width 0.14605)
		(layer "B.Cu")
		(net "PCIE_COMP_TO_IOM_CLK_4_DN")
	)
	(segment
		(start 78.25105 -65.50025)
		(end 76.985368 -65.50025)
		(width 0.14605)
		(layer "B.Cu")
		(net "PCIE_COMP_TO_IOM_CLK_4_DN")
	)
	(segment
		(start 119.70004 -44.200064)
		(end 119.70004 -43.819064)
		(width 0.14605)
		(layer "B.Cu")
		(net "PCIE_COMP_TO_IOM_CLK_4_DN")
	)
	(segment
		(start 87.01024 -52.734972)
		(end 87.898224 -56.91378)
		(width 0.14605)
		(layer "B.Cu")
		(net "PCIE_COMP_TO_IOM_CLK_4_DN")
	)
	(segment
		(start 87.898224 -56.91378)
		(end 86.269576 -64.606424)
		(width 0.14605)
		(layer "B.Cu")
		(net "PCIE_COMP_TO_IOM_CLK_4_DN")
	)
	(arc
		(start 120.3706 -43.655742)
		(mid 120.837573 -43.462315)
		(end 121.031 -42.995342)
		(width 0.14605)
		(layer "B.Cu")
		(net "PCIE_COMP_TO_IOM_CLK_4_DN")
	)
	(arc
		(start 119.70004 -43.819064)
		(mid 119.747876 -43.703578)
		(end 119.863362 -43.655742)
		(width 0.14605)
		(layer "B.Cu")
		(net "PCIE_COMP_TO_IOM_CLK_4_DN")
	)
	(segment
		(start 130.200908 -27.476196)
		(end 129.359406 -27.476196)
		(width 0.14605)
		(layer "F.Cu")
		(net "PCIE_COMP_TO_IOM_CLK_3_DP")
	)
	(segment
		(start 183.55564 -133.886956)
		(end 183.649874 -133.98119)
		(width 0.14605)
		(layer "F.Cu")
		(net "PCIE_COMP_TO_IOM_CLK_3_DP")
	)
	(segment
		(start 134.100062 -42.800016)
		(end 134.100062 -43.181016)
		(width 0.14605)
		(layer "F.Cu")
		(net "PCIE_COMP_TO_IOM_CLK_3_DP")
	)
	(segment
		(start 129.359406 -27.476196)
		(end 128.846072 -26.962862)
		(width 0.14605)
		(layer "F.Cu")
		(net "PCIE_COMP_TO_IOM_CLK_3_DP")
	)
	(segment
		(start 134.71652 -30.543754)
		(end 134.335774 -30.162754)
		(width 0.14605)
		(layer "F.Cu")
		(net "PCIE_COMP_TO_IOM_CLK_3_DP")
	)
	(segment
		(start 134.843774 -30.671008)
		(end 134.71652 -30.543754)
		(width 0.14605)
		(layer "F.Cu")
		(net "PCIE_COMP_TO_IOM_CLK_3_DP")
	)
	(segment
		(start 128.51511 -26.211276)
		(end 128.467866 -26.211276)
		(width 0.14605)
		(layer "F.Cu")
		(net "PCIE_COMP_TO_IOM_CLK_3_DP")
	)
	(segment
		(start 183.615838 -133.136132)
		(end 183.615838 -133.569202)
		(width 0.14605)
		(layer "F.Cu")
		(net "PCIE_COMP_TO_IOM_CLK_3_DP")
	)
	(segment
		(start 183.616092 -133.135878)
		(end 183.615838 -133.136132)
		(width 0.14605)
		(layer "F.Cu")
		(net "PCIE_COMP_TO_IOM_CLK_3_DP")
	)
	(segment
		(start 183.615838 -133.569202)
		(end 183.55564 -133.6294)
		(width 0.14605)
		(layer "F.Cu")
		(net "PCIE_COMP_TO_IOM_CLK_3_DP")
	)
	(segment
		(start 128.846072 -26.962862)
		(end 128.846072 -26.542238)
		(width 0.14605)
		(layer "F.Cu")
		(net "PCIE_COMP_TO_IOM_CLK_3_DP")
	)
	(segment
		(start 183.55564 -133.6294)
		(end 183.55564 -133.886956)
		(width 0.14605)
		(layer "F.Cu")
		(net "PCIE_COMP_TO_IOM_CLK_3_DP")
	)
	(segment
		(start 183.649874 -133.98119)
		(end 183.649874 -134.875016)
		(width 0.14605)
		(layer "F.Cu")
		(net "PCIE_COMP_TO_IOM_CLK_3_DP")
	)
	(segment
		(start 134.844028 -43.066716)
		(end 134.844028 -30.671008)
		(width 0.14605)
		(layer "F.Cu")
		(net "PCIE_COMP_TO_IOM_CLK_3_DP")
	)
	(segment
		(start 134.263638 -43.344592)
		(end 134.566152 -43.344592)
		(width 0.14605)
		(layer "F.Cu")
		(net "PCIE_COMP_TO_IOM_CLK_3_DP")
	)
	(segment
		(start 134.844028 -30.671008)
		(end 134.843774 -30.671008)
		(width 0.14605)
		(layer "F.Cu")
		(net "PCIE_COMP_TO_IOM_CLK_3_DP")
	)
	(segment
		(start 183.905144 -132.973826)
		(end 183.778144 -132.973826)
		(width 0.14605)
		(layer "F.Cu")
		(net "PCIE_COMP_TO_IOM_CLK_3_DP")
	)
	(segment
		(start 134.335774 -30.162754)
		(end 130.200908 -27.476196)
		(width 0.14605)
		(layer "F.Cu")
		(net "PCIE_COMP_TO_IOM_CLK_3_DP")
	)
	(via
		(at 128.467866 -26.211276)
		(size 0.508)
		(drill 0.254)
		(layers "F.Cu" "B.Cu")
		(net "PCIE_COMP_TO_IOM_CLK_3_DP")
	)
	(arc
		(start 134.566152 -43.344592)
		(mid 134.76264 -43.263204)
		(end 134.844028 -43.066716)
		(width 0.14605)
		(layer "F.Cu")
		(net "PCIE_COMP_TO_IOM_CLK_3_DP")
	)
	(arc
		(start 183.778144 -132.973826)
		(mid 183.663556 -133.02129)
		(end 183.616092 -133.135878)
		(width 0.14605)
		(layer "F.Cu")
		(net "PCIE_COMP_TO_IOM_CLK_3_DP")
	)
	(arc
		(start 134.100062 -43.181016)
		(mid 134.147972 -43.296682)
		(end 134.263638 -43.344592)
		(width 0.14605)
		(layer "F.Cu")
		(net "PCIE_COMP_TO_IOM_CLK_3_DP")
	)
	(arc
		(start 128.846072 -26.542238)
		(mid 128.749135 -26.308213)
		(end 128.51511 -26.211276)
		(width 0.14605)
		(layer "F.Cu")
		(net "PCIE_COMP_TO_IOM_CLK_3_DP")
	)
	(segment
		(start 169.227754 -87.105236)
		(end 172.07992 -100.52431)
		(width 0.1397)
		(layer "In5.Cu")
		(net "PCIE_COMP_TO_IOM_CLK_3_DP")
	)
	(segment
		(start 169.513758 -124.927868)
		(end 170.059096 -127.493014)
		(width 0.1397)
		(layer "In5.Cu")
		(net "PCIE_COMP_TO_IOM_CLK_3_DP")
	)
	(segment
		(start 172.032422 -129.92481)
		(end 177.333148 -131.050538)
		(width 0.1397)
		(layer "In5.Cu")
		(net "PCIE_COMP_TO_IOM_CLK_3_DP")
	)
	(segment
		(start 177.333148 -131.050538)
		(end 179.271422 -131.462272)
		(width 0.1397)
		(layer "In5.Cu")
		(net "PCIE_COMP_TO_IOM_CLK_3_DP")
	)
	(segment
		(start 183.625998 -132.130292)
		(end 183.625998 -132.821172)
		(width 0.1397)
		(layer "In5.Cu")
		(net "PCIE_COMP_TO_IOM_CLK_3_DP")
	)
	(segment
		(start 172.07992 -100.52431)
		(end 168.463468 -117.540278)
		(width 0.1397)
		(layer "In5.Cu")
		(net "PCIE_COMP_TO_IOM_CLK_3_DP")
	)
	(segment
		(start 145.145506 -20.183348)
		(end 148.937218 -20.989544)
		(width 0.1397)
		(layer "In5.Cu")
		(net "PCIE_COMP_TO_IOM_CLK_3_DP")
	)
	(segment
		(start 136.358122 -20.176236)
		(end 145.111724 -20.176236)
		(width 0.1397)
		(layer "In5.Cu")
		(net "PCIE_COMP_TO_IOM_CLK_3_DP")
	)
	(segment
		(start 148.937218 -20.989544)
		(end 155.701492 -25.382728)
		(width 0.1397)
		(layer "In5.Cu")
		(net "PCIE_COMP_TO_IOM_CLK_3_DP")
	)
	(segment
		(start 183.778144 -132.973826)
		(end 183.905144 -132.973826)
		(width 0.1397)
		(layer "In5.Cu")
		(net "PCIE_COMP_TO_IOM_CLK_3_DP")
	)
	(segment
		(start 179.271422 -131.462272)
		(end 181.226206 -131.046982)
		(width 0.1397)
		(layer "In5.Cu")
		(net "PCIE_COMP_TO_IOM_CLK_3_DP")
	)
	(segment
		(start 170.728132 -80.04556)
		(end 169.227754 -87.105236)
		(width 0.1397)
		(layer "In5.Cu")
		(net "PCIE_COMP_TO_IOM_CLK_3_DP")
	)
	(segment
		(start 183.625998 -132.821172)
		(end 183.626252 -132.821172)
		(width 0.1397)
		(layer "In5.Cu")
		(net "PCIE_COMP_TO_IOM_CLK_3_DP")
	)
	(segment
		(start 128.83642 -25.92578)
		(end 128.83642 -25.64511)
		(width 0.1397)
		(layer "In5.Cu")
		(net "PCIE_COMP_TO_IOM_CLK_3_DP")
	)
	(segment
		(start 171.351194 -129.482342)
		(end 172.032422 -129.924556)
		(width 0.1397)
		(layer "In5.Cu")
		(net "PCIE_COMP_TO_IOM_CLK_3_DP")
	)
	(segment
		(start 160.768538 -33.184846)
		(end 170.728132 -80.04556)
		(width 0.1397)
		(layer "In5.Cu")
		(net "PCIE_COMP_TO_IOM_CLK_3_DP")
	)
	(segment
		(start 182.898034 -131.402328)
		(end 183.625998 -132.130292)
		(width 0.1397)
		(layer "In5.Cu")
		(net "PCIE_COMP_TO_IOM_CLK_3_DP")
	)
	(segment
		(start 169.773854 -123.705112)
		(end 169.513758 -124.927868)
		(width 0.1397)
		(layer "In5.Cu")
		(net "PCIE_COMP_TO_IOM_CLK_3_DP")
	)
	(segment
		(start 183.626252 -132.821172)
		(end 183.626252 -132.821934)
		(width 0.1397)
		(layer "In5.Cu")
		(net "PCIE_COMP_TO_IOM_CLK_3_DP")
	)
	(segment
		(start 129.80289 -24.433784)
		(end 136.358122 -20.176236)
		(width 0.1397)
		(layer "In5.Cu")
		(net "PCIE_COMP_TO_IOM_CLK_3_DP")
	)
	(segment
		(start 170.059096 -127.493014)
		(end 171.351194 -129.482342)
		(width 0.1397)
		(layer "In5.Cu")
		(net "PCIE_COMP_TO_IOM_CLK_3_DP")
	)
	(segment
		(start 155.701492 -25.382728)
		(end 160.768538 -33.184846)
		(width 0.1397)
		(layer "In5.Cu")
		(net "PCIE_COMP_TO_IOM_CLK_3_DP")
	)
	(segment
		(start 145.111724 -20.176236)
		(end 145.145506 -20.183348)
		(width 0.1397)
		(layer "In5.Cu")
		(net "PCIE_COMP_TO_IOM_CLK_3_DP")
	)
	(segment
		(start 168.463468 -117.540278)
		(end 169.773854 -123.705112)
		(width 0.1397)
		(layer "In5.Cu")
		(net "PCIE_COMP_TO_IOM_CLK_3_DP")
	)
	(segment
		(start 181.226206 -131.046982)
		(end 182.898034 -131.402328)
		(width 0.1397)
		(layer "In5.Cu")
		(net "PCIE_COMP_TO_IOM_CLK_3_DP")
	)
	(segment
		(start 128.467866 -26.211276)
		(end 128.550924 -26.211276)
		(width 0.1397)
		(layer "In5.Cu")
		(net "PCIE_COMP_TO_IOM_CLK_3_DP")
	)
	(segment
		(start 172.032422 -129.924556)
		(end 172.032422 -129.92481)
		(width 0.1397)
		(layer "In5.Cu")
		(net "PCIE_COMP_TO_IOM_CLK_3_DP")
	)
	(segment
		(start 129.009394 -25.22728)
		(end 129.80289 -24.433784)
		(width 0.1397)
		(layer "In5.Cu")
		(net "PCIE_COMP_TO_IOM_CLK_3_DP")
	)
	(arc
		(start 183.626252 -132.821934)
		(mid 183.67074 -132.929338)
		(end 183.778144 -132.973826)
		(width 0.1397)
		(layer "In5.Cu")
		(net "PCIE_COMP_TO_IOM_CLK_3_DP")
	)
	(arc
		(start 128.550924 -26.211276)
		(mid 128.7528 -26.127656)
		(end 128.83642 -25.92578)
		(width 0.1397)
		(layer "In5.Cu")
		(net "PCIE_COMP_TO_IOM_CLK_3_DP")
	)
	(arc
		(start 128.83642 -25.64511)
		(mid 128.881377 -25.419005)
		(end 129.009394 -25.22728)
		(width 0.1397)
		(layer "In5.Cu")
		(net "PCIE_COMP_TO_IOM_CLK_3_DP")
	)
	(segment
		(start 135.155178 -30.541976)
		(end 134.532878 -29.919422)
		(width 0.14605)
		(layer "F.Cu")
		(net "PCIE_COMP_TO_IOM_CLK_3_DN")
	)
	(segment
		(start 134.263384 -43.655742)
		(end 134.566152 -43.655742)
		(width 0.14605)
		(layer "F.Cu")
		(net "PCIE_COMP_TO_IOM_CLK_3_DN")
	)
	(segment
		(start 183.304688 -133.44017)
		(end 183.24449 -133.500368)
		(width 0.14605)
		(layer "F.Cu")
		(net "PCIE_COMP_TO_IOM_CLK_3_DN")
	)
	(segment
		(start 129.488438 -27.165046)
		(end 129.157222 -26.83383)
		(width 0.14605)
		(layer "F.Cu")
		(net "PCIE_COMP_TO_IOM_CLK_3_DN")
	)
	(segment
		(start 183.24449 -133.500368)
		(end 183.24449 -133.886956)
		(width 0.14605)
		(layer "F.Cu")
		(net "PCIE_COMP_TO_IOM_CLK_3_DN")
	)
	(segment
		(start 183.304688 -133.13537)
		(end 183.304688 -133.44017)
		(width 0.14605)
		(layer "F.Cu")
		(net "PCIE_COMP_TO_IOM_CLK_3_DN")
	)
	(segment
		(start 183.150002 -133.981444)
		(end 183.150002 -134.875016)
		(width 0.14605)
		(layer "F.Cu")
		(net "PCIE_COMP_TO_IOM_CLK_3_DN")
	)
	(segment
		(start 183.24449 -133.886956)
		(end 183.150002 -133.981444)
		(width 0.14605)
		(layer "F.Cu")
		(net "PCIE_COMP_TO_IOM_CLK_3_DN")
	)
	(segment
		(start 129.488184 -26.211276)
		(end 129.535174 -26.211276)
		(width 0.14605)
		(layer "F.Cu")
		(net "PCIE_COMP_TO_IOM_CLK_3_DN")
	)
	(segment
		(start 134.532878 -29.919422)
		(end 130.29311 -27.165046)
		(width 0.14605)
		(layer "F.Cu")
		(net "PCIE_COMP_TO_IOM_CLK_3_DN")
	)
	(segment
		(start 183.016144 -132.973826)
		(end 183.143144 -132.973826)
		(width 0.14605)
		(layer "F.Cu")
		(net "PCIE_COMP_TO_IOM_CLK_3_DN")
	)
	(segment
		(start 129.157222 -26.83383)
		(end 129.157222 -26.542238)
		(width 0.14605)
		(layer "F.Cu")
		(net "PCIE_COMP_TO_IOM_CLK_3_DN")
	)
	(segment
		(start 134.100062 -44.200064)
		(end 134.100062 -43.819064)
		(width 0.14605)
		(layer "F.Cu")
		(net "PCIE_COMP_TO_IOM_CLK_3_DN")
	)
	(segment
		(start 135.155178 -43.066716)
		(end 135.155178 -30.541976)
		(width 0.14605)
		(layer "F.Cu")
		(net "PCIE_COMP_TO_IOM_CLK_3_DN")
	)
	(segment
		(start 130.29311 -27.165046)
		(end 129.488438 -27.165046)
		(width 0.14605)
		(layer "F.Cu")
		(net "PCIE_COMP_TO_IOM_CLK_3_DN")
	)
	(via
		(at 129.535174 -26.211276)
		(size 0.508)
		(drill 0.254)
		(layers "F.Cu" "B.Cu")
		(net "PCIE_COMP_TO_IOM_CLK_3_DN")
	)
	(arc
		(start 129.157222 -26.542238)
		(mid 129.254159 -26.308213)
		(end 129.488184 -26.211276)
		(width 0.14605)
		(layer "F.Cu")
		(net "PCIE_COMP_TO_IOM_CLK_3_DN")
	)
	(arc
		(start 134.100062 -43.819064)
		(mid 134.147898 -43.703578)
		(end 134.263384 -43.655742)
		(width 0.14605)
		(layer "F.Cu")
		(net "PCIE_COMP_TO_IOM_CLK_3_DN")
	)
	(arc
		(start 183.143144 -132.973826)
		(mid 183.257373 -133.021141)
		(end 183.304688 -133.13537)
		(width 0.14605)
		(layer "F.Cu")
		(net "PCIE_COMP_TO_IOM_CLK_3_DN")
	)
	(arc
		(start 134.566152 -43.655742)
		(mid 134.982656 -43.48322)
		(end 135.155178 -43.066716)
		(width 0.14605)
		(layer "F.Cu")
		(net "PCIE_COMP_TO_IOM_CLK_3_DN")
	)
	(segment
		(start 168.125648 -117.540278)
		(end 169.436034 -123.705112)
		(width 0.1397)
		(layer "In5.Cu")
		(net "PCIE_COMP_TO_IOM_CLK_3_DN")
	)
	(segment
		(start 177.187352 -131.53898)
		(end 177.398172 -131.402074)
		(width 0.1397)
		(layer "In5.Cu")
		(net "PCIE_COMP_TO_IOM_CLK_3_DN")
	)
	(segment
		(start 174.852076 -131.043172)
		(end 175.062896 -130.906012)
		(width 0.1397)
		(layer "In5.Cu")
		(net "PCIE_COMP_TO_IOM_CLK_3_DN")
	)
	(segment
		(start 176.777396 -131.452112)
		(end 177.187352 -131.53898)
		(width 0.1397)
		(layer "In5.Cu")
		(net "PCIE_COMP_TO_IOM_CLK_3_DN")
	)
	(segment
		(start 183.143144 -132.973826)
		(end 183.016144 -132.973826)
		(width 0.1397)
		(layer "In5.Cu")
		(net "PCIE_COMP_TO_IOM_CLK_3_DN")
	)
	(segment
		(start 145.076926 -20.506436)
		(end 146.943064 -20.903438)
		(width 0.1397)
		(layer "In5.Cu")
		(net "PCIE_COMP_TO_IOM_CLK_3_DN")
	)
	(segment
		(start 130.011932 -24.691848)
		(end 136.456166 -20.506436)
		(width 0.1397)
		(layer "In5.Cu")
		(net "PCIE_COMP_TO_IOM_CLK_3_DN")
	)
	(segment
		(start 183.295798 -132.267198)
		(end 183.295798 -132.821172)
		(width 0.1397)
		(layer "In5.Cu")
		(net "PCIE_COMP_TO_IOM_CLK_3_DN")
	)
	(segment
		(start 136.456166 -20.506436)
		(end 145.076926 -20.506436)
		(width 0.1397)
		(layer "In5.Cu")
		(net "PCIE_COMP_TO_IOM_CLK_3_DN")
	)
	(segment
		(start 171.903898 -130.235198)
		(end 173.137576 -130.497326)
		(width 0.1397)
		(layer "In5.Cu")
		(net "PCIE_COMP_TO_IOM_CLK_3_DN")
	)
	(segment
		(start 174.305214 -130.74523)
		(end 174.44212 -130.95605)
		(width 0.1397)
		(layer "In5.Cu")
		(net "PCIE_COMP_TO_IOM_CLK_3_DN")
	)
	(segment
		(start 168.889934 -87.105236)
		(end 171.7421 -100.52431)
		(width 0.1397)
		(layer "In5.Cu")
		(net "PCIE_COMP_TO_IOM_CLK_3_DN")
	)
	(segment
		(start 181.226206 -131.384802)
		(end 182.733696 -131.705096)
		(width 0.1397)
		(layer "In5.Cu")
		(net "PCIE_COMP_TO_IOM_CLK_3_DN")
	)
	(segment
		(start 175.472852 -130.993134)
		(end 175.609758 -131.204208)
		(width 0.1397)
		(layer "In5.Cu")
		(net "PCIE_COMP_TO_IOM_CLK_3_DN")
	)
	(segment
		(start 174.44212 -130.95605)
		(end 174.852076 -131.043172)
		(width 0.1397)
		(layer "In5.Cu")
		(net "PCIE_COMP_TO_IOM_CLK_3_DN")
	)
	(segment
		(start 173.895258 -130.658108)
		(end 174.305214 -130.74523)
		(width 0.1397)
		(layer "In5.Cu")
		(net "PCIE_COMP_TO_IOM_CLK_3_DN")
	)
	(segment
		(start 177.398172 -131.402074)
		(end 179.271422 -131.800092)
		(width 0.1397)
		(layer "In5.Cu")
		(net "PCIE_COMP_TO_IOM_CLK_3_DN")
	)
	(segment
		(start 179.271422 -131.800092)
		(end 181.226206 -131.384802)
		(width 0.1397)
		(layer "In5.Cu")
		(net "PCIE_COMP_TO_IOM_CLK_3_DN")
	)
	(segment
		(start 160.45815 -33.31337)
		(end 170.390312 -80.04556)
		(width 0.1397)
		(layer "In5.Cu")
		(net "PCIE_COMP_TO_IOM_CLK_3_DN")
	)
	(segment
		(start 175.609758 -131.204208)
		(end 176.019714 -131.291076)
		(width 0.1397)
		(layer "In5.Cu")
		(net "PCIE_COMP_TO_IOM_CLK_3_DN")
	)
	(segment
		(start 169.175938 -124.927868)
		(end 169.748708 -127.621538)
		(width 0.1397)
		(layer "In5.Cu")
		(net "PCIE_COMP_TO_IOM_CLK_3_DN")
	)
	(segment
		(start 148.808694 -21.299932)
		(end 155.462732 -25.621488)
		(width 0.1397)
		(layer "In5.Cu")
		(net "PCIE_COMP_TO_IOM_CLK_3_DN")
	)
	(segment
		(start 129.535174 -26.211276)
		(end 129.452116 -26.211276)
		(width 0.1397)
		(layer "In5.Cu")
		(net "PCIE_COMP_TO_IOM_CLK_3_DN")
	)
	(segment
		(start 170.390312 -80.04556)
		(end 168.889934 -87.105236)
		(width 0.1397)
		(layer "In5.Cu")
		(net "PCIE_COMP_TO_IOM_CLK_3_DN")
	)
	(segment
		(start 173.684438 -130.795014)
		(end 173.895258 -130.658108)
		(width 0.1397)
		(layer "In5.Cu")
		(net "PCIE_COMP_TO_IOM_CLK_3_DN")
	)
	(segment
		(start 173.137576 -130.497326)
		(end 173.274482 -130.708146)
		(width 0.1397)
		(layer "In5.Cu")
		(net "PCIE_COMP_TO_IOM_CLK_3_DN")
	)
	(segment
		(start 171.112434 -129.721102)
		(end 171.903898 -130.235198)
		(width 0.1397)
		(layer "In5.Cu")
		(net "PCIE_COMP_TO_IOM_CLK_3_DN")
	)
	(segment
		(start 173.274482 -130.708146)
		(end 173.684438 -130.795014)
		(width 0.1397)
		(layer "In5.Cu")
		(net "PCIE_COMP_TO_IOM_CLK_3_DN")
	)
	(segment
		(start 182.733696 -131.705096)
		(end 183.295798 -132.267198)
		(width 0.1397)
		(layer "In5.Cu")
		(net "PCIE_COMP_TO_IOM_CLK_3_DN")
	)
	(segment
		(start 155.462732 -25.621488)
		(end 160.45815 -33.31337)
		(width 0.1397)
		(layer "In5.Cu")
		(net "PCIE_COMP_TO_IOM_CLK_3_DN")
	)
	(segment
		(start 176.230534 -131.15417)
		(end 176.64049 -131.241292)
		(width 0.1397)
		(layer "In5.Cu")
		(net "PCIE_COMP_TO_IOM_CLK_3_DN")
	)
	(segment
		(start 129.243074 -25.46096)
		(end 130.011932 -24.691848)
		(width 0.1397)
		(layer "In5.Cu")
		(net "PCIE_COMP_TO_IOM_CLK_3_DN")
	)
	(segment
		(start 175.062896 -130.906012)
		(end 175.472852 -130.993134)
		(width 0.1397)
		(layer "In5.Cu")
		(net "PCIE_COMP_TO_IOM_CLK_3_DN")
	)
	(segment
		(start 169.748708 -127.621538)
		(end 171.112434 -129.721102)
		(width 0.1397)
		(layer "In5.Cu")
		(net "PCIE_COMP_TO_IOM_CLK_3_DN")
	)
	(segment
		(start 171.7421 -100.52431)
		(end 168.125648 -117.540278)
		(width 0.1397)
		(layer "In5.Cu")
		(net "PCIE_COMP_TO_IOM_CLK_3_DN")
	)
	(segment
		(start 176.019714 -131.291076)
		(end 176.230534 -131.15417)
		(width 0.1397)
		(layer "In5.Cu")
		(net "PCIE_COMP_TO_IOM_CLK_3_DN")
	)
	(segment
		(start 129.16662 -25.92578)
		(end 129.16662 -25.645364)
		(width 0.1397)
		(layer "In5.Cu")
		(net "PCIE_COMP_TO_IOM_CLK_3_DN")
	)
	(segment
		(start 176.64049 -131.241292)
		(end 176.777396 -131.452112)
		(width 0.1397)
		(layer "In5.Cu")
		(net "PCIE_COMP_TO_IOM_CLK_3_DN")
	)
	(segment
		(start 169.436034 -123.705112)
		(end 169.175938 -124.927868)
		(width 0.1397)
		(layer "In5.Cu")
		(net "PCIE_COMP_TO_IOM_CLK_3_DN")
	)
	(segment
		(start 146.943064 -20.903438)
		(end 148.808694 -21.299932)
		(width 0.1397)
		(layer "In5.Cu")
		(net "PCIE_COMP_TO_IOM_CLK_3_DN")
	)
	(arc
		(start 129.16662 -25.645364)
		(mid 129.186477 -25.545538)
		(end 129.243074 -25.46096)
		(width 0.1397)
		(layer "In5.Cu")
		(net "PCIE_COMP_TO_IOM_CLK_3_DN")
	)
	(arc
		(start 183.295798 -132.821172)
		(mid 183.251087 -132.929115)
		(end 183.143144 -132.973826)
		(width 0.1397)
		(layer "In5.Cu")
		(net "PCIE_COMP_TO_IOM_CLK_3_DN")
	)
	(arc
		(start 129.452116 -26.211276)
		(mid 129.25024 -26.127656)
		(end 129.16662 -25.92578)
		(width 0.1397)
		(layer "In5.Cu")
		(net "PCIE_COMP_TO_IOM_CLK_3_DN")
	)
	(segment
		(start 208.555336 -136.061196)
		(end 208.555336 -135.847582)
		(width 0.14605)
		(layer "F.Cu")
		(net "PCIE_COMP_TO_IOM_CLK_2_DP")
	)
	(segment
		(start 209.46999 -136.97585)
		(end 208.555336 -136.061196)
		(width 0.14605)
		(layer "F.Cu")
		(net "PCIE_COMP_TO_IOM_CLK_2_DP")
	)
	(segment
		(start 208.649824 -135.753094)
		(end 208.649824 -134.875016)
		(width 0.14605)
		(layer "F.Cu")
		(net "PCIE_COMP_TO_IOM_CLK_2_DP")
	)
	(segment
		(start 213.33333 -138.87704)
		(end 213.422992 -138.966702)
		(width 0.14605)
		(layer "F.Cu")
		(net "PCIE_COMP_TO_IOM_CLK_2_DP")
	)
	(segment
		(start 209.856832 -136.97585)
		(end 209.46999 -136.97585)
		(width 0.14605)
		(layer "F.Cu")
		(net "PCIE_COMP_TO_IOM_CLK_2_DP")
	)
	(segment
		(start 208.555336 -135.847582)
		(end 208.649824 -135.753094)
		(width 0.14605)
		(layer "F.Cu")
		(net "PCIE_COMP_TO_IOM_CLK_2_DP")
	)
	(segment
		(start 212.291676 -139.410694)
		(end 209.856832 -136.97585)
		(width 0.14605)
		(layer "F.Cu")
		(net "PCIE_COMP_TO_IOM_CLK_2_DP")
	)
	(segment
		(start 213.422992 -139.195302)
		(end 213.2076 -139.410694)
		(width 0.14605)
		(layer "F.Cu")
		(net "PCIE_COMP_TO_IOM_CLK_2_DP")
	)
	(arc
		(start 213.422992 -138.966702)
		(mid 213.470337 -139.081002)
		(end 213.422992 -139.195302)
		(width 0.14605)
		(layer "F.Cu")
		(net "PCIE_COMP_TO_IOM_CLK_2_DP")
	)
	(arc
		(start 213.2076 -139.410694)
		(mid 212.749638 -139.600388)
		(end 212.291676 -139.410694)
		(width 0.14605)
		(layer "F.Cu")
		(net "PCIE_COMP_TO_IOM_CLK_2_DP")
	)
	(segment
		(start 144.87398 -44.32681)
		(end 142.608554 -43.33494)
		(width 0.1397)
		(layer "In5.Cu")
		(net "PCIE_COMP_TO_IOM_CLK_2_DP")
	)
	(segment
		(start 204.883258 -145.623026)
		(end 204.473302 -145.710148)
		(width 0.1397)
		(layer "In5.Cu")
		(net "PCIE_COMP_TO_IOM_CLK_2_DP")
	)
	(segment
		(start 205.64094 -145.46199)
		(end 205.504034 -145.67281)
		(width 0.1397)
		(layer "In5.Cu")
		(net "PCIE_COMP_TO_IOM_CLK_2_DP")
	)
	(segment
		(start 158.201614 -143.226282)
		(end 155.914852 -139.70508)
		(width 0.1397)
		(layer "In5.Cu")
		(net "PCIE_COMP_TO_IOM_CLK_2_DP")
	)
	(segment
		(start 153.929334 -130.364484)
		(end 156.280612 -119.304562)
		(width 0.1397)
		(layer "In5.Cu")
		(net "PCIE_COMP_TO_IOM_CLK_2_DP")
	)
	(segment
		(start 213.422992 -139.181586)
		(end 212.840062 -139.764516)
		(width 0.1397)
		(layer "In5.Cu")
		(net "PCIE_COMP_TO_IOM_CLK_2_DP")
	)
	(segment
		(start 206.808578 -145.213832)
		(end 206.671672 -145.424652)
		(width 0.1397)
		(layer "In5.Cu")
		(net "PCIE_COMP_TO_IOM_CLK_2_DP")
	)
	(segment
		(start 190.183262 -146.836892)
		(end 189.773306 -146.924014)
		(width 0.1397)
		(layer "In5.Cu")
		(net "PCIE_COMP_TO_IOM_CLK_2_DP")
	)
	(segment
		(start 206.671672 -145.424652)
		(end 206.261716 -145.511774)
		(width 0.1397)
		(layer "In5.Cu")
		(net "PCIE_COMP_TO_IOM_CLK_2_DP")
	)
	(segment
		(start 155.234386 -77.063346)
		(end 149.390354 -49.57191)
		(width 0.1397)
		(layer "In5.Cu")
		(net "PCIE_COMP_TO_IOM_CLK_2_DP")
	)
	(segment
		(start 156.280612 -119.304562)
		(end 158.824422 -107.339384)
		(width 0.1397)
		(layer "In5.Cu")
		(net "PCIE_COMP_TO_IOM_CLK_2_DP")
	)
	(segment
		(start 206.050896 -145.374868)
		(end 205.64094 -145.46199)
		(width 0.1397)
		(layer "In5.Cu")
		(net "PCIE_COMP_TO_IOM_CLK_2_DP")
	)
	(segment
		(start 209.248502 -144.877028)
		(end 208.596992 -145.015458)
		(width 0.1397)
		(layer "In5.Cu")
		(net "PCIE_COMP_TO_IOM_CLK_2_DP")
	)
	(segment
		(start 204.473302 -145.710148)
		(end 204.336396 -145.920968)
		(width 0.1397)
		(layer "In5.Cu")
		(net "PCIE_COMP_TO_IOM_CLK_2_DP")
	)
	(segment
		(start 191.56172 -146.72564)
		(end 191.3509 -146.588734)
		(width 0.1397)
		(layer "In5.Cu")
		(net "PCIE_COMP_TO_IOM_CLK_2_DP")
	)
	(segment
		(start 153.811224 -83.757262)
		(end 155.234386 -77.063346)
		(width 0.1397)
		(layer "In5.Cu")
		(net "PCIE_COMP_TO_IOM_CLK_2_DP")
	)
	(segment
		(start 196.467222 -147.594066)
		(end 191.971676 -146.638518)
		(width 0.1397)
		(layer "In5.Cu")
		(net "PCIE_COMP_TO_IOM_CLK_2_DP")
	)
	(segment
		(start 178.970432 -149.401784)
		(end 162.232848 -145.844006)
		(width 0.1397)
		(layer "In5.Cu")
		(net "PCIE_COMP_TO_IOM_CLK_2_DP")
	)
	(segment
		(start 191.971676 -146.638518)
		(end 191.56172 -146.72564)
		(width 0.1397)
		(layer "In5.Cu")
		(net "PCIE_COMP_TO_IOM_CLK_2_DP")
	)
	(segment
		(start 205.504034 -145.67281)
		(end 205.094078 -145.759932)
		(width 0.1397)
		(layer "In5.Cu")
		(net "PCIE_COMP_TO_IOM_CLK_2_DP")
	)
	(segment
		(start 206.261716 -145.511774)
		(end 206.050896 -145.374868)
		(width 0.1397)
		(layer "In5.Cu")
		(net "PCIE_COMP_TO_IOM_CLK_2_DP")
	)
	(segment
		(start 189.773306 -146.924014)
		(end 189.6364 -147.134834)
		(width 0.1397)
		(layer "In5.Cu")
		(net "PCIE_COMP_TO_IOM_CLK_2_DP")
	)
	(segment
		(start 190.394082 -146.973798)
		(end 190.183262 -146.836892)
		(width 0.1397)
		(layer "In5.Cu")
		(net "PCIE_COMP_TO_IOM_CLK_2_DP")
	)
	(segment
		(start 208.386172 -144.878552)
		(end 207.976216 -144.965674)
		(width 0.1397)
		(layer "In5.Cu")
		(net "PCIE_COMP_TO_IOM_CLK_2_DP")
	)
	(segment
		(start 212.118448 -142.007082)
		(end 209.248502 -144.877028)
		(width 0.1397)
		(layer "In5.Cu")
		(net "PCIE_COMP_TO_IOM_CLK_2_DP")
	)
	(segment
		(start 190.940944 -146.675856)
		(end 190.804038 -146.886676)
		(width 0.1397)
		(layer "In5.Cu")
		(net "PCIE_COMP_TO_IOM_CLK_2_DP")
	)
	(segment
		(start 149.390354 -49.57191)
		(end 144.87398 -44.32681)
		(width 0.1397)
		(layer "In5.Cu")
		(net "PCIE_COMP_TO_IOM_CLK_2_DP")
	)
	(segment
		(start 207.429354 -145.263616)
		(end 207.218534 -145.12671)
		(width 0.1397)
		(layer "In5.Cu")
		(net "PCIE_COMP_TO_IOM_CLK_2_DP")
	)
	(segment
		(start 207.976216 -144.965674)
		(end 207.83931 -145.176494)
		(width 0.1397)
		(layer "In5.Cu")
		(net "PCIE_COMP_TO_IOM_CLK_2_DP")
	)
	(segment
		(start 204.336396 -145.920968)
		(end 196.467222 -147.594066)
		(width 0.1397)
		(layer "In5.Cu")
		(net "PCIE_COMP_TO_IOM_CLK_2_DP")
	)
	(segment
		(start 207.218534 -145.12671)
		(end 206.808578 -145.213832)
		(width 0.1397)
		(layer "In5.Cu")
		(net "PCIE_COMP_TO_IOM_CLK_2_DP")
	)
	(segment
		(start 158.824422 -107.339384)
		(end 153.811224 -83.757262)
		(width 0.1397)
		(layer "In5.Cu")
		(net "PCIE_COMP_TO_IOM_CLK_2_DP")
	)
	(segment
		(start 188.605668 -147.172172)
		(end 188.468762 -147.382992)
		(width 0.1397)
		(layer "In5.Cu")
		(net "PCIE_COMP_TO_IOM_CLK_2_DP")
	)
	(segment
		(start 189.6364 -147.134834)
		(end 189.226444 -147.221956)
		(width 0.1397)
		(layer "In5.Cu")
		(net "PCIE_COMP_TO_IOM_CLK_2_DP")
	)
	(segment
		(start 189.015624 -147.08505)
		(end 188.605668 -147.172172)
		(width 0.1397)
		(layer "In5.Cu")
		(net "PCIE_COMP_TO_IOM_CLK_2_DP")
	)
	(segment
		(start 142.608554 -43.33494)
		(end 141.45387 -43.33494)
		(width 0.1397)
		(layer "In5.Cu")
		(net "PCIE_COMP_TO_IOM_CLK_2_DP")
	)
	(segment
		(start 207.83931 -145.176494)
		(end 207.429354 -145.263616)
		(width 0.1397)
		(layer "In5.Cu")
		(net "PCIE_COMP_TO_IOM_CLK_2_DP")
	)
	(segment
		(start 212.466174 -140.66774)
		(end 212.466174 -141.2113)
		(width 0.1397)
		(layer "In5.Cu")
		(net "PCIE_COMP_TO_IOM_CLK_2_DP")
	)
	(segment
		(start 205.094078 -145.759932)
		(end 204.883258 -145.623026)
		(width 0.1397)
		(layer "In5.Cu")
		(net "PCIE_COMP_TO_IOM_CLK_2_DP")
	)
	(segment
		(start 188.468762 -147.382992)
		(end 178.970432 -149.401784)
		(width 0.1397)
		(layer "In5.Cu")
		(net "PCIE_COMP_TO_IOM_CLK_2_DP")
	)
	(segment
		(start 162.232848 -145.844006)
		(end 158.201614 -143.226282)
		(width 0.1397)
		(layer "In5.Cu")
		(net "PCIE_COMP_TO_IOM_CLK_2_DP")
	)
	(segment
		(start 155.914852 -139.70508)
		(end 153.929334 -130.364484)
		(width 0.1397)
		(layer "In5.Cu")
		(net "PCIE_COMP_TO_IOM_CLK_2_DP")
	)
	(segment
		(start 191.3509 -146.588734)
		(end 190.940944 -146.675856)
		(width 0.1397)
		(layer "In5.Cu")
		(net "PCIE_COMP_TO_IOM_CLK_2_DP")
	)
	(segment
		(start 189.226444 -147.221956)
		(end 189.015624 -147.08505)
		(width 0.1397)
		(layer "In5.Cu")
		(net "PCIE_COMP_TO_IOM_CLK_2_DP")
	)
	(segment
		(start 190.804038 -146.886676)
		(end 190.394082 -146.973798)
		(width 0.1397)
		(layer "In5.Cu")
		(net "PCIE_COMP_TO_IOM_CLK_2_DP")
	)
	(segment
		(start 141.299946 -43.181016)
		(end 141.299946 -42.800016)
		(width 0.1397)
		(layer "In5.Cu")
		(net "PCIE_COMP_TO_IOM_CLK_2_DP")
	)
	(segment
		(start 208.596992 -145.015458)
		(end 208.386172 -144.878552)
		(width 0.1397)
		(layer "In5.Cu")
		(net "PCIE_COMP_TO_IOM_CLK_2_DP")
	)
	(segment
		(start 212.149436 -141.976348)
		(end 212.118448 -142.007082)
		(width 0.1397)
		(layer "In5.Cu")
		(net "PCIE_COMP_TO_IOM_CLK_2_DP")
	)
	(segment
		(start 213.33333 -138.87704)
		(end 213.422992 -138.966702)
		(width 0.1397)
		(layer "In5.Cu")
		(net "PCIE_COMP_TO_IOM_CLK_2_DP")
	)
	(arc
		(start 141.45387 -43.33494)
		(mid 141.345029 -43.289857)
		(end 141.299946 -43.181016)
		(width 0.1397)
		(layer "In5.Cu")
		(net "PCIE_COMP_TO_IOM_CLK_2_DP")
	)
	(arc
		(start 213.422992 -138.966702)
		(mid 213.467496 -139.074144)
		(end 213.422992 -139.181586)
		(width 0.1397)
		(layer "In5.Cu")
		(net "PCIE_COMP_TO_IOM_CLK_2_DP")
	)
	(arc
		(start 212.840062 -139.764516)
		(mid 212.56325 -140.178934)
		(end 212.466174 -140.66774)
		(width 0.1397)
		(layer "In5.Cu")
		(net "PCIE_COMP_TO_IOM_CLK_2_DP")
	)
	(arc
		(start 212.466174 -141.2113)
		(mid 212.383911 -141.625335)
		(end 212.149436 -141.976348)
		(width 0.1397)
		(layer "In5.Cu")
		(net "PCIE_COMP_TO_IOM_CLK_2_DP")
	)
	(segment
		(start 212.071458 -139.630912)
		(end 211.592922 -139.152376)
		(width 0.14605)
		(layer "F.Cu")
		(net "PCIE_COMP_TO_IOM_CLK_2_DN")
	)
	(segment
		(start 208.244186 -135.877554)
		(end 208.149952 -135.78332)
		(width 0.14605)
		(layer "F.Cu")
		(net "PCIE_COMP_TO_IOM_CLK_2_DN")
	)
	(segment
		(start 213.961726 -139.505436)
		(end 213.872064 -139.415774)
		(width 0.14605)
		(layer "F.Cu")
		(net "PCIE_COMP_TO_IOM_CLK_2_DN")
	)
	(segment
		(start 209.7278 -137.287)
		(end 209.340958 -137.287)
		(width 0.14605)
		(layer "F.Cu")
		(net "PCIE_COMP_TO_IOM_CLK_2_DN")
	)
	(segment
		(start 211.592922 -139.152376)
		(end 211.592922 -139.152122)
		(width 0.14605)
		(layer "F.Cu")
		(net "PCIE_COMP_TO_IOM_CLK_2_DN")
	)
	(segment
		(start 211.592922 -139.152122)
		(end 209.7278 -137.287)
		(width 0.14605)
		(layer "F.Cu")
		(net "PCIE_COMP_TO_IOM_CLK_2_DN")
	)
	(segment
		(start 208.244186 -136.190228)
		(end 208.244186 -135.877554)
		(width 0.14605)
		(layer "F.Cu")
		(net "PCIE_COMP_TO_IOM_CLK_2_DN")
	)
	(segment
		(start 213.642956 -139.415774)
		(end 213.427818 -139.630912)
		(width 0.14605)
		(layer "F.Cu")
		(net "PCIE_COMP_TO_IOM_CLK_2_DN")
	)
	(segment
		(start 209.340958 -137.287)
		(end 208.244186 -136.190228)
		(width 0.14605)
		(layer "F.Cu")
		(net "PCIE_COMP_TO_IOM_CLK_2_DN")
	)
	(segment
		(start 208.149952 -135.78332)
		(end 208.149952 -134.875016)
		(width 0.14605)
		(layer "F.Cu")
		(net "PCIE_COMP_TO_IOM_CLK_2_DN")
	)
	(arc
		(start 213.872064 -139.415774)
		(mid 213.75751 -139.368324)
		(end 213.642956 -139.415774)
		(width 0.14605)
		(layer "F.Cu")
		(net "PCIE_COMP_TO_IOM_CLK_2_DN")
	)
	(arc
		(start 213.427818 -139.630912)
		(mid 212.749638 -139.911823)
		(end 212.071458 -139.630912)
		(width 0.14605)
		(layer "F.Cu")
		(net "PCIE_COMP_TO_IOM_CLK_2_DN")
	)
	(segment
		(start 154.781758 -124.76607)
		(end 155.957524 -119.235982)
		(width 0.1397)
		(layer "In5.Cu")
		(net "PCIE_COMP_TO_IOM_CLK_2_DN")
	)
	(segment
		(start 191.6303 -147.048982)
		(end 178.970432 -149.739604)
		(width 0.1397)
		(layer "In5.Cu")
		(net "PCIE_COMP_TO_IOM_CLK_2_DN")
	)
	(segment
		(start 209.41284 -145.179796)
		(end 196.467222 -147.931886)
		(width 0.1397)
		(layer "In5.Cu")
		(net "PCIE_COMP_TO_IOM_CLK_2_DN")
	)
	(segment
		(start 212.351112 -142.241524)
		(end 209.41284 -145.179796)
		(width 0.1397)
		(layer "In5.Cu")
		(net "PCIE_COMP_TO_IOM_CLK_2_DN")
	)
	(segment
		(start 155.957524 -119.235982)
		(end 157.221936 -113.288064)
		(width 0.1397)
		(layer "In5.Cu")
		(net "PCIE_COMP_TO_IOM_CLK_2_DN")
	)
	(segment
		(start 144.672558 -44.599352)
		(end 142.539212 -43.66514)
		(width 0.1397)
		(layer "In5.Cu")
		(net "PCIE_COMP_TO_IOM_CLK_2_DN")
	)
	(segment
		(start 158.486602 -107.339384)
		(end 153.473404 -83.757262)
		(width 0.1397)
		(layer "In5.Cu")
		(net "PCIE_COMP_TO_IOM_CLK_2_DN")
	)
	(segment
		(start 157.221936 -113.28781)
		(end 158.486602 -107.339384)
		(width 0.1397)
		(layer "In5.Cu")
		(net "PCIE_COMP_TO_IOM_CLK_2_DN")
	)
	(segment
		(start 162.104324 -146.154394)
		(end 157.962854 -143.465042)
		(width 0.1397)
		(layer "In5.Cu")
		(net "PCIE_COMP_TO_IOM_CLK_2_DN")
	)
	(segment
		(start 212.796374 -140.66774)
		(end 212.796374 -141.2113)
		(width 0.1397)
		(layer "In5.Cu")
		(net "PCIE_COMP_TO_IOM_CLK_2_DN")
	)
	(segment
		(start 153.591514 -130.364484)
		(end 154.781758 -124.76607)
		(width 0.1397)
		(layer "In5.Cu")
		(net "PCIE_COMP_TO_IOM_CLK_2_DN")
	)
	(segment
		(start 154.599132 -135.103616)
		(end 153.591514 -130.364484)
		(width 0.1397)
		(layer "In5.Cu")
		(net "PCIE_COMP_TO_IOM_CLK_2_DN")
	)
	(segment
		(start 153.473404 -83.757262)
		(end 154.19959 -80.341724)
		(width 0.1397)
		(layer "In5.Cu")
		(net "PCIE_COMP_TO_IOM_CLK_2_DN")
	)
	(segment
		(start 157.962854 -143.465042)
		(end 155.604464 -139.833604)
		(width 0.1397)
		(layer "In5.Cu")
		(net "PCIE_COMP_TO_IOM_CLK_2_DN")
	)
	(segment
		(start 213.961726 -139.505436)
		(end 213.872064 -139.415774)
		(width 0.1397)
		(layer "In5.Cu")
		(net "PCIE_COMP_TO_IOM_CLK_2_DN")
	)
	(segment
		(start 142.539212 -43.66514)
		(end 141.45387 -43.66514)
		(width 0.1397)
		(layer "In5.Cu")
		(net "PCIE_COMP_TO_IOM_CLK_2_DN")
	)
	(segment
		(start 196.467222 -147.931886)
		(end 191.971676 -146.976338)
		(width 0.1397)
		(layer "In5.Cu")
		(net "PCIE_COMP_TO_IOM_CLK_2_DN")
	)
	(segment
		(start 154.19959 -80.341724)
		(end 154.896566 -77.063346)
		(width 0.1397)
		(layer "In5.Cu")
		(net "PCIE_COMP_TO_IOM_CLK_2_DN")
	)
	(segment
		(start 157.221936 -113.288064)
		(end 157.221936 -113.28781)
		(width 0.1397)
		(layer "In5.Cu")
		(net "PCIE_COMP_TO_IOM_CLK_2_DN")
	)
	(segment
		(start 141.299946 -43.819064)
		(end 141.299946 -44.200064)
		(width 0.1397)
		(layer "In5.Cu")
		(net "PCIE_COMP_TO_IOM_CLK_2_DN")
	)
	(segment
		(start 149.084792 -49.723294)
		(end 144.672558 -44.599352)
		(width 0.1397)
		(layer "In5.Cu")
		(net "PCIE_COMP_TO_IOM_CLK_2_DN")
	)
	(segment
		(start 191.6303 -147.048728)
		(end 191.6303 -147.048982)
		(width 0.1397)
		(layer "In5.Cu")
		(net "PCIE_COMP_TO_IOM_CLK_2_DN")
	)
	(segment
		(start 191.971676 -146.976338)
		(end 191.6303 -147.048728)
		(width 0.1397)
		(layer "In5.Cu")
		(net "PCIE_COMP_TO_IOM_CLK_2_DN")
	)
	(segment
		(start 213.656164 -139.415774)
		(end 213.073742 -139.998196)
		(width 0.1397)
		(layer "In5.Cu")
		(net "PCIE_COMP_TO_IOM_CLK_2_DN")
	)
	(segment
		(start 155.604464 -139.833604)
		(end 154.599132 -135.103616)
		(width 0.1397)
		(layer "In5.Cu")
		(net "PCIE_COMP_TO_IOM_CLK_2_DN")
	)
	(segment
		(start 154.896566 -77.063346)
		(end 149.084792 -49.723294)
		(width 0.1397)
		(layer "In5.Cu")
		(net "PCIE_COMP_TO_IOM_CLK_2_DN")
	)
	(segment
		(start 178.970432 -149.739604)
		(end 162.104324 -146.154394)
		(width 0.1397)
		(layer "In5.Cu")
		(net "PCIE_COMP_TO_IOM_CLK_2_DN")
	)
	(segment
		(start 212.382608 -142.210536)
		(end 212.351112 -142.241524)
		(width 0.1397)
		(layer "In5.Cu")
		(net "PCIE_COMP_TO_IOM_CLK_2_DN")
	)
	(segment
		(start 212.796374 -141.2113)
		(end 212.796628 -141.2113)
		(width 0.1397)
		(layer "In5.Cu")
		(net "PCIE_COMP_TO_IOM_CLK_2_DN")
	)
	(arc
		(start 212.796628 -141.2113)
		(mid 212.689073 -141.752126)
		(end 212.382608 -142.210536)
		(width 0.1397)
		(layer "In5.Cu")
		(net "PCIE_COMP_TO_IOM_CLK_2_DN")
	)
	(arc
		(start 213.872064 -139.415774)
		(mid 213.764114 -139.37106)
		(end 213.656164 -139.415774)
		(width 0.1397)
		(layer "In5.Cu")
		(net "PCIE_COMP_TO_IOM_CLK_2_DN")
	)
	(arc
		(start 213.073742 -139.998196)
		(mid 212.868485 -140.305385)
		(end 212.796374 -140.66774)
		(width 0.1397)
		(layer "In5.Cu")
		(net "PCIE_COMP_TO_IOM_CLK_2_DN")
	)
	(arc
		(start 141.45387 -43.66514)
		(mid 141.345029 -43.710223)
		(end 141.299946 -43.819064)
		(width 0.1397)
		(layer "In5.Cu")
		(net "PCIE_COMP_TO_IOM_CLK_2_DN")
	)
	(segment
		(start 204.048614 -138.348466)
		(end 204.048614 -135.8138)
		(width 0.14605)
		(layer "F.Cu")
		(net "PCIE_COMP_TO_IOM_9_DP")
	)
	(segment
		(start 205.643226 -139.943078)
		(end 204.048614 -138.348466)
		(width 0.14605)
		(layer "F.Cu")
		(net "PCIE_COMP_TO_IOM_9_DP")
	)
	(segment
		(start 205.456536 -141.219936)
		(end 205.643226 -141.033246)
		(width 0.14605)
		(layer "F.Cu")
		(net "PCIE_COMP_TO_IOM_9_DP")
	)
	(segment
		(start 204.14996 -135.712454)
		(end 204.14996 -134.875016)
		(width 0.14605)
		(layer "F.Cu")
		(net "PCIE_COMP_TO_IOM_9_DP")
	)
	(segment
		(start 205.546198 -141.538198)
		(end 205.456536 -141.448536)
		(width 0.14605)
		(layer "F.Cu")
		(net "PCIE_COMP_TO_IOM_9_DP")
	)
	(segment
		(start 204.048614 -135.8138)
		(end 204.14996 -135.712454)
		(width 0.14605)
		(layer "F.Cu")
		(net "PCIE_COMP_TO_IOM_9_DP")
	)
	(arc
		(start 205.456536 -141.448536)
		(mid 205.409191 -141.334236)
		(end 205.456536 -141.219936)
		(width 0.14605)
		(layer "F.Cu")
		(net "PCIE_COMP_TO_IOM_9_DP")
	)
	(arc
		(start 205.643226 -141.033246)
		(mid 205.869007 -140.488162)
		(end 205.643226 -139.943078)
		(width 0.14605)
		(layer "F.Cu")
		(net "PCIE_COMP_TO_IOM_9_DP")
	)
	(segment
		(start 161.628582 -98.492818)
		(end 150.535386 -45.89399)
		(width 0.14605)
		(layer "B.Cu")
		(net "PCIE_COMP_TO_IOM_9_DP")
	)
	(segment
		(start 156.044646 -127.241808)
		(end 161.628582 -98.492818)
		(width 0.14605)
		(layer "B.Cu")
		(net "PCIE_COMP_TO_IOM_9_DP")
	)
	(segment
		(start 164.407088 -145.850356)
		(end 160.601406 -143.282416)
		(width 0.14605)
		(layer "B.Cu")
		(net "PCIE_COMP_TO_IOM_9_DP")
	)
	(segment
		(start 166.74084 -146.303746)
		(end 166.74084 -146.303492)
		(width 0.14605)
		(layer "B.Cu")
		(net "PCIE_COMP_TO_IOM_9_DP")
	)
	(segment
		(start 138.755374 -30.357826)
		(end 138.755374 -33.520126)
		(width 0.14605)
		(layer "B.Cu")
		(net "PCIE_COMP_TO_IOM_9_DP")
	)
	(segment
		(start 150.291546 -44.73829)
		(end 150.111206 -44.620434)
		(width 0.14605)
		(layer "B.Cu")
		(net "PCIE_COMP_TO_IOM_9_DP")
	)
	(segment
		(start 149.623526 -42.309288)
		(end 149.533102 -41.880536)
		(width 0.14605)
		(layer "B.Cu")
		(net "PCIE_COMP_TO_IOM_9_DP")
	)
	(segment
		(start 141.808708 -29.0322)
		(end 140.081 -29.0322)
		(width 0.14605)
		(layer "B.Cu")
		(net "PCIE_COMP_TO_IOM_9_DP")
	)
	(segment
		(start 205.018894 -142.603982)
		(end 204.687932 -142.935198)
		(width 0.14605)
		(layer "B.Cu")
		(net "PCIE_COMP_TO_IOM_9_DP")
	)
	(segment
		(start 194.15633 -145.426176)
		(end 184.606438 -147.291552)
		(width 0.14605)
		(layer "B.Cu")
		(net "PCIE_COMP_TO_IOM_9_DP")
	)
	(segment
		(start 166.74084 -146.303492)
		(end 164.407088 -145.850356)
		(width 0.14605)
		(layer "B.Cu")
		(net "PCIE_COMP_TO_IOM_9_DP")
	)
	(segment
		(start 143.1671 -29.57957)
		(end 142.553182 -29.18079)
		(width 0.14605)
		(layer "B.Cu")
		(net "PCIE_COMP_TO_IOM_9_DP")
	)
	(segment
		(start 150.138384 -44.011342)
		(end 150.04796 -43.58259)
		(width 0.14605)
		(layer "B.Cu")
		(net "PCIE_COMP_TO_IOM_9_DP")
	)
	(segment
		(start 184.606438 -147.291552)
		(end 178.22926 -148.537422)
		(width 0.14605)
		(layer "B.Cu")
		(net "PCIE_COMP_TO_IOM_9_DP")
	)
	(segment
		(start 205.018894 -141.778482)
		(end 205.018894 -142.603982)
		(width 0.14605)
		(layer "B.Cu")
		(net "PCIE_COMP_TO_IOM_9_DP")
	)
	(segment
		(start 149.80412 -42.42689)
		(end 149.623526 -42.309288)
		(width 0.14605)
		(layer "B.Cu")
		(net "PCIE_COMP_TO_IOM_9_DP")
	)
	(segment
		(start 139.499848 -33.581086)
		(end 139.499848 -33.200086)
		(width 0.14605)
		(layer "B.Cu")
		(net "PCIE_COMP_TO_IOM_9_DP")
	)
	(segment
		(start 178.229006 -148.537422)
		(end 178.229006 -148.537168)
		(width 0.14605)
		(layer "B.Cu")
		(net "PCIE_COMP_TO_IOM_9_DP")
	)
	(segment
		(start 205.227936 -141.448536)
		(end 205.227428 -141.449044)
		(width 0.14605)
		(layer "B.Cu")
		(net "PCIE_COMP_TO_IOM_9_DP")
	)
	(segment
		(start 194.15633 -145.425668)
		(end 194.15633 -145.426176)
		(width 0.14605)
		(layer "B.Cu")
		(net "PCIE_COMP_TO_IOM_9_DP")
	)
	(segment
		(start 150.38197 -45.167042)
		(end 150.291546 -44.73829)
		(width 0.14605)
		(layer "B.Cu")
		(net "PCIE_COMP_TO_IOM_9_DP")
	)
	(segment
		(start 150.020782 -44.191682)
		(end 150.138384 -44.011342)
		(width 0.14605)
		(layer "B.Cu")
		(net "PCIE_COMP_TO_IOM_9_DP")
	)
	(segment
		(start 205.546198 -141.538198)
		(end 205.456536 -141.448536)
		(width 0.14605)
		(layer "B.Cu")
		(net "PCIE_COMP_TO_IOM_9_DP")
	)
	(segment
		(start 204.687932 -142.935198)
		(end 203.767944 -143.547846)
		(width 0.14605)
		(layer "B.Cu")
		(net "PCIE_COMP_TO_IOM_9_DP")
	)
	(segment
		(start 149.650958 -41.699942)
		(end 148.983954 -38.537388)
		(width 0.14605)
		(layer "B.Cu")
		(net "PCIE_COMP_TO_IOM_9_DP")
	)
	(segment
		(start 178.22926 -148.537422)
		(end 178.229006 -148.537422)
		(width 0.14605)
		(layer "B.Cu")
		(net "PCIE_COMP_TO_IOM_9_DP")
	)
	(segment
		(start 149.867366 -43.464734)
		(end 149.776942 -43.036236)
		(width 0.14605)
		(layer "B.Cu")
		(net "PCIE_COMP_TO_IOM_9_DP")
	)
	(segment
		(start 150.535386 -45.89399)
		(end 150.354792 -45.776134)
		(width 0.14605)
		(layer "B.Cu")
		(net "PCIE_COMP_TO_IOM_9_DP")
	)
	(segment
		(start 150.354792 -45.776134)
		(end 150.264368 -45.347382)
		(width 0.14605)
		(layer "B.Cu")
		(net "PCIE_COMP_TO_IOM_9_DP")
	)
	(segment
		(start 142.553182 -29.18079)
		(end 141.808708 -29.0322)
		(width 0.14605)
		(layer "B.Cu")
		(net "PCIE_COMP_TO_IOM_9_DP")
	)
	(segment
		(start 149.533102 -41.880536)
		(end 149.650958 -41.699942)
		(width 0.14605)
		(layer "B.Cu")
		(net "PCIE_COMP_TO_IOM_9_DP")
	)
	(segment
		(start 205.227428 -141.44879)
		(end 205.104492 -141.571726)
		(width 0.14605)
		(layer "B.Cu")
		(net "PCIE_COMP_TO_IOM_9_DP")
	)
	(segment
		(start 149.894544 -42.855642)
		(end 149.80412 -42.42689)
		(width 0.14605)
		(layer "B.Cu")
		(net "PCIE_COMP_TO_IOM_9_DP")
	)
	(segment
		(start 203.767944 -143.547846)
		(end 194.15633 -145.425668)
		(width 0.14605)
		(layer "B.Cu")
		(net "PCIE_COMP_TO_IOM_9_DP")
	)
	(segment
		(start 160.601406 -143.282416)
		(end 158.57728 -140.282168)
		(width 0.14605)
		(layer "B.Cu")
		(net "PCIE_COMP_TO_IOM_9_DP")
	)
	(segment
		(start 140.081 -29.0322)
		(end 138.755374 -30.357826)
		(width 0.14605)
		(layer "B.Cu")
		(net "PCIE_COMP_TO_IOM_9_DP")
	)
	(segment
		(start 148.983954 -38.537388)
		(end 143.1671 -29.57957)
		(width 0.14605)
		(layer "B.Cu")
		(net "PCIE_COMP_TO_IOM_9_DP")
	)
	(segment
		(start 205.227428 -141.449044)
		(end 205.227428 -141.44879)
		(width 0.14605)
		(layer "B.Cu")
		(net "PCIE_COMP_TO_IOM_9_DP")
	)
	(segment
		(start 138.97991 -33.744662)
		(end 139.336272 -33.744662)
		(width 0.14605)
		(layer "B.Cu")
		(net "PCIE_COMP_TO_IOM_9_DP")
	)
	(segment
		(start 150.264368 -45.347382)
		(end 150.38197 -45.167042)
		(width 0.14605)
		(layer "B.Cu")
		(net "PCIE_COMP_TO_IOM_9_DP")
	)
	(segment
		(start 158.57728 -140.282168)
		(end 156.044646 -127.241808)
		(width 0.14605)
		(layer "B.Cu")
		(net "PCIE_COMP_TO_IOM_9_DP")
	)
	(segment
		(start 150.04796 -43.58259)
		(end 149.867366 -43.464734)
		(width 0.14605)
		(layer "B.Cu")
		(net "PCIE_COMP_TO_IOM_9_DP")
	)
	(segment
		(start 149.776942 -43.036236)
		(end 149.894544 -42.855642)
		(width 0.14605)
		(layer "B.Cu")
		(net "PCIE_COMP_TO_IOM_9_DP")
	)
	(segment
		(start 150.111206 -44.620434)
		(end 150.020782 -44.191682)
		(width 0.14605)
		(layer "B.Cu")
		(net "PCIE_COMP_TO_IOM_9_DP")
	)
	(segment
		(start 178.229006 -148.537168)
		(end 166.74084 -146.303746)
		(width 0.14605)
		(layer "B.Cu")
		(net "PCIE_COMP_TO_IOM_9_DP")
	)
	(arc
		(start 205.456536 -141.448536)
		(mid 205.342236 -141.401191)
		(end 205.227936 -141.448536)
		(width 0.14605)
		(layer "B.Cu")
		(net "PCIE_COMP_TO_IOM_9_DP")
	)
	(arc
		(start 139.336272 -33.744662)
		(mid 139.451938 -33.696752)
		(end 139.499848 -33.581086)
		(width 0.14605)
		(layer "B.Cu")
		(net "PCIE_COMP_TO_IOM_9_DP")
	)
	(arc
		(start 138.755374 -33.520126)
		(mid 138.821139 -33.678897)
		(end 138.97991 -33.744662)
		(width 0.14605)
		(layer "B.Cu")
		(net "PCIE_COMP_TO_IOM_9_DP")
	)
	(arc
		(start 205.104492 -141.571726)
		(mid 205.041108 -141.666586)
		(end 205.018894 -141.778482)
		(width 0.14605)
		(layer "B.Cu")
		(net "PCIE_COMP_TO_IOM_9_DP")
	)
	(segment
		(start 203.737464 -138.477752)
		(end 203.737464 -135.80745)
		(width 0.14605)
		(layer "F.Cu")
		(net "PCIE_COMP_TO_IOM_9_DN")
	)
	(segment
		(start 203.649834 -135.71982)
		(end 203.649834 -134.875016)
		(width 0.14605)
		(layer "F.Cu")
		(net "PCIE_COMP_TO_IOM_9_DN")
	)
	(segment
		(start 204.917802 -140.909802)
		(end 205.007464 -140.999464)
		(width 0.14605)
		(layer "F.Cu")
		(net "PCIE_COMP_TO_IOM_9_DN")
	)
	(segment
		(start 205.423008 -140.163296)
		(end 203.737464 -138.477752)
		(width 0.14605)
		(layer "F.Cu")
		(net "PCIE_COMP_TO_IOM_9_DN")
	)
	(segment
		(start 205.236572 -140.999464)
		(end 205.423008 -140.813028)
		(width 0.14605)
		(layer "F.Cu")
		(net "PCIE_COMP_TO_IOM_9_DN")
	)
	(segment
		(start 203.737464 -135.80745)
		(end 203.649834 -135.71982)
		(width 0.14605)
		(layer "F.Cu")
		(net "PCIE_COMP_TO_IOM_9_DN")
	)
	(arc
		(start 205.423008 -140.813028)
		(mid 205.557572 -140.488162)
		(end 205.423008 -140.163296)
		(width 0.14605)
		(layer "F.Cu")
		(net "PCIE_COMP_TO_IOM_9_DN")
	)
	(arc
		(start 205.007464 -140.999464)
		(mid 205.122018 -141.046914)
		(end 205.236572 -140.999464)
		(width 0.14605)
		(layer "F.Cu")
		(net "PCIE_COMP_TO_IOM_9_DN")
	)
	(segment
		(start 204.489558 -142.693136)
		(end 203.64704 -143.254222)
		(width 0.14605)
		(layer "B.Cu")
		(net "PCIE_COMP_TO_IOM_9_DN")
	)
	(segment
		(start 142.672816 -28.887166)
		(end 142.475458 -28.847542)
		(width 0.14605)
		(layer "B.Cu")
		(net "PCIE_COMP_TO_IOM_9_DN")
	)
	(segment
		(start 204.987906 -141.24813)
		(end 204.884528 -141.351508)
		(width 0.14605)
		(layer "B.Cu")
		(net "PCIE_COMP_TO_IOM_9_DN")
	)
	(segment
		(start 139.951968 -28.72105)
		(end 138.444224 -30.228794)
		(width 0.14605)
		(layer "B.Cu")
		(net "PCIE_COMP_TO_IOM_9_DN")
	)
	(segment
		(start 149.955504 -41.635934)
		(end 149.276562 -38.416484)
		(width 0.14605)
		(layer "B.Cu")
		(net "PCIE_COMP_TO_IOM_9_DN")
	)
	(segment
		(start 142.055596 -28.763976)
		(end 141.839442 -28.72105)
		(width 0.14605)
		(layer "B.Cu")
		(net "PCIE_COMP_TO_IOM_9_DN")
	)
	(segment
		(start 204.987652 -141.247876)
		(end 204.987906 -141.24813)
		(width 0.14605)
		(layer "B.Cu")
		(net "PCIE_COMP_TO_IOM_9_DN")
	)
	(segment
		(start 205.007464 -141.228318)
		(end 204.987652 -141.247876)
		(width 0.14605)
		(layer "B.Cu")
		(net "PCIE_COMP_TO_IOM_9_DN")
	)
	(segment
		(start 158.870904 -140.160502)
		(end 156.361638 -127.241808)
		(width 0.14605)
		(layer "B.Cu")
		(net "PCIE_COMP_TO_IOM_9_DN")
	)
	(segment
		(start 178.229006 -148.220176)
		(end 167.05199 -146.047206)
		(width 0.14605)
		(layer "B.Cu")
		(net "PCIE_COMP_TO_IOM_9_DN")
	)
	(segment
		(start 167.05199 -146.047206)
		(end 167.05199 -146.046952)
		(width 0.14605)
		(layer "B.Cu")
		(net "PCIE_COMP_TO_IOM_9_DN")
	)
	(segment
		(start 160.825688 -143.058134)
		(end 158.870904 -140.160502)
		(width 0.14605)
		(layer "B.Cu")
		(net "PCIE_COMP_TO_IOM_9_DN")
	)
	(segment
		(start 141.839442 -28.72105)
		(end 139.951968 -28.72105)
		(width 0.14605)
		(layer "B.Cu")
		(net "PCIE_COMP_TO_IOM_9_DN")
	)
	(segment
		(start 142.117318 -28.776168)
		(end 142.055596 -28.763976)
		(width 0.14605)
		(layer "B.Cu")
		(net "PCIE_COMP_TO_IOM_9_DN")
	)
	(segment
		(start 142.475458 -28.847542)
		(end 142.117318 -28.776168)
		(width 0.14605)
		(layer "B.Cu")
		(net "PCIE_COMP_TO_IOM_9_DN")
	)
	(segment
		(start 204.917802 -140.909802)
		(end 205.007464 -140.999464)
		(width 0.14605)
		(layer "B.Cu")
		(net "PCIE_COMP_TO_IOM_9_DN")
	)
	(segment
		(start 204.707744 -142.47495)
		(end 204.489558 -142.693136)
		(width 0.14605)
		(layer "B.Cu")
		(net "PCIE_COMP_TO_IOM_9_DN")
	)
	(segment
		(start 139.499848 -34.219134)
		(end 139.499848 -34.600134)
		(width 0.14605)
		(layer "B.Cu")
		(net "PCIE_COMP_TO_IOM_9_DN")
	)
	(segment
		(start 203.64704 -143.254222)
		(end 178.229006 -148.220176)
		(width 0.14605)
		(layer "B.Cu")
		(net "PCIE_COMP_TO_IOM_9_DN")
	)
	(segment
		(start 138.97991 -34.055812)
		(end 139.336526 -34.055812)
		(width 0.14605)
		(layer "B.Cu")
		(net "PCIE_COMP_TO_IOM_9_DN")
	)
	(segment
		(start 143.392144 -29.354526)
		(end 142.672816 -28.887166)
		(width 0.14605)
		(layer "B.Cu")
		(net "PCIE_COMP_TO_IOM_9_DN")
	)
	(segment
		(start 138.444224 -30.228794)
		(end 138.444224 -33.520126)
		(width 0.14605)
		(layer "B.Cu")
		(net "PCIE_COMP_TO_IOM_9_DN")
	)
	(segment
		(start 161.946082 -98.490278)
		(end 149.955504 -41.635934)
		(width 0.14605)
		(layer "B.Cu")
		(net "PCIE_COMP_TO_IOM_9_DN")
	)
	(segment
		(start 167.05199 -146.046952)
		(end 164.528754 -145.556732)
		(width 0.14605)
		(layer "B.Cu")
		(net "PCIE_COMP_TO_IOM_9_DN")
	)
	(segment
		(start 204.707744 -141.778482)
		(end 204.707744 -142.47495)
		(width 0.14605)
		(layer "B.Cu")
		(net "PCIE_COMP_TO_IOM_9_DN")
	)
	(segment
		(start 164.528754 -145.556732)
		(end 160.825688 -143.058134)
		(width 0.14605)
		(layer "B.Cu")
		(net "PCIE_COMP_TO_IOM_9_DN")
	)
	(segment
		(start 149.276562 -38.416484)
		(end 143.392144 -29.354526)
		(width 0.14605)
		(layer "B.Cu")
		(net "PCIE_COMP_TO_IOM_9_DN")
	)
	(segment
		(start 156.361638 -127.241808)
		(end 161.946082 -98.490278)
		(width 0.14605)
		(layer "B.Cu")
		(net "PCIE_COMP_TO_IOM_9_DN")
	)
	(arc
		(start 139.336526 -34.055812)
		(mid 139.452012 -34.103648)
		(end 139.499848 -34.219134)
		(width 0.14605)
		(layer "B.Cu")
		(net "PCIE_COMP_TO_IOM_9_DN")
	)
	(arc
		(start 205.007464 -140.999464)
		(mid 205.054988 -141.113928)
		(end 205.007464 -141.228318)
		(width 0.14605)
		(layer "B.Cu")
		(net "PCIE_COMP_TO_IOM_9_DN")
	)
	(arc
		(start 204.884528 -141.351508)
		(mid 204.753663 -141.547406)
		(end 204.707744 -141.778482)
		(width 0.14605)
		(layer "B.Cu")
		(net "PCIE_COMP_TO_IOM_9_DN")
	)
	(arc
		(start 138.444224 -33.520126)
		(mid 138.601123 -33.898913)
		(end 138.97991 -34.055812)
		(width 0.14605)
		(layer "B.Cu")
		(net "PCIE_COMP_TO_IOM_9_DN")
	)
	(segment
		(start 207.048608 -136.398)
		(end 207.048608 -135.8138)
		(width 0.14605)
		(layer "F.Cu")
		(net "PCIE_COMP_TO_IOM_8_DP")
	)
	(segment
		(start 210.155536 -140.838936)
		(end 210.370928 -140.623544)
		(width 0.14605)
		(layer "F.Cu")
		(net "PCIE_COMP_TO_IOM_8_DP")
	)
	(segment
		(start 207.15224 -135.710168)
		(end 207.15224 -134.877302)
		(width 0.14605)
		(layer "F.Cu")
		(net "PCIE_COMP_TO_IOM_8_DP")
	)
	(segment
		(start 210.370928 -139.50442)
		(end 209.614008 -138.7475)
		(width 0.14605)
		(layer "F.Cu")
		(net "PCIE_COMP_TO_IOM_8_DP")
	)
	(segment
		(start 209.398362 -138.7475)
		(end 207.048608 -136.398)
		(width 0.14605)
		(layer "F.Cu")
		(net "PCIE_COMP_TO_IOM_8_DP")
	)
	(segment
		(start 209.614008 -138.7475)
		(end 209.398362 -138.7475)
		(width 0.14605)
		(layer "F.Cu")
		(net "PCIE_COMP_TO_IOM_8_DP")
	)
	(segment
		(start 207.15224 -134.877302)
		(end 207.149954 -134.875016)
		(width 0.14605)
		(layer "F.Cu")
		(net "PCIE_COMP_TO_IOM_8_DP")
	)
	(segment
		(start 207.048608 -135.8138)
		(end 207.15224 -135.710168)
		(width 0.14605)
		(layer "F.Cu")
		(net "PCIE_COMP_TO_IOM_8_DP")
	)
	(segment
		(start 210.245198 -141.157198)
		(end 210.155536 -141.067536)
		(width 0.14605)
		(layer "F.Cu")
		(net "PCIE_COMP_TO_IOM_8_DP")
	)
	(arc
		(start 210.370928 -140.623544)
		(mid 210.602706 -140.063982)
		(end 210.370928 -139.50442)
		(width 0.14605)
		(layer "F.Cu")
		(net "PCIE_COMP_TO_IOM_8_DP")
	)
	(arc
		(start 210.155536 -141.067536)
		(mid 210.108191 -140.953236)
		(end 210.155536 -140.838936)
		(width 0.14605)
		(layer "F.Cu")
		(net "PCIE_COMP_TO_IOM_8_DP")
	)
	(segment
		(start 148.61921 -44.011342)
		(end 148.438616 -43.893994)
		(width 0.14605)
		(layer "B.Cu")
		(net "PCIE_COMP_TO_IOM_8_DP")
	)
	(segment
		(start 154.685238 -126.453138)
		(end 160.130236 -98.444304)
		(width 0.14605)
		(layer "B.Cu")
		(net "PCIE_COMP_TO_IOM_8_DP")
	)
	(segment
		(start 147.44954 -38.480746)
		(end 142.16253 -30.337506)
		(width 0.14605)
		(layer "B.Cu")
		(net "PCIE_COMP_TO_IOM_8_DP")
	)
	(segment
		(start 148.836634 -45.776388)
		(end 148.954236 -45.595794)
		(width 0.14605)
		(layer "B.Cu")
		(net "PCIE_COMP_TO_IOM_8_DP")
	)
	(segment
		(start 141.348206 -30.1752)
		(end 140.793724 -30.1752)
		(width 0.14605)
		(layer "B.Cu")
		(net "PCIE_COMP_TO_IOM_8_DP")
	)
	(segment
		(start 157.52445 -141.056868)
		(end 154.685238 -126.453138)
		(width 0.14605)
		(layer "B.Cu")
		(net "PCIE_COMP_TO_IOM_8_DP")
	)
	(segment
		(start 149.080982 -46.931834)
		(end 149.198584 -46.75124)
		(width 0.14605)
		(layer "B.Cu")
		(net "PCIE_COMP_TO_IOM_8_DP")
	)
	(segment
		(start 208.460594 -142.533624)
		(end 204.66431 -145.074132)
		(width 0.14605)
		(layer "B.Cu")
		(net "PCIE_COMP_TO_IOM_8_DP")
	)
	(segment
		(start 148.438616 -43.893994)
		(end 148.347938 -43.465242)
		(width 0.14605)
		(layer "B.Cu")
		(net "PCIE_COMP_TO_IOM_8_DP")
	)
	(segment
		(start 148.682964 -45.04944)
		(end 148.592286 -44.620688)
		(width 0.14605)
		(layer "B.Cu")
		(net "PCIE_COMP_TO_IOM_8_DP")
	)
	(segment
		(start 149.17166 -47.360586)
		(end 149.080982 -46.931834)
		(width 0.14605)
		(layer "B.Cu")
		(net "PCIE_COMP_TO_IOM_8_DP")
	)
	(segment
		(start 140.793724 -30.1752)
		(end 140.555472 -30.413452)
		(width 0.14605)
		(layer "B.Cu")
		(net "PCIE_COMP_TO_IOM_8_DP")
	)
	(segment
		(start 141.299946 -32.38119)
		(end 141.299946 -32.00019)
		(width 0.14605)
		(layer "B.Cu")
		(net "PCIE_COMP_TO_IOM_8_DP")
	)
	(segment
		(start 148.954236 -45.595794)
		(end 148.863558 -45.167042)
		(width 0.14605)
		(layer "B.Cu")
		(net "PCIE_COMP_TO_IOM_8_DP")
	)
	(segment
		(start 148.709888 -44.440094)
		(end 148.61921 -44.011342)
		(width 0.14605)
		(layer "B.Cu")
		(net "PCIE_COMP_TO_IOM_8_DP")
	)
	(segment
		(start 149.352254 -47.478188)
		(end 149.17166 -47.360586)
		(width 0.14605)
		(layer "B.Cu")
		(net "PCIE_COMP_TO_IOM_8_DP")
	)
	(segment
		(start 148.347938 -43.465242)
		(end 148.46554 -43.284648)
		(width 0.14605)
		(layer "B.Cu")
		(net "PCIE_COMP_TO_IOM_8_DP")
	)
	(segment
		(start 163.875466 -146.991832)
		(end 159.56788 -144.08658)
		(width 0.14605)
		(layer "B.Cu")
		(net "PCIE_COMP_TO_IOM_8_DP")
	)
	(segment
		(start 148.592286 -44.620688)
		(end 148.709888 -44.440094)
		(width 0.14605)
		(layer "B.Cu")
		(net "PCIE_COMP_TO_IOM_8_DP")
	)
	(segment
		(start 149.198584 -46.75124)
		(end 149.107906 -46.322488)
		(width 0.14605)
		(layer "B.Cu")
		(net "PCIE_COMP_TO_IOM_8_DP")
	)
	(segment
		(start 149.107906 -46.322488)
		(end 148.927312 -46.204886)
		(width 0.14605)
		(layer "B.Cu")
		(net "PCIE_COMP_TO_IOM_8_DP")
	)
	(segment
		(start 140.772642 -32.544512)
		(end 141.136624 -32.544512)
		(width 0.14605)
		(layer "B.Cu")
		(net "PCIE_COMP_TO_IOM_8_DP")
	)
	(segment
		(start 148.863558 -45.167042)
		(end 148.682964 -45.04944)
		(width 0.14605)
		(layer "B.Cu")
		(net "PCIE_COMP_TO_IOM_8_DP")
	)
	(segment
		(start 179.338732 -149.996906)
		(end 163.875466 -146.991832)
		(width 0.14605)
		(layer "B.Cu")
		(net "PCIE_COMP_TO_IOM_8_DP")
	)
	(segment
		(start 204.66431 -145.074132)
		(end 179.338732 -149.996906)
		(width 0.14605)
		(layer "B.Cu")
		(net "PCIE_COMP_TO_IOM_8_DP")
	)
	(segment
		(start 140.555472 -30.413452)
		(end 140.555472 -32.327342)
		(width 0.14605)
		(layer "B.Cu")
		(net "PCIE_COMP_TO_IOM_8_DP")
	)
	(segment
		(start 160.130236 -98.444304)
		(end 154.741118 -72.960992)
		(width 0.14605)
		(layer "B.Cu")
		(net "PCIE_COMP_TO_IOM_8_DP")
	)
	(segment
		(start 154.741118 -72.960992)
		(end 149.352254 -47.478188)
		(width 0.14605)
		(layer "B.Cu")
		(net "PCIE_COMP_TO_IOM_8_DP")
	)
	(segment
		(start 148.927312 -46.204886)
		(end 148.836634 -45.776388)
		(width 0.14605)
		(layer "B.Cu")
		(net "PCIE_COMP_TO_IOM_8_DP")
	)
	(segment
		(start 148.46554 -43.284648)
		(end 147.44954 -38.480746)
		(width 0.14605)
		(layer "B.Cu")
		(net "PCIE_COMP_TO_IOM_8_DP")
	)
	(segment
		(start 209.926682 -141.067536)
		(end 208.460594 -142.533624)
		(width 0.14605)
		(layer "B.Cu")
		(net "PCIE_COMP_TO_IOM_8_DP")
	)
	(segment
		(start 210.245198 -141.157198)
		(end 210.155536 -141.067536)
		(width 0.14605)
		(layer "B.Cu")
		(net "PCIE_COMP_TO_IOM_8_DP")
	)
	(segment
		(start 159.56788 -144.08658)
		(end 157.52445 -141.056868)
		(width 0.14605)
		(layer "B.Cu")
		(net "PCIE_COMP_TO_IOM_8_DP")
	)
	(segment
		(start 142.16253 -30.337506)
		(end 141.348206 -30.1752)
		(width 0.14605)
		(layer "B.Cu")
		(net "PCIE_COMP_TO_IOM_8_DP")
	)
	(arc
		(start 210.155536 -141.067536)
		(mid 210.041146 -141.020266)
		(end 209.926682 -141.067536)
		(width 0.14605)
		(layer "B.Cu")
		(net "PCIE_COMP_TO_IOM_8_DP")
	)
	(arc
		(start 140.555472 -32.327342)
		(mid 140.61908 -32.480904)
		(end 140.772642 -32.544512)
		(width 0.14605)
		(layer "B.Cu")
		(net "PCIE_COMP_TO_IOM_8_DP")
	)
	(arc
		(start 141.136624 -32.544512)
		(mid 141.25211 -32.496676)
		(end 141.299946 -32.38119)
		(width 0.14605)
		(layer "B.Cu")
		(net "PCIE_COMP_TO_IOM_8_DP")
	)
	(segment
		(start 209.26933 -139.05865)
		(end 206.737458 -136.527032)
		(width 0.14605)
		(layer "F.Cu")
		(net "PCIE_COMP_TO_IOM_8_DN")
	)
	(segment
		(start 209.484722 -139.05865)
		(end 209.26933 -139.05865)
		(width 0.14605)
		(layer "F.Cu")
		(net "PCIE_COMP_TO_IOM_8_DN")
	)
	(segment
		(start 206.649828 -135.71982)
		(end 206.649828 -134.875016)
		(width 0.14605)
		(layer "F.Cu")
		(net "PCIE_COMP_TO_IOM_8_DN")
	)
	(segment
		(start 209.616802 -140.528802)
		(end 209.706464 -140.618464)
		(width 0.14605)
		(layer "F.Cu")
		(net "PCIE_COMP_TO_IOM_8_DN")
	)
	(segment
		(start 206.737458 -136.527032)
		(end 206.737458 -135.80745)
		(width 0.14605)
		(layer "F.Cu")
		(net "PCIE_COMP_TO_IOM_8_DN")
	)
	(segment
		(start 210.15071 -139.724638)
		(end 209.484722 -139.05865)
		(width 0.14605)
		(layer "F.Cu")
		(net "PCIE_COMP_TO_IOM_8_DN")
	)
	(segment
		(start 206.737458 -135.80745)
		(end 206.649828 -135.71982)
		(width 0.14605)
		(layer "F.Cu")
		(net "PCIE_COMP_TO_IOM_8_DN")
	)
	(segment
		(start 209.935572 -140.618464)
		(end 210.15071 -140.403326)
		(width 0.14605)
		(layer "F.Cu")
		(net "PCIE_COMP_TO_IOM_8_DN")
	)
	(arc
		(start 209.706464 -140.618464)
		(mid 209.821018 -140.665914)
		(end 209.935572 -140.618464)
		(width 0.14605)
		(layer "F.Cu")
		(net "PCIE_COMP_TO_IOM_8_DN")
	)
	(arc
		(start 210.15071 -140.403326)
		(mid 210.291271 -140.063982)
		(end 210.15071 -139.724638)
		(width 0.14605)
		(layer "F.Cu")
		(net "PCIE_COMP_TO_IOM_8_DN")
	)
	(segment
		(start 140.244322 -30.28442)
		(end 140.244322 -32.327342)
		(width 0.14605)
		(layer "B.Cu")
		(net "PCIE_COMP_TO_IOM_8_DN")
	)
	(segment
		(start 208.261966 -142.291816)
		(end 204.543406 -144.780508)
		(width 0.14605)
		(layer "B.Cu")
		(net "PCIE_COMP_TO_IOM_8_DN")
	)
	(segment
		(start 141.299946 -33.018984)
		(end 141.299946 -33.399984)
		(width 0.14605)
		(layer "B.Cu")
		(net "PCIE_COMP_TO_IOM_8_DN")
	)
	(segment
		(start 155.00223 -126.453138)
		(end 160.447736 -98.441764)
		(width 0.14605)
		(layer "B.Cu")
		(net "PCIE_COMP_TO_IOM_8_DN")
	)
	(segment
		(start 160.447736 -98.441764)
		(end 149.6568 -47.413926)
		(width 0.14605)
		(layer "B.Cu")
		(net "PCIE_COMP_TO_IOM_8_DN")
	)
	(segment
		(start 142.352268 -30.057852)
		(end 141.37894 -29.86405)
		(width 0.14605)
		(layer "B.Cu")
		(net "PCIE_COMP_TO_IOM_8_DN")
	)
	(segment
		(start 140.772642 -32.855662)
		(end 141.136624 -32.855662)
		(width 0.14605)
		(layer "B.Cu")
		(net "PCIE_COMP_TO_IOM_8_DN")
	)
	(segment
		(start 157.818074 -140.935202)
		(end 155.00223 -126.453138)
		(width 0.14605)
		(layer "B.Cu")
		(net "PCIE_COMP_TO_IOM_8_DN")
	)
	(segment
		(start 204.543406 -144.780508)
		(end 179.338732 -149.679914)
		(width 0.14605)
		(layer "B.Cu")
		(net "PCIE_COMP_TO_IOM_8_DN")
	)
	(segment
		(start 147.742148 -38.359588)
		(end 142.352268 -30.057852)
		(width 0.14605)
		(layer "B.Cu")
		(net "PCIE_COMP_TO_IOM_8_DN")
	)
	(segment
		(start 179.338732 -149.679914)
		(end 163.997132 -146.698208)
		(width 0.14605)
		(layer "B.Cu")
		(net "PCIE_COMP_TO_IOM_8_DN")
	)
	(segment
		(start 149.6568 -47.413672)
		(end 147.742148 -38.359588)
		(width 0.14605)
		(layer "B.Cu")
		(net "PCIE_COMP_TO_IOM_8_DN")
	)
	(segment
		(start 149.6568 -47.413926)
		(end 149.6568 -47.413672)
		(width 0.14605)
		(layer "B.Cu")
		(net "PCIE_COMP_TO_IOM_8_DN")
	)
	(segment
		(start 209.616802 -140.528802)
		(end 209.706464 -140.618464)
		(width 0.14605)
		(layer "B.Cu")
		(net "PCIE_COMP_TO_IOM_8_DN")
	)
	(segment
		(start 141.37894 -29.86405)
		(end 140.664692 -29.86405)
		(width 0.14605)
		(layer "B.Cu")
		(net "PCIE_COMP_TO_IOM_8_DN")
	)
	(segment
		(start 209.706464 -140.847572)
		(end 209.49793 -141.055852)
		(width 0.14605)
		(layer "B.Cu")
		(net "PCIE_COMP_TO_IOM_8_DN")
	)
	(segment
		(start 209.49793 -141.055852)
		(end 208.261966 -142.291816)
		(width 0.14605)
		(layer "B.Cu")
		(net "PCIE_COMP_TO_IOM_8_DN")
	)
	(segment
		(start 159.792162 -143.862298)
		(end 157.818074 -140.935202)
		(width 0.14605)
		(layer "B.Cu")
		(net "PCIE_COMP_TO_IOM_8_DN")
	)
	(segment
		(start 163.997132 -146.698208)
		(end 159.792162 -143.862298)
		(width 0.14605)
		(layer "B.Cu")
		(net "PCIE_COMP_TO_IOM_8_DN")
	)
	(segment
		(start 140.664692 -29.86405)
		(end 140.244322 -30.28442)
		(width 0.14605)
		(layer "B.Cu")
		(net "PCIE_COMP_TO_IOM_8_DN")
	)
	(arc
		(start 140.244322 -32.327342)
		(mid 140.399063 -32.700921)
		(end 140.772642 -32.855662)
		(width 0.14605)
		(layer "B.Cu")
		(net "PCIE_COMP_TO_IOM_8_DN")
	)
	(arc
		(start 209.706464 -140.618464)
		(mid 209.753914 -140.733018)
		(end 209.706464 -140.847572)
		(width 0.14605)
		(layer "B.Cu")
		(net "PCIE_COMP_TO_IOM_8_DN")
	)
	(arc
		(start 141.136624 -32.855662)
		(mid 141.25211 -32.903498)
		(end 141.299946 -33.018984)
		(width 0.14605)
		(layer "B.Cu")
		(net "PCIE_COMP_TO_IOM_8_DN")
	)
	(segment
		(start 76.34859 -92.95003)
		(end 76.59878 -93.20022)
		(width 0.14605)
		(layer "F.Cu")
		(net "PCIE_COMP_TO_IOM_23_DP")
	)
	(segment
		(start 76.59878 -93.20022)
		(end 76.82738 -93.20022)
		(width 0.14605)
		(layer "F.Cu")
		(net "PCIE_COMP_TO_IOM_23_DP")
	)
	(segment
		(start 75.475084 -92.95003)
		(end 76.34859 -92.95003)
		(width 0.14605)
		(layer "F.Cu")
		(net "PCIE_COMP_TO_IOM_23_DP")
	)
	(arc
		(start 76.82738 -93.20022)
		(mid 77.09752 -93.121884)
		(end 77.283818 -92.911168)
		(width 0.14605)
		(layer "F.Cu")
		(net "PCIE_COMP_TO_IOM_23_DP")
	)
	(segment
		(start 98.065844 -47.129446)
		(end 98.926142 -51.411632)
		(width 0.14605)
		(layer "B.Cu")
		(net "PCIE_COMP_TO_IOM_23_DP")
	)
	(segment
		(start 86.623398 -92.878402)
		(end 85.6488 -93.853)
		(width 0.14605)
		(layer "B.Cu")
		(net "PCIE_COMP_TO_IOM_23_DP")
	)
	(segment
		(start 104.182672 -33.989264)
		(end 103.091234 -34.716466)
		(width 0.14605)
		(layer "B.Cu")
		(net "PCIE_COMP_TO_IOM_23_DP")
	)
	(segment
		(start 98.08718 -55.359808)
		(end 98.726752 -58.369454)
		(width 0.14605)
		(layer "B.Cu")
		(net "PCIE_COMP_TO_IOM_23_DP")
	)
	(segment
		(start 77.57287 -93.20022)
		(end 77.283818 -92.911168)
		(width 0.14605)
		(layer "B.Cu")
		(net "PCIE_COMP_TO_IOM_23_DP")
	)
	(segment
		(start 99.586288 -39.972742)
		(end 98.065844 -47.129446)
		(width 0.14605)
		(layer "B.Cu")
		(net "PCIE_COMP_TO_IOM_23_DP")
	)
	(segment
		(start 84.6328 -93.853)
		(end 84.3026 -93.5228)
		(width 0.14605)
		(layer "B.Cu")
		(net "PCIE_COMP_TO_IOM_23_DP")
	)
	(segment
		(start 98.726752 -58.369454)
		(end 94.971108 -76.036932)
		(width 0.14605)
		(layer "B.Cu")
		(net "PCIE_COMP_TO_IOM_23_DP")
	)
	(segment
		(start 105.375964 -33.750504)
		(end 104.182672 -33.989264)
		(width 0.14605)
		(layer "B.Cu")
		(net "PCIE_COMP_TO_IOM_23_DP")
	)
	(segment
		(start 84.3026 -93.5228)
		(end 84.3026 -92.8116)
		(width 0.14605)
		(layer "B.Cu")
		(net "PCIE_COMP_TO_IOM_23_DP")
	)
	(segment
		(start 105.405936 -33.744662)
		(end 105.375964 -33.750504)
		(width 0.14605)
		(layer "B.Cu")
		(net "PCIE_COMP_TO_IOM_23_DP")
	)
	(segment
		(start 89.633806 -84.257134)
		(end 88.374474 -90.181938)
		(width 0.14605)
		(layer "B.Cu")
		(net "PCIE_COMP_TO_IOM_23_DP")
	)
	(segment
		(start 83.5914 -92.1004)
		(end 79.8322 -92.1004)
		(width 0.14605)
		(layer "B.Cu")
		(net "PCIE_COMP_TO_IOM_23_DP")
	)
	(segment
		(start 78.73238 -93.20022)
		(end 77.57287 -93.20022)
		(width 0.14605)
		(layer "B.Cu")
		(net "PCIE_COMP_TO_IOM_23_DP")
	)
	(segment
		(start 79.8322 -92.1004)
		(end 78.73238 -93.20022)
		(width 0.14605)
		(layer "B.Cu")
		(net "PCIE_COMP_TO_IOM_23_DP")
	)
	(segment
		(start 98.926142 -51.411632)
		(end 98.310446 -54.30901)
		(width 0.14605)
		(layer "B.Cu")
		(net "PCIE_COMP_TO_IOM_23_DP")
	)
	(segment
		(start 88.374474 -90.181938)
		(end 86.623398 -92.878402)
		(width 0.14605)
		(layer "B.Cu")
		(net "PCIE_COMP_TO_IOM_23_DP")
	)
	(segment
		(start 103.091234 -34.716466)
		(end 99.586288 -39.972742)
		(width 0.14605)
		(layer "B.Cu")
		(net "PCIE_COMP_TO_IOM_23_DP")
	)
	(segment
		(start 98.310446 -54.30901)
		(end 98.08718 -55.359808)
		(width 0.14605)
		(layer "B.Cu")
		(net "PCIE_COMP_TO_IOM_23_DP")
	)
	(segment
		(start 106.93654 -33.744662)
		(end 105.405936 -33.744662)
		(width 0.14605)
		(layer "B.Cu")
		(net "PCIE_COMP_TO_IOM_23_DP")
	)
	(segment
		(start 94.971108 -76.036932)
		(end 89.633806 -84.257134)
		(width 0.14605)
		(layer "B.Cu")
		(net "PCIE_COMP_TO_IOM_23_DP")
	)
	(segment
		(start 84.3026 -92.8116)
		(end 83.5914 -92.1004)
		(width 0.14605)
		(layer "B.Cu")
		(net "PCIE_COMP_TO_IOM_23_DP")
	)
	(segment
		(start 85.6488 -93.853)
		(end 84.6328 -93.853)
		(width 0.14605)
		(layer "B.Cu")
		(net "PCIE_COMP_TO_IOM_23_DP")
	)
	(segment
		(start 107.099862 -33.200086)
		(end 107.099862 -33.581086)
		(width 0.14605)
		(layer "B.Cu")
		(net "PCIE_COMP_TO_IOM_23_DP")
	)
	(arc
		(start 107.099862 -33.581086)
		(mid 107.052041 -33.696662)
		(end 106.93654 -33.744662)
		(width 0.14605)
		(layer "B.Cu")
		(net "PCIE_COMP_TO_IOM_23_DP")
	)
	(segment
		(start 76.575158 -93.51137)
		(end 76.82738 -93.51137)
		(width 0.14605)
		(layer "F.Cu")
		(net "PCIE_COMP_TO_IOM_23_DN")
	)
	(segment
		(start 75.475084 -93.75013)
		(end 76.336398 -93.75013)
		(width 0.14605)
		(layer "F.Cu")
		(net "PCIE_COMP_TO_IOM_23_DN")
	)
	(segment
		(start 76.336398 -93.75013)
		(end 76.575158 -93.51137)
		(width 0.14605)
		(layer "F.Cu")
		(net "PCIE_COMP_TO_IOM_23_DN")
	)
	(arc
		(start 76.82738 -93.51137)
		(mid 77.097462 -93.589623)
		(end 77.283818 -93.800168)
		(width 0.14605)
		(layer "F.Cu")
		(net "PCIE_COMP_TO_IOM_23_DN")
	)
	(segment
		(start 107.099862 -34.600134)
		(end 107.099862 -34.219134)
		(width 0.14605)
		(layer "B.Cu")
		(net "PCIE_COMP_TO_IOM_23_DN")
	)
	(segment
		(start 106.93654 -34.055812)
		(end 105.436924 -34.055812)
		(width 0.14605)
		(layer "B.Cu")
		(net "PCIE_COMP_TO_IOM_23_DN")
	)
	(segment
		(start 104.304084 -34.28238)
		(end 103.315516 -34.941002)
		(width 0.14605)
		(layer "B.Cu")
		(net "PCIE_COMP_TO_IOM_23_DN")
	)
	(segment
		(start 103.315516 -34.941002)
		(end 99.878388 -40.095932)
		(width 0.14605)
		(layer "B.Cu")
		(net "PCIE_COMP_TO_IOM_23_DN")
	)
	(segment
		(start 89.92616 -84.378292)
		(end 88.666828 -90.303096)
		(width 0.14605)
		(layer "B.Cu")
		(net "PCIE_COMP_TO_IOM_23_DN")
	)
	(segment
		(start 83.462368 -92.41155)
		(end 79.961232 -92.41155)
		(width 0.14605)
		(layer "B.Cu")
		(net "PCIE_COMP_TO_IOM_23_DN")
	)
	(segment
		(start 95.263462 -76.15809)
		(end 89.92616 -84.378292)
		(width 0.14605)
		(layer "B.Cu")
		(net "PCIE_COMP_TO_IOM_23_DN")
	)
	(segment
		(start 98.383598 -47.131224)
		(end 99.243896 -51.41341)
		(width 0.14605)
		(layer "B.Cu")
		(net "PCIE_COMP_TO_IOM_23_DN")
	)
	(segment
		(start 83.99145 -92.940632)
		(end 83.462368 -92.41155)
		(width 0.14605)
		(layer "B.Cu")
		(net "PCIE_COMP_TO_IOM_23_DN")
	)
	(segment
		(start 99.878388 -40.095932)
		(end 98.383598 -47.131224)
		(width 0.14605)
		(layer "B.Cu")
		(net "PCIE_COMP_TO_IOM_23_DN")
	)
	(segment
		(start 99.243896 -51.41341)
		(end 98.405442 -55.359808)
		(width 0.14605)
		(layer "B.Cu")
		(net "PCIE_COMP_TO_IOM_23_DN")
	)
	(segment
		(start 105.436924 -34.055812)
		(end 104.304084 -34.28238)
		(width 0.14605)
		(layer "B.Cu")
		(net "PCIE_COMP_TO_IOM_23_DN")
	)
	(segment
		(start 85.777832 -94.16415)
		(end 84.503768 -94.16415)
		(width 0.14605)
		(layer "B.Cu")
		(net "PCIE_COMP_TO_IOM_23_DN")
	)
	(segment
		(start 88.666828 -90.303096)
		(end 86.86673 -93.075506)
		(width 0.14605)
		(layer "B.Cu")
		(net "PCIE_COMP_TO_IOM_23_DN")
	)
	(segment
		(start 98.405442 -55.359808)
		(end 99.045014 -58.369454)
		(width 0.14605)
		(layer "B.Cu")
		(net "PCIE_COMP_TO_IOM_23_DN")
	)
	(segment
		(start 86.86673 -93.075506)
		(end 85.777832 -94.16415)
		(width 0.14605)
		(layer "B.Cu")
		(net "PCIE_COMP_TO_IOM_23_DN")
	)
	(segment
		(start 79.961232 -92.41155)
		(end 78.861412 -93.51137)
		(width 0.14605)
		(layer "B.Cu")
		(net "PCIE_COMP_TO_IOM_23_DN")
	)
	(segment
		(start 84.503768 -94.16415)
		(end 83.99145 -93.651832)
		(width 0.14605)
		(layer "B.Cu")
		(net "PCIE_COMP_TO_IOM_23_DN")
	)
	(segment
		(start 77.572616 -93.51137)
		(end 77.283818 -93.800168)
		(width 0.14605)
		(layer "B.Cu")
		(net "PCIE_COMP_TO_IOM_23_DN")
	)
	(segment
		(start 99.045014 -58.369454)
		(end 95.263462 -76.15809)
		(width 0.14605)
		(layer "B.Cu")
		(net "PCIE_COMP_TO_IOM_23_DN")
	)
	(segment
		(start 83.99145 -93.651832)
		(end 83.99145 -92.940632)
		(width 0.14605)
		(layer "B.Cu")
		(net "PCIE_COMP_TO_IOM_23_DN")
	)
	(segment
		(start 78.861412 -93.51137)
		(end 77.572616 -93.51137)
		(width 0.14605)
		(layer "B.Cu")
		(net "PCIE_COMP_TO_IOM_23_DN")
	)
	(arc
		(start 107.099862 -34.219134)
		(mid 107.052026 -34.103648)
		(end 106.93654 -34.055812)
		(width 0.14605)
		(layer "B.Cu")
		(net "PCIE_COMP_TO_IOM_23_DN")
	)
	(segment
		(start 77.424534 -89.99982)
		(end 77.424788 -89.999566)
		(width 0.14605)
		(layer "F.Cu")
		(net "PCIE_COMP_TO_IOM_22_DP")
	)
	(segment
		(start 75.475084 -89.750138)
		(end 76.575412 -89.750138)
		(width 0.14605)
		(layer "F.Cu")
		(net "PCIE_COMP_TO_IOM_22_DP")
	)
	(segment
		(start 76.825094 -89.99982)
		(end 77.424534 -89.99982)
		(width 0.14605)
		(layer "F.Cu")
		(net "PCIE_COMP_TO_IOM_22_DP")
	)
	(segment
		(start 76.575412 -89.750138)
		(end 76.825094 -89.99982)
		(width 0.14605)
		(layer "F.Cu")
		(net "PCIE_COMP_TO_IOM_22_DP")
	)
	(arc
		(start 77.424788 -89.999566)
		(mid 77.802125 -89.924509)
		(end 78.122018 -89.710768)
		(width 0.14605)
		(layer "F.Cu")
		(net "PCIE_COMP_TO_IOM_22_DP")
	)
	(segment
		(start 86.46795 -88.71585)
		(end 85.40115 -88.71585)
		(width 0.14605)
		(layer "B.Cu")
		(net "PCIE_COMP_TO_IOM_22_DP")
	)
	(segment
		(start 108.155486 -32.327342)
		(end 108.155486 -31.507684)
		(width 0.14605)
		(layer "B.Cu")
		(net "PCIE_COMP_TO_IOM_22_DP")
	)
	(segment
		(start 97.45091 -58.381138)
		(end 93.848682 -75.632056)
		(width 0.14605)
		(layer "B.Cu")
		(net "PCIE_COMP_TO_IOM_22_DP")
	)
	(segment
		(start 108.155486 -31.507684)
		(end 107.514136 -30.866334)
		(width 0.14605)
		(layer "B.Cu")
		(net "PCIE_COMP_TO_IOM_22_DP")
	)
	(segment
		(start 83.4644 -90.6526)
		(end 80.4926 -90.6526)
		(width 0.14605)
		(layer "B.Cu")
		(net "PCIE_COMP_TO_IOM_22_DP")
	)
	(segment
		(start 106.477562 -30.961838)
		(end 105.97007 -31.063438)
		(width 0.14605)
		(layer "B.Cu")
		(net "PCIE_COMP_TO_IOM_22_DP")
	)
	(segment
		(start 85.40115 -88.71585)
		(end 83.4644 -90.6526)
		(width 0.14605)
		(layer "B.Cu")
		(net "PCIE_COMP_TO_IOM_22_DP")
	)
	(segment
		(start 106.955336 -30.866334)
		(end 106.925364 -30.872176)
		(width 0.14605)
		(layer "B.Cu")
		(net "PCIE_COMP_TO_IOM_22_DP")
	)
	(segment
		(start 79.83982 -89.99982)
		(end 78.41107 -89.99982)
		(width 0.14605)
		(layer "B.Cu")
		(net "PCIE_COMP_TO_IOM_22_DP")
	)
	(segment
		(start 98.482912 -39.460932)
		(end 96.863408 -47.078646)
		(width 0.14605)
		(layer "B.Cu")
		(net "PCIE_COMP_TO_IOM_22_DP")
	)
	(segment
		(start 88.501474 -83.86699)
		(end 87.82812 -87.036148)
		(width 0.14605)
		(layer "B.Cu")
		(net "PCIE_COMP_TO_IOM_22_DP")
	)
	(segment
		(start 96.863408 -47.078646)
		(end 97.738438 -51.41722)
		(width 0.14605)
		(layer "B.Cu")
		(net "PCIE_COMP_TO_IOM_22_DP")
	)
	(segment
		(start 105.97007 -31.063438)
		(end 102.579932 -33.314894)
		(width 0.14605)
		(layer "B.Cu")
		(net "PCIE_COMP_TO_IOM_22_DP")
	)
	(segment
		(start 108.736638 -32.544512)
		(end 108.372656 -32.544512)
		(width 0.14605)
		(layer "B.Cu")
		(net "PCIE_COMP_TO_IOM_22_DP")
	)
	(segment
		(start 80.4926 -90.6526)
		(end 79.83982 -89.99982)
		(width 0.14605)
		(layer "B.Cu")
		(net "PCIE_COMP_TO_IOM_22_DP")
	)
	(segment
		(start 108.89996 -32.00019)
		(end 108.89996 -32.38119)
		(width 0.14605)
		(layer "B.Cu")
		(net "PCIE_COMP_TO_IOM_22_DP")
	)
	(segment
		(start 96.854264 -55.57774)
		(end 97.45091 -58.381138)
		(width 0.14605)
		(layer "B.Cu")
		(net "PCIE_COMP_TO_IOM_22_DP")
	)
	(segment
		(start 87.23503 -87.94877)
		(end 86.46795 -88.71585)
		(width 0.14605)
		(layer "B.Cu")
		(net "PCIE_COMP_TO_IOM_22_DP")
	)
	(segment
		(start 87.82812 -87.036148)
		(end 87.23503 -87.94877)
		(width 0.14605)
		(layer "B.Cu")
		(net "PCIE_COMP_TO_IOM_22_DP")
	)
	(segment
		(start 106.925364 -30.872176)
		(end 106.477562 -30.961838)
		(width 0.14605)
		(layer "B.Cu")
		(net "PCIE_COMP_TO_IOM_22_DP")
	)
	(segment
		(start 102.579932 -33.314894)
		(end 98.482912 -39.460932)
		(width 0.14605)
		(layer "B.Cu")
		(net "PCIE_COMP_TO_IOM_22_DP")
	)
	(segment
		(start 93.848682 -75.632056)
		(end 88.501474 -83.86699)
		(width 0.14605)
		(layer "B.Cu")
		(net "PCIE_COMP_TO_IOM_22_DP")
	)
	(segment
		(start 97.738438 -51.41722)
		(end 96.854264 -55.57774)
		(width 0.14605)
		(layer "B.Cu")
		(net "PCIE_COMP_TO_IOM_22_DP")
	)
	(segment
		(start 78.41107 -89.99982)
		(end 78.122018 -89.710768)
		(width 0.14605)
		(layer "B.Cu")
		(net "PCIE_COMP_TO_IOM_22_DP")
	)
	(segment
		(start 107.514136 -30.866334)
		(end 106.955336 -30.866334)
		(width 0.14605)
		(layer "B.Cu")
		(net "PCIE_COMP_TO_IOM_22_DP")
	)
	(arc
		(start 108.372656 -32.544512)
		(mid 108.219094 -32.480904)
		(end 108.155486 -32.327342)
		(width 0.14605)
		(layer "B.Cu")
		(net "PCIE_COMP_TO_IOM_22_DP")
	)
	(arc
		(start 108.89996 -32.38119)
		(mid 108.852124 -32.496676)
		(end 108.736638 -32.544512)
		(width 0.14605)
		(layer "B.Cu")
		(net "PCIE_COMP_TO_IOM_22_DP")
	)
	(segment
		(start 76.604622 -90.549984)
		(end 76.843636 -90.31097)
		(width 0.14605)
		(layer "F.Cu")
		(net "PCIE_COMP_TO_IOM_22_DN")
	)
	(segment
		(start 76.843636 -90.31097)
		(end 77.424788 -90.31097)
		(width 0.14605)
		(layer "F.Cu")
		(net "PCIE_COMP_TO_IOM_22_DN")
	)
	(segment
		(start 75.475084 -90.549984)
		(end 76.604622 -90.549984)
		(width 0.14605)
		(layer "F.Cu")
		(net "PCIE_COMP_TO_IOM_22_DN")
	)
	(arc
		(start 77.424788 -90.31097)
		(mid 77.802125 -90.386027)
		(end 78.122018 -90.599768)
		(width 0.14605)
		(layer "F.Cu")
		(net "PCIE_COMP_TO_IOM_22_DN")
	)
	(segment
		(start 94.141544 -75.752706)
		(end 88.793828 -83.988148)
		(width 0.14605)
		(layer "B.Cu")
		(net "PCIE_COMP_TO_IOM_22_DN")
	)
	(segment
		(start 85.530182 -89.027)
		(end 83.593432 -90.96375)
		(width 0.14605)
		(layer "B.Cu")
		(net "PCIE_COMP_TO_IOM_22_DN")
	)
	(segment
		(start 106.986324 -31.177484)
		(end 106.091228 -31.356554)
		(width 0.14605)
		(layer "B.Cu")
		(net "PCIE_COMP_TO_IOM_22_DN")
	)
	(segment
		(start 108.736638 -32.855662)
		(end 108.372656 -32.855662)
		(width 0.14605)
		(layer "B.Cu")
		(net "PCIE_COMP_TO_IOM_22_DN")
	)
	(segment
		(start 98.775012 -39.584122)
		(end 97.181416 -47.080424)
		(width 0.14605)
		(layer "B.Cu")
		(net "PCIE_COMP_TO_IOM_22_DN")
	)
	(segment
		(start 97.173034 -55.575454)
		(end 97.768918 -58.38063)
		(width 0.14605)
		(layer "B.Cu")
		(net "PCIE_COMP_TO_IOM_22_DN")
	)
	(segment
		(start 108.89996 -33.399984)
		(end 108.89996 -33.018984)
		(width 0.14605)
		(layer "B.Cu")
		(net "PCIE_COMP_TO_IOM_22_DN")
	)
	(segment
		(start 98.056446 -51.418998)
		(end 97.173034 -55.575454)
		(width 0.14605)
		(layer "B.Cu")
		(net "PCIE_COMP_TO_IOM_22_DN")
	)
	(segment
		(start 88.120474 -87.157306)
		(end 87.478362 -88.145874)
		(width 0.14605)
		(layer "B.Cu")
		(net "PCIE_COMP_TO_IOM_22_DN")
	)
	(segment
		(start 86.596982 -89.027)
		(end 85.530182 -89.027)
		(width 0.14605)
		(layer "B.Cu")
		(net "PCIE_COMP_TO_IOM_22_DN")
	)
	(segment
		(start 80.363568 -90.96375)
		(end 79.710788 -90.31097)
		(width 0.14605)
		(layer "B.Cu")
		(net "PCIE_COMP_TO_IOM_22_DN")
	)
	(segment
		(start 83.593432 -90.96375)
		(end 80.363568 -90.96375)
		(width 0.14605)
		(layer "B.Cu")
		(net "PCIE_COMP_TO_IOM_22_DN")
	)
	(segment
		(start 79.710788 -90.31097)
		(end 78.410816 -90.31097)
		(width 0.14605)
		(layer "B.Cu")
		(net "PCIE_COMP_TO_IOM_22_DN")
	)
	(segment
		(start 107.385104 -31.177484)
		(end 106.986324 -31.177484)
		(width 0.14605)
		(layer "B.Cu")
		(net "PCIE_COMP_TO_IOM_22_DN")
	)
	(segment
		(start 97.768918 -58.38063)
		(end 94.141544 -75.752706)
		(width 0.14605)
		(layer "B.Cu")
		(net "PCIE_COMP_TO_IOM_22_DN")
	)
	(segment
		(start 97.181416 -47.080424)
		(end 98.056446 -51.418998)
		(width 0.14605)
		(layer "B.Cu")
		(net "PCIE_COMP_TO_IOM_22_DN")
	)
	(segment
		(start 106.091228 -31.356554)
		(end 102.804214 -33.539684)
		(width 0.14605)
		(layer "B.Cu")
		(net "PCIE_COMP_TO_IOM_22_DN")
	)
	(segment
		(start 78.410816 -90.31097)
		(end 78.122018 -90.599768)
		(width 0.14605)
		(layer "B.Cu")
		(net "PCIE_COMP_TO_IOM_22_DN")
	)
	(segment
		(start 87.478362 -88.145874)
		(end 86.596982 -89.027)
		(width 0.14605)
		(layer "B.Cu")
		(net "PCIE_COMP_TO_IOM_22_DN")
	)
	(segment
		(start 107.844336 -31.636716)
		(end 107.385104 -31.177484)
		(width 0.14605)
		(layer "B.Cu")
		(net "PCIE_COMP_TO_IOM_22_DN")
	)
	(segment
		(start 107.844336 -32.327342)
		(end 107.844336 -31.636716)
		(width 0.14605)
		(layer "B.Cu")
		(net "PCIE_COMP_TO_IOM_22_DN")
	)
	(segment
		(start 102.804214 -33.539684)
		(end 98.775012 -39.584122)
		(width 0.14605)
		(layer "B.Cu")
		(net "PCIE_COMP_TO_IOM_22_DN")
	)
	(segment
		(start 88.793828 -83.988148)
		(end 88.120474 -87.157306)
		(width 0.14605)
		(layer "B.Cu")
		(net "PCIE_COMP_TO_IOM_22_DN")
	)
	(arc
		(start 108.89996 -33.018984)
		(mid 108.852124 -32.903498)
		(end 108.736638 -32.855662)
		(width 0.14605)
		(layer "B.Cu")
		(net "PCIE_COMP_TO_IOM_22_DN")
	)
	(arc
		(start 108.372656 -32.855662)
		(mid 107.999077 -32.700921)
		(end 107.844336 -32.327342)
		(width 0.14605)
		(layer "B.Cu")
		(net "PCIE_COMP_TO_IOM_22_DN")
	)
	(segment
		(start 76.349352 -86.549992)
		(end 76.59878 -86.79942)
		(width 0.14605)
		(layer "F.Cu")
		(net "PCIE_COMP_TO_IOM_21_DP")
	)
	(segment
		(start 76.59878 -86.79942)
		(end 76.82738 -86.79942)
		(width 0.14605)
		(layer "F.Cu")
		(net "PCIE_COMP_TO_IOM_21_DP")
	)
	(segment
		(start 75.475084 -86.549992)
		(end 76.349352 -86.549992)
		(width 0.14605)
		(layer "F.Cu")
		(net "PCIE_COMP_TO_IOM_21_DP")
	)
	(arc
		(start 76.82738 -86.79942)
		(mid 77.09752 -86.721084)
		(end 77.283818 -86.510368)
		(width 0.14605)
		(layer "F.Cu")
		(net "PCIE_COMP_TO_IOM_21_DP")
	)
	(segment
		(start 84.46135 -86.840568)
		(end 83.574382 -85.9536)
		(width 0.14605)
		(layer "B.Cu")
		(net "PCIE_COMP_TO_IOM_21_DP")
	)
	(segment
		(start 96.179386 -58.664348)
		(end 96.179132 -58.664348)
		(width 0.14605)
		(layer "B.Cu")
		(net "PCIE_COMP_TO_IOM_21_DP")
	)
	(segment
		(start 84.46135 -87.272368)
		(end 84.46135 -86.840568)
		(width 0.14605)
		(layer "B.Cu")
		(net "PCIE_COMP_TO_IOM_21_DP")
	)
	(segment
		(start 96.179132 -58.664348)
		(end 92.738448 -75.163172)
		(width 0.14605)
		(layer "B.Cu")
		(net "PCIE_COMP_TO_IOM_21_DP")
	)
	(segment
		(start 95.602298 -55.950358)
		(end 96.179386 -58.664348)
		(width 0.14605)
		(layer "B.Cu")
		(net "PCIE_COMP_TO_IOM_21_DP")
	)
	(segment
		(start 84.761832 -87.57285)
		(end 84.46135 -87.272368)
		(width 0.14605)
		(layer "B.Cu")
		(net "PCIE_COMP_TO_IOM_21_DP")
	)
	(segment
		(start 86.941406 -85.515958)
		(end 86.18855 -86.675468)
		(width 0.14605)
		(layer "B.Cu")
		(net "PCIE_COMP_TO_IOM_21_DP")
	)
	(segment
		(start 109.955584 -33.520126)
		(end 109.955584 -30.413452)
		(width 0.14605)
		(layer "B.Cu")
		(net "PCIE_COMP_TO_IOM_21_DP")
	)
	(segment
		(start 87.393526 -83.390486)
		(end 86.941406 -85.515958)
		(width 0.14605)
		(layer "B.Cu")
		(net "PCIE_COMP_TO_IOM_21_DP")
	)
	(segment
		(start 110.536482 -33.744662)
		(end 110.18012 -33.744662)
		(width 0.14605)
		(layer "B.Cu")
		(net "PCIE_COMP_TO_IOM_21_DP")
	)
	(segment
		(start 97.402142 -38.85565)
		(end 95.670624 -47.0027)
		(width 0.14605)
		(layer "B.Cu")
		(net "PCIE_COMP_TO_IOM_21_DP")
	)
	(segment
		(start 83.574382 -85.9536)
		(end 79.628746 -85.9536)
		(width 0.14605)
		(layer "B.Cu")
		(net "PCIE_COMP_TO_IOM_21_DP")
	)
	(segment
		(start 92.738448 -75.163172)
		(end 87.393526 -83.390486)
		(width 0.14605)
		(layer "B.Cu")
		(net "PCIE_COMP_TO_IOM_21_DP")
	)
	(segment
		(start 77.56525 -86.7918)
		(end 77.283818 -86.510368)
		(width 0.14605)
		(layer "B.Cu")
		(net "PCIE_COMP_TO_IOM_21_DP")
	)
	(segment
		(start 96.568006 -51.40706)
		(end 95.602298 -55.950358)
		(width 0.14605)
		(layer "B.Cu")
		(net "PCIE_COMP_TO_IOM_21_DP")
	)
	(segment
		(start 109.955584 -30.413452)
		(end 109.25429 -29.712158)
		(width 0.14605)
		(layer "B.Cu")
		(net "PCIE_COMP_TO_IOM_21_DP")
	)
	(segment
		(start 106.355642 -29.712158)
		(end 104.74198 -30.034738)
		(width 0.14605)
		(layer "B.Cu")
		(net "PCIE_COMP_TO_IOM_21_DP")
	)
	(segment
		(start 110.700058 -33.200086)
		(end 110.700058 -33.581086)
		(width 0.14605)
		(layer "B.Cu")
		(net "PCIE_COMP_TO_IOM_21_DP")
	)
	(segment
		(start 102.087934 -31.804864)
		(end 97.402142 -38.85565)
		(width 0.14605)
		(layer "B.Cu")
		(net "PCIE_COMP_TO_IOM_21_DP")
	)
	(segment
		(start 86.18855 -86.675468)
		(end 85.291168 -87.57285)
		(width 0.14605)
		(layer "B.Cu")
		(net "PCIE_COMP_TO_IOM_21_DP")
	)
	(segment
		(start 79.628746 -85.9536)
		(end 78.7908 -86.7918)
		(width 0.14605)
		(layer "B.Cu")
		(net "PCIE_COMP_TO_IOM_21_DP")
	)
	(segment
		(start 104.74198 -30.034738)
		(end 102.087934 -31.804864)
		(width 0.14605)
		(layer "B.Cu")
		(net "PCIE_COMP_TO_IOM_21_DP")
	)
	(segment
		(start 85.291168 -87.57285)
		(end 84.761832 -87.57285)
		(width 0.14605)
		(layer "B.Cu")
		(net "PCIE_COMP_TO_IOM_21_DP")
	)
	(segment
		(start 109.25429 -29.712158)
		(end 106.355642 -29.712158)
		(width 0.14605)
		(layer "B.Cu")
		(net "PCIE_COMP_TO_IOM_21_DP")
	)
	(segment
		(start 95.670624 -47.0027)
		(end 96.568006 -51.40706)
		(width 0.14605)
		(layer "B.Cu")
		(net "PCIE_COMP_TO_IOM_21_DP")
	)
	(segment
		(start 78.7908 -86.7918)
		(end 77.56525 -86.7918)
		(width 0.14605)
		(layer "B.Cu")
		(net "PCIE_COMP_TO_IOM_21_DP")
	)
	(arc
		(start 110.18012 -33.744662)
		(mid 110.021349 -33.678897)
		(end 109.955584 -33.520126)
		(width 0.14605)
		(layer "B.Cu")
		(net "PCIE_COMP_TO_IOM_21_DP")
	)
	(arc
		(start 110.700058 -33.581086)
		(mid 110.652148 -33.696752)
		(end 110.536482 -33.744662)
		(width 0.14605)
		(layer "B.Cu")
		(net "PCIE_COMP_TO_IOM_21_DP")
	)
	(segment
		(start 75.475084 -87.350092)
		(end 76.335636 -87.350092)
		(width 0.14605)
		(layer "F.Cu")
		(net "PCIE_COMP_TO_IOM_21_DN")
	)
	(segment
		(start 76.575158 -87.11057)
		(end 76.82738 -87.11057)
		(width 0.14605)
		(layer "F.Cu")
		(net "PCIE_COMP_TO_IOM_21_DN")
	)
	(segment
		(start 76.335636 -87.350092)
		(end 76.575158 -87.11057)
		(width 0.14605)
		(layer "F.Cu")
		(net "PCIE_COMP_TO_IOM_21_DN")
	)
	(arc
		(start 76.82738 -87.11057)
		(mid 77.097462 -87.188823)
		(end 77.283818 -87.399368)
		(width 0.14605)
		(layer "F.Cu")
		(net "PCIE_COMP_TO_IOM_21_DN")
	)
	(segment
		(start 95.988632 -47.00397)
		(end 96.886014 -51.40833)
		(width 0.14605)
		(layer "B.Cu")
		(net "PCIE_COMP_TO_IOM_21_DN")
	)
	(segment
		(start 85.4202 -87.884)
		(end 84.6328 -87.884)
		(width 0.14605)
		(layer "B.Cu")
		(net "PCIE_COMP_TO_IOM_21_DN")
	)
	(segment
		(start 93.03131 -75.283822)
		(end 87.68588 -83.511644)
		(width 0.14605)
		(layer "B.Cu")
		(net "PCIE_COMP_TO_IOM_21_DN")
	)
	(segment
		(start 109.125258 -30.023308)
		(end 106.38663 -30.023308)
		(width 0.14605)
		(layer "B.Cu")
		(net "PCIE_COMP_TO_IOM_21_DN")
	)
	(segment
		(start 77.580236 -87.10295)
		(end 77.283818 -87.399368)
		(width 0.14605)
		(layer "B.Cu")
		(net "PCIE_COMP_TO_IOM_21_DN")
	)
	(segment
		(start 87.23376 -85.637116)
		(end 86.431882 -86.872572)
		(width 0.14605)
		(layer "B.Cu")
		(net "PCIE_COMP_TO_IOM_21_DN")
	)
	(segment
		(start 78.919832 -87.10295)
		(end 77.580236 -87.10295)
		(width 0.14605)
		(layer "B.Cu")
		(net "PCIE_COMP_TO_IOM_21_DN")
	)
	(segment
		(start 87.68588 -83.511644)
		(end 87.23376 -85.637116)
		(width 0.14605)
		(layer "B.Cu")
		(net "PCIE_COMP_TO_IOM_21_DN")
	)
	(segment
		(start 86.431882 -86.872572)
		(end 85.4202 -87.884)
		(width 0.14605)
		(layer "B.Cu")
		(net "PCIE_COMP_TO_IOM_21_DN")
	)
	(segment
		(start 84.1502 -87.4014)
		(end 84.1502 -86.9696)
		(width 0.14605)
		(layer "B.Cu")
		(net "PCIE_COMP_TO_IOM_21_DN")
	)
	(segment
		(start 110.700058 -34.600134)
		(end 110.700058 -34.219134)
		(width 0.14605)
		(layer "B.Cu")
		(net "PCIE_COMP_TO_IOM_21_DN")
	)
	(segment
		(start 104.863392 -30.327854)
		(end 102.312724 -32.029146)
		(width 0.14605)
		(layer "B.Cu")
		(net "PCIE_COMP_TO_IOM_21_DN")
	)
	(segment
		(start 96.886014 -51.40833)
		(end 95.92056 -55.950358)
		(width 0.14605)
		(layer "B.Cu")
		(net "PCIE_COMP_TO_IOM_21_DN")
	)
	(segment
		(start 102.312724 -32.029146)
		(end 97.694242 -38.978332)
		(width 0.14605)
		(layer "B.Cu")
		(net "PCIE_COMP_TO_IOM_21_DN")
	)
	(segment
		(start 109.644434 -33.520126)
		(end 109.644434 -30.542484)
		(width 0.14605)
		(layer "B.Cu")
		(net "PCIE_COMP_TO_IOM_21_DN")
	)
	(segment
		(start 84.1502 -86.9696)
		(end 83.44535 -86.26475)
		(width 0.14605)
		(layer "B.Cu")
		(net "PCIE_COMP_TO_IOM_21_DN")
	)
	(segment
		(start 106.38663 -30.023308)
		(end 104.863392 -30.327854)
		(width 0.14605)
		(layer "B.Cu")
		(net "PCIE_COMP_TO_IOM_21_DN")
	)
	(segment
		(start 97.694242 -38.978332)
		(end 95.988632 -47.00397)
		(width 0.14605)
		(layer "B.Cu")
		(net "PCIE_COMP_TO_IOM_21_DN")
	)
	(segment
		(start 109.644434 -30.542484)
		(end 109.125258 -30.023308)
		(width 0.14605)
		(layer "B.Cu")
		(net "PCIE_COMP_TO_IOM_21_DN")
	)
	(segment
		(start 96.497394 -58.66384)
		(end 93.03131 -75.283822)
		(width 0.14605)
		(layer "B.Cu")
		(net "PCIE_COMP_TO_IOM_21_DN")
	)
	(segment
		(start 95.92056 -55.950358)
		(end 96.497394 -58.66384)
		(width 0.14605)
		(layer "B.Cu")
		(net "PCIE_COMP_TO_IOM_21_DN")
	)
	(segment
		(start 84.6328 -87.884)
		(end 84.1502 -87.4014)
		(width 0.14605)
		(layer "B.Cu")
		(net "PCIE_COMP_TO_IOM_21_DN")
	)
	(segment
		(start 83.44535 -86.26475)
		(end 79.757778 -86.26475)
		(width 0.14605)
		(layer "B.Cu")
		(net "PCIE_COMP_TO_IOM_21_DN")
	)
	(segment
		(start 110.536736 -34.055812)
		(end 110.18012 -34.055812)
		(width 0.14605)
		(layer "B.Cu")
		(net "PCIE_COMP_TO_IOM_21_DN")
	)
	(segment
		(start 79.757778 -86.26475)
		(end 78.919832 -87.10295)
		(width 0.14605)
		(layer "B.Cu")
		(net "PCIE_COMP_TO_IOM_21_DN")
	)
	(arc
		(start 110.700058 -34.219134)
		(mid 110.652222 -34.103648)
		(end 110.536736 -34.055812)
		(width 0.14605)
		(layer "B.Cu")
		(net "PCIE_COMP_TO_IOM_21_DN")
	)
	(arc
		(start 110.18012 -34.055812)
		(mid 109.801333 -33.898913)
		(end 109.644434 -33.520126)
		(width 0.14605)
		(layer "B.Cu")
		(net "PCIE_COMP_TO_IOM_21_DN")
	)
	(segment
		(start 76.576174 -83.3501)
		(end 76.825094 -83.59902)
		(width 0.14605)
		(layer "F.Cu")
		(net "PCIE_COMP_TO_IOM_20_DP")
	)
	(segment
		(start 77.424534 -83.59902)
		(end 77.424788 -83.598766)
		(width 0.14605)
		(layer "F.Cu")
		(net "PCIE_COMP_TO_IOM_20_DP")
	)
	(segment
		(start 76.825094 -83.59902)
		(end 77.424534 -83.59902)
		(width 0.14605)
		(layer "F.Cu")
		(net "PCIE_COMP_TO_IOM_20_DP")
	)
	(segment
		(start 75.475084 -83.3501)
		(end 76.576174 -83.3501)
		(width 0.14605)
		(layer "F.Cu")
		(net "PCIE_COMP_TO_IOM_20_DP")
	)
	(arc
		(start 77.424788 -83.598766)
		(mid 77.802125 -83.523709)
		(end 78.122018 -83.309968)
		(width 0.14605)
		(layer "F.Cu")
		(net "PCIE_COMP_TO_IOM_20_DP")
	)
	(segment
		(start 91.652852 -74.608436)
		(end 87.336376 -81.268824)
		(width 0.14605)
		(layer "B.Cu")
		(net "PCIE_COMP_TO_IOM_20_DP")
	)
	(segment
		(start 80.4926 -84.201)
		(end 79.890366 -83.598766)
		(width 0.14605)
		(layer "B.Cu")
		(net "PCIE_COMP_TO_IOM_20_DP")
	)
	(segment
		(start 112.499902 -32.00019)
		(end 112.499902 -32.38119)
		(width 0.14605)
		(layer "B.Cu")
		(net "PCIE_COMP_TO_IOM_20_DP")
	)
	(segment
		(start 111.755682 -32.327596)
		(end 111.755682 -30.582108)
		(width 0.14605)
		(layer "B.Cu")
		(net "PCIE_COMP_TO_IOM_20_DP")
	)
	(segment
		(start 109.723174 -28.5496)
		(end 106.003598 -28.5496)
		(width 0.14605)
		(layer "B.Cu")
		(net "PCIE_COMP_TO_IOM_20_DP")
	)
	(segment
		(start 95.389954 -51.435)
		(end 94.336362 -56.391302)
		(width 0.14605)
		(layer "B.Cu")
		(net "PCIE_COMP_TO_IOM_20_DP")
	)
	(segment
		(start 101.640894 -30.38348)
		(end 96.323404 -38.369748)
		(width 0.14605)
		(layer "B.Cu")
		(net "PCIE_COMP_TO_IOM_20_DP")
	)
	(segment
		(start 83.438746 -84.201)
		(end 80.4926 -84.201)
		(width 0.14605)
		(layer "B.Cu")
		(net "PCIE_COMP_TO_IOM_20_DP")
	)
	(segment
		(start 94.336362 -56.391302)
		(end 94.89567 -59.022742)
		(width 0.14605)
		(layer "B.Cu")
		(net "PCIE_COMP_TO_IOM_20_DP")
	)
	(segment
		(start 112.33658 -32.544512)
		(end 111.972598 -32.544512)
		(width 0.14605)
		(layer "B.Cu")
		(net "PCIE_COMP_TO_IOM_20_DP")
	)
	(segment
		(start 111.755682 -30.582108)
		(end 109.723174 -28.5496)
		(width 0.14605)
		(layer "B.Cu")
		(net "PCIE_COMP_TO_IOM_20_DP")
	)
	(segment
		(start 94.89567 -59.022742)
		(end 91.652852 -74.608436)
		(width 0.14605)
		(layer "B.Cu")
		(net "PCIE_COMP_TO_IOM_20_DP")
	)
	(segment
		(start 94.490032 -46.991016)
		(end 95.389954 -51.435)
		(width 0.14605)
		(layer "B.Cu")
		(net "PCIE_COMP_TO_IOM_20_DP")
	)
	(segment
		(start 87.336376 -81.268824)
		(end 85.852 -82.7532)
		(width 0.14605)
		(layer "B.Cu")
		(net "PCIE_COMP_TO_IOM_20_DP")
	)
	(segment
		(start 84.887054 -82.7532)
		(end 83.438746 -84.201)
		(width 0.14605)
		(layer "B.Cu")
		(net "PCIE_COMP_TO_IOM_20_DP")
	)
	(segment
		(start 103.661972 -29.035756)
		(end 101.640894 -30.38348)
		(width 0.14605)
		(layer "B.Cu")
		(net "PCIE_COMP_TO_IOM_20_DP")
	)
	(segment
		(start 96.323404 -38.369748)
		(end 94.490032 -46.991016)
		(width 0.14605)
		(layer "B.Cu")
		(net "PCIE_COMP_TO_IOM_20_DP")
	)
	(segment
		(start 78.410816 -83.598766)
		(end 78.122018 -83.309968)
		(width 0.14605)
		(layer "B.Cu")
		(net "PCIE_COMP_TO_IOM_20_DP")
	)
	(segment
		(start 79.890366 -83.598766)
		(end 78.410816 -83.598766)
		(width 0.14605)
		(layer "B.Cu")
		(net "PCIE_COMP_TO_IOM_20_DP")
	)
	(segment
		(start 85.852 -82.7532)
		(end 84.887054 -82.7532)
		(width 0.14605)
		(layer "B.Cu")
		(net "PCIE_COMP_TO_IOM_20_DP")
	)
	(segment
		(start 106.003598 -28.5496)
		(end 103.661972 -29.035756)
		(width 0.14605)
		(layer "B.Cu")
		(net "PCIE_COMP_TO_IOM_20_DP")
	)
	(arc
		(start 112.499902 -32.38119)
		(mid 112.452066 -32.496676)
		(end 112.33658 -32.544512)
		(width 0.14605)
		(layer "B.Cu")
		(net "PCIE_COMP_TO_IOM_20_DP")
	)
	(arc
		(start 111.972598 -32.544512)
		(mid 111.819215 -32.480979)
		(end 111.755682 -32.327596)
		(width 0.14605)
		(layer "B.Cu")
		(net "PCIE_COMP_TO_IOM_20_DP")
	)
	(segment
		(start 76.60386 -84.149946)
		(end 76.843636 -83.91017)
		(width 0.14605)
		(layer "F.Cu")
		(net "PCIE_COMP_TO_IOM_20_DN")
	)
	(segment
		(start 75.475084 -84.149946)
		(end 76.60386 -84.149946)
		(width 0.14605)
		(layer "F.Cu")
		(net "PCIE_COMP_TO_IOM_20_DN")
	)
	(segment
		(start 76.843636 -83.91017)
		(end 77.424788 -83.91017)
		(width 0.14605)
		(layer "F.Cu")
		(net "PCIE_COMP_TO_IOM_20_DN")
	)
	(arc
		(start 77.424788 -83.91017)
		(mid 77.802125 -83.985227)
		(end 78.122018 -84.198968)
		(width 0.14605)
		(layer "F.Cu")
		(net "PCIE_COMP_TO_IOM_20_DN")
	)
	(segment
		(start 85.981032 -83.06435)
		(end 85.016086 -83.06435)
		(width 0.14605)
		(layer "B.Cu")
		(net "PCIE_COMP_TO_IOM_20_DN")
	)
	(segment
		(start 109.594142 -28.86075)
		(end 106.035602 -28.86075)
		(width 0.14605)
		(layer "B.Cu")
		(net "PCIE_COMP_TO_IOM_20_DN")
	)
	(segment
		(start 103.7844 -29.328364)
		(end 101.86543 -30.607762)
		(width 0.14605)
		(layer "B.Cu")
		(net "PCIE_COMP_TO_IOM_20_DN")
	)
	(segment
		(start 94.654624 -56.391302)
		(end 95.213678 -59.02198)
		(width 0.14605)
		(layer "B.Cu")
		(net "PCIE_COMP_TO_IOM_20_DN")
	)
	(segment
		(start 85.016086 -83.06435)
		(end 83.567778 -84.51215)
		(width 0.14605)
		(layer "B.Cu")
		(net "PCIE_COMP_TO_IOM_20_DN")
	)
	(segment
		(start 95.707962 -51.436524)
		(end 94.654624 -56.391302)
		(width 0.14605)
		(layer "B.Cu")
		(net "PCIE_COMP_TO_IOM_20_DN")
	)
	(segment
		(start 80.363568 -84.51215)
		(end 79.761334 -83.909916)
		(width 0.14605)
		(layer "B.Cu")
		(net "PCIE_COMP_TO_IOM_20_DN")
	)
	(segment
		(start 78.41107 -83.909916)
		(end 78.122018 -84.198968)
		(width 0.14605)
		(layer "B.Cu")
		(net "PCIE_COMP_TO_IOM_20_DN")
	)
	(segment
		(start 111.444532 -32.327596)
		(end 111.444532 -30.71114)
		(width 0.14605)
		(layer "B.Cu")
		(net "PCIE_COMP_TO_IOM_20_DN")
	)
	(segment
		(start 111.444532 -30.71114)
		(end 109.594142 -28.86075)
		(width 0.14605)
		(layer "B.Cu")
		(net "PCIE_COMP_TO_IOM_20_DN")
	)
	(segment
		(start 112.499902 -33.399984)
		(end 112.499902 -33.018984)
		(width 0.14605)
		(layer "B.Cu")
		(net "PCIE_COMP_TO_IOM_20_DN")
	)
	(segment
		(start 112.33658 -32.855662)
		(end 111.972598 -32.855662)
		(width 0.14605)
		(layer "B.Cu")
		(net "PCIE_COMP_TO_IOM_20_DN")
	)
	(segment
		(start 79.761334 -83.909916)
		(end 78.41107 -83.909916)
		(width 0.14605)
		(layer "B.Cu")
		(net "PCIE_COMP_TO_IOM_20_DN")
	)
	(segment
		(start 83.567778 -84.51215)
		(end 80.363568 -84.51215)
		(width 0.14605)
		(layer "B.Cu")
		(net "PCIE_COMP_TO_IOM_20_DN")
	)
	(segment
		(start 94.80804 -46.99254)
		(end 95.707962 -51.436524)
		(width 0.14605)
		(layer "B.Cu")
		(net "PCIE_COMP_TO_IOM_20_DN")
	)
	(segment
		(start 87.579708 -81.465674)
		(end 85.981032 -83.06435)
		(width 0.14605)
		(layer "B.Cu")
		(net "PCIE_COMP_TO_IOM_20_DN")
	)
	(segment
		(start 101.86543 -30.607762)
		(end 96.615504 -38.492684)
		(width 0.14605)
		(layer "B.Cu")
		(net "PCIE_COMP_TO_IOM_20_DN")
	)
	(segment
		(start 91.945714 -74.728832)
		(end 87.579708 -81.465674)
		(width 0.14605)
		(layer "B.Cu")
		(net "PCIE_COMP_TO_IOM_20_DN")
	)
	(segment
		(start 96.615504 -38.492684)
		(end 94.80804 -46.99254)
		(width 0.14605)
		(layer "B.Cu")
		(net "PCIE_COMP_TO_IOM_20_DN")
	)
	(segment
		(start 106.035602 -28.86075)
		(end 103.7844 -29.328364)
		(width 0.14605)
		(layer "B.Cu")
		(net "PCIE_COMP_TO_IOM_20_DN")
	)
	(segment
		(start 95.213678 -59.02198)
		(end 91.945714 -74.728832)
		(width 0.14605)
		(layer "B.Cu")
		(net "PCIE_COMP_TO_IOM_20_DN")
	)
	(arc
		(start 112.499902 -33.018984)
		(mid 112.452066 -32.903498)
		(end 112.33658 -32.855662)
		(width 0.14605)
		(layer "B.Cu")
		(net "PCIE_COMP_TO_IOM_20_DN")
	)
	(arc
		(start 111.972598 -32.855662)
		(mid 111.599199 -32.700995)
		(end 111.444532 -32.327596)
		(width 0.14605)
		(layer "B.Cu")
		(net "PCIE_COMP_TO_IOM_20_DN")
	)
	(segment
		(start 76.350114 -80.149954)
		(end 76.59878 -80.39862)
		(width 0.14605)
		(layer "F.Cu")
		(net "PCIE_COMP_TO_IOM_19_DP")
	)
	(segment
		(start 76.59878 -80.39862)
		(end 76.82738 -80.39862)
		(width 0.14605)
		(layer "F.Cu")
		(net "PCIE_COMP_TO_IOM_19_DP")
	)
	(segment
		(start 75.475084 -80.149954)
		(end 76.350114 -80.149954)
		(width 0.14605)
		(layer "F.Cu")
		(net "PCIE_COMP_TO_IOM_19_DP")
	)
	(arc
		(start 76.82738 -80.39862)
		(mid 77.09752 -80.320284)
		(end 77.283818 -80.109568)
		(width 0.14605)
		(layer "F.Cu")
		(net "PCIE_COMP_TO_IOM_19_DP")
	)
	(segment
		(start 83.4136 -79.502)
		(end 79.5528 -79.502)
		(width 0.14605)
		(layer "B.Cu")
		(net "PCIE_COMP_TO_IOM_19_DP")
	)
	(segment
		(start 93.550486 -59.54395)
		(end 90.551254 -73.809098)
		(width 0.14605)
		(layer "B.Cu")
		(net "PCIE_COMP_TO_IOM_19_DP")
	)
	(segment
		(start 95.255588 -37.877496)
		(end 93.236542 -47.37608)
		(width 0.14605)
		(layer "B.Cu")
		(net "PCIE_COMP_TO_IOM_19_DP")
	)
	(segment
		(start 78.65618 -80.39862)
		(end 77.57287 -80.39862)
		(width 0.14605)
		(layer "B.Cu")
		(net "PCIE_COMP_TO_IOM_19_DP")
	)
	(segment
		(start 85.50275 -80.91805)
		(end 84.82965 -80.91805)
		(width 0.14605)
		(layer "B.Cu")
		(net "PCIE_COMP_TO_IOM_19_DP")
	)
	(segment
		(start 93.236542 -47.37608)
		(end 93.806772 -50.224944)
		(width 0.14605)
		(layer "B.Cu")
		(net "PCIE_COMP_TO_IOM_19_DP")
	)
	(segment
		(start 90.551254 -73.809098)
		(end 86.735158 -79.685642)
		(width 0.14605)
		(layer "B.Cu")
		(net "PCIE_COMP_TO_IOM_19_DP")
	)
	(segment
		(start 77.57287 -80.39862)
		(end 77.283818 -80.109568)
		(width 0.14605)
		(layer "B.Cu")
		(net "PCIE_COMP_TO_IOM_19_DP")
	)
	(segment
		(start 86.735158 -79.685642)
		(end 85.50275 -80.91805)
		(width 0.14605)
		(layer "B.Cu")
		(net "PCIE_COMP_TO_IOM_19_DP")
	)
	(segment
		(start 114.136424 -33.744662)
		(end 113.780062 -33.744662)
		(width 0.14605)
		(layer "B.Cu")
		(net "PCIE_COMP_TO_IOM_19_DP")
	)
	(segment
		(start 103.78059 -27.4066)
		(end 100.959412 -29.290264)
		(width 0.14605)
		(layer "B.Cu")
		(net "PCIE_COMP_TO_IOM_19_DP")
	)
	(segment
		(start 92.68587 -55.476902)
		(end 93.550486 -59.54395)
		(width 0.14605)
		(layer "B.Cu")
		(net "PCIE_COMP_TO_IOM_19_DP")
	)
	(segment
		(start 100.959412 -29.290264)
		(end 95.255588 -37.877496)
		(width 0.14605)
		(layer "B.Cu")
		(net "PCIE_COMP_TO_IOM_19_DP")
	)
	(segment
		(start 113.555526 -33.520126)
		(end 113.555526 -30.402022)
		(width 0.14605)
		(layer "B.Cu")
		(net "PCIE_COMP_TO_IOM_19_DP")
	)
	(segment
		(start 79.5528 -79.502)
		(end 78.65618 -80.39862)
		(width 0.14605)
		(layer "B.Cu")
		(net "PCIE_COMP_TO_IOM_19_DP")
	)
	(segment
		(start 84.82965 -80.91805)
		(end 83.4136 -79.502)
		(width 0.14605)
		(layer "B.Cu")
		(net "PCIE_COMP_TO_IOM_19_DP")
	)
	(segment
		(start 114.3 -33.200086)
		(end 114.3 -33.581086)
		(width 0.14605)
		(layer "B.Cu")
		(net "PCIE_COMP_TO_IOM_19_DP")
	)
	(segment
		(start 113.555526 -30.402022)
		(end 110.560104 -27.4066)
		(width 0.14605)
		(layer "B.Cu")
		(net "PCIE_COMP_TO_IOM_19_DP")
	)
	(segment
		(start 93.806772 -50.224944)
		(end 92.68587 -55.476902)
		(width 0.14605)
		(layer "B.Cu")
		(net "PCIE_COMP_TO_IOM_19_DP")
	)
	(segment
		(start 110.560104 -27.4066)
		(end 103.78059 -27.4066)
		(width 0.14605)
		(layer "B.Cu")
		(net "PCIE_COMP_TO_IOM_19_DP")
	)
	(arc
		(start 114.3 -33.581086)
		(mid 114.25209 -33.696752)
		(end 114.136424 -33.744662)
		(width 0.14605)
		(layer "B.Cu")
		(net "PCIE_COMP_TO_IOM_19_DP")
	)
	(arc
		(start 113.780062 -33.744662)
		(mid 113.621291 -33.678897)
		(end 113.555526 -33.520126)
		(width 0.14605)
		(layer "B.Cu")
		(net "PCIE_COMP_TO_IOM_19_DP")
	)
	(segment
		(start 76.334874 -80.950054)
		(end 76.575158 -80.70977)
		(width 0.14605)
		(layer "F.Cu")
		(net "PCIE_COMP_TO_IOM_19_DN")
	)
	(segment
		(start 76.575158 -80.70977)
		(end 76.82738 -80.70977)
		(width 0.14605)
		(layer "F.Cu")
		(net "PCIE_COMP_TO_IOM_19_DN")
	)
	(segment
		(start 75.475084 -80.950054)
		(end 76.334874 -80.950054)
		(width 0.14605)
		(layer "F.Cu")
		(net "PCIE_COMP_TO_IOM_19_DN")
	)
	(arc
		(start 76.82738 -80.70977)
		(mid 77.097462 -80.788023)
		(end 77.283818 -80.998568)
		(width 0.14605)
		(layer "F.Cu")
		(net "PCIE_COMP_TO_IOM_19_DN")
	)
	(segment
		(start 114.136678 -34.055812)
		(end 113.780062 -34.055812)
		(width 0.14605)
		(layer "B.Cu")
		(net "PCIE_COMP_TO_IOM_19_DN")
	)
	(segment
		(start 101.184202 -29.514546)
		(end 95.547688 -38.000178)
		(width 0.14605)
		(layer "B.Cu")
		(net "PCIE_COMP_TO_IOM_19_DN")
	)
	(segment
		(start 93.554296 -47.377858)
		(end 94.124526 -50.226976)
		(width 0.14605)
		(layer "B.Cu")
		(net "PCIE_COMP_TO_IOM_19_DN")
	)
	(segment
		(start 77.572616 -80.70977)
		(end 77.283818 -80.998568)
		(width 0.14605)
		(layer "B.Cu")
		(net "PCIE_COMP_TO_IOM_19_DN")
	)
	(segment
		(start 93.868748 -59.543696)
		(end 90.843862 -73.930002)
		(width 0.14605)
		(layer "B.Cu")
		(net "PCIE_COMP_TO_IOM_19_DN")
	)
	(segment
		(start 86.955376 -79.90586)
		(end 86.955122 -79.90586)
		(width 0.14605)
		(layer "B.Cu")
		(net "PCIE_COMP_TO_IOM_19_DN")
	)
	(segment
		(start 110.431072 -27.71775)
		(end 103.875078 -27.71775)
		(width 0.14605)
		(layer "B.Cu")
		(net "PCIE_COMP_TO_IOM_19_DN")
	)
	(segment
		(start 84.700618 -81.2292)
		(end 83.284568 -79.81315)
		(width 0.14605)
		(layer "B.Cu")
		(net "PCIE_COMP_TO_IOM_19_DN")
	)
	(segment
		(start 113.244376 -30.531054)
		(end 110.431072 -27.71775)
		(width 0.14605)
		(layer "B.Cu")
		(net "PCIE_COMP_TO_IOM_19_DN")
	)
	(segment
		(start 113.244376 -33.520126)
		(end 113.244376 -30.531054)
		(width 0.14605)
		(layer "B.Cu")
		(net "PCIE_COMP_TO_IOM_19_DN")
	)
	(segment
		(start 95.547688 -38.000178)
		(end 93.554296 -47.377858)
		(width 0.14605)
		(layer "B.Cu")
		(net "PCIE_COMP_TO_IOM_19_DN")
	)
	(segment
		(start 79.681832 -79.81315)
		(end 78.785212 -80.70977)
		(width 0.14605)
		(layer "B.Cu")
		(net "PCIE_COMP_TO_IOM_19_DN")
	)
	(segment
		(start 90.843862 -73.930002)
		(end 86.97849 -79.882746)
		(width 0.14605)
		(layer "B.Cu")
		(net "PCIE_COMP_TO_IOM_19_DN")
	)
	(segment
		(start 103.875078 -27.71775)
		(end 101.184202 -29.514546)
		(width 0.14605)
		(layer "B.Cu")
		(net "PCIE_COMP_TO_IOM_19_DN")
	)
	(segment
		(start 114.3 -34.600134)
		(end 114.3 -34.219134)
		(width 0.14605)
		(layer "B.Cu")
		(net "PCIE_COMP_TO_IOM_19_DN")
	)
	(segment
		(start 78.785212 -80.70977)
		(end 77.572616 -80.70977)
		(width 0.14605)
		(layer "B.Cu")
		(net "PCIE_COMP_TO_IOM_19_DN")
	)
	(segment
		(start 86.955122 -79.90586)
		(end 85.631782 -81.2292)
		(width 0.14605)
		(layer "B.Cu")
		(net "PCIE_COMP_TO_IOM_19_DN")
	)
	(segment
		(start 94.124526 -50.226976)
		(end 93.004132 -55.477156)
		(width 0.14605)
		(layer "B.Cu")
		(net "PCIE_COMP_TO_IOM_19_DN")
	)
	(segment
		(start 86.97849 -79.882746)
		(end 86.955376 -79.90586)
		(width 0.14605)
		(layer "B.Cu")
		(net "PCIE_COMP_TO_IOM_19_DN")
	)
	(segment
		(start 85.631782 -81.2292)
		(end 84.700618 -81.2292)
		(width 0.14605)
		(layer "B.Cu")
		(net "PCIE_COMP_TO_IOM_19_DN")
	)
	(segment
		(start 93.004132 -55.477156)
		(end 93.868748 -59.543696)
		(width 0.14605)
		(layer "B.Cu")
		(net "PCIE_COMP_TO_IOM_19_DN")
	)
	(segment
		(start 83.284568 -79.81315)
		(end 79.681832 -79.81315)
		(width 0.14605)
		(layer "B.Cu")
		(net "PCIE_COMP_TO_IOM_19_DN")
	)
	(arc
		(start 114.3 -34.219134)
		(mid 114.252164 -34.103648)
		(end 114.136678 -34.055812)
		(width 0.14605)
		(layer "B.Cu")
		(net "PCIE_COMP_TO_IOM_19_DN")
	)
	(arc
		(start 113.780062 -34.055812)
		(mid 113.401275 -33.898913)
		(end 113.244376 -33.520126)
		(width 0.14605)
		(layer "B.Cu")
		(net "PCIE_COMP_TO_IOM_19_DN")
	)
	(segment
		(start 77.424534 -77.19822)
		(end 77.424788 -77.197966)
		(width 0.14605)
		(layer "F.Cu")
		(net "PCIE_COMP_TO_IOM_18_DP")
	)
	(segment
		(start 75.475084 -76.950062)
		(end 76.576936 -76.950062)
		(width 0.14605)
		(layer "F.Cu")
		(net "PCIE_COMP_TO_IOM_18_DP")
	)
	(segment
		(start 76.825094 -77.19822)
		(end 77.424534 -77.19822)
		(width 0.14605)
		(layer "F.Cu")
		(net "PCIE_COMP_TO_IOM_18_DP")
	)
	(segment
		(start 76.576936 -76.950062)
		(end 76.825094 -77.19822)
		(width 0.14605)
		(layer "F.Cu")
		(net "PCIE_COMP_TO_IOM_18_DP")
	)
	(arc
		(start 77.424788 -77.197966)
		(mid 77.802125 -77.122909)
		(end 78.122018 -76.909168)
		(width 0.14605)
		(layer "F.Cu")
		(net "PCIE_COMP_TO_IOM_18_DP")
	)
	(segment
		(start 91.607132 -49.337722)
		(end 91.823032 -50.353468)
		(width 0.14605)
		(layer "B.Cu")
		(net "PCIE_COMP_TO_IOM_18_DP")
	)
	(segment
		(start 115.936522 -32.544512)
		(end 115.57254 -32.544512)
		(width 0.14605)
		(layer "B.Cu")
		(net "PCIE_COMP_TO_IOM_18_DP")
	)
	(segment
		(start 111.539782 -26.2636)
		(end 103.228394 -26.2636)
		(width 0.14605)
		(layer "B.Cu")
		(net "PCIE_COMP_TO_IOM_18_DP")
	)
	(segment
		(start 86.592664 -75.8317)
		(end 86.275418 -76.1492)
		(width 0.14605)
		(layer "B.Cu")
		(net "PCIE_COMP_TO_IOM_18_DP")
	)
	(segment
		(start 91.81973 -57.968642)
		(end 88.758776 -72.510142)
		(width 0.14605)
		(layer "B.Cu")
		(net "PCIE_COMP_TO_IOM_18_DP")
	)
	(segment
		(start 88.758776 -72.510142)
		(end 86.592664 -75.8317)
		(width 0.14605)
		(layer "B.Cu")
		(net "PCIE_COMP_TO_IOM_18_DP")
	)
	(segment
		(start 84.0867 -77.2795)
		(end 83.566 -77.8002)
		(width 0.14605)
		(layer "B.Cu")
		(net "PCIE_COMP_TO_IOM_18_DP")
	)
	(segment
		(start 103.228394 -26.2636)
		(end 100.185982 -28.295346)
		(width 0.14605)
		(layer "B.Cu")
		(net "PCIE_COMP_TO_IOM_18_DP")
	)
	(segment
		(start 78.41107 -77.19822)
		(end 78.122018 -76.909168)
		(width 0.14605)
		(layer "B.Cu")
		(net "PCIE_COMP_TO_IOM_18_DP")
	)
	(segment
		(start 94.15653 -37.341048)
		(end 91.607132 -49.337722)
		(width 0.14605)
		(layer "B.Cu")
		(net "PCIE_COMP_TO_IOM_18_DP")
	)
	(segment
		(start 86.275418 -76.1492)
		(end 84.6582 -76.1492)
		(width 0.14605)
		(layer "B.Cu")
		(net "PCIE_COMP_TO_IOM_18_DP")
	)
	(segment
		(start 100.185982 -28.295346)
		(end 94.15653 -37.341048)
		(width 0.14605)
		(layer "B.Cu")
		(net "PCIE_COMP_TO_IOM_18_DP")
	)
	(segment
		(start 84.6582 -76.1492)
		(end 84.0867 -76.7207)
		(width 0.14605)
		(layer "B.Cu")
		(net "PCIE_COMP_TO_IOM_18_DP")
	)
	(segment
		(start 116.099844 -32.00019)
		(end 116.099844 -32.38119)
		(width 0.14605)
		(layer "B.Cu")
		(net "PCIE_COMP_TO_IOM_18_DP")
	)
	(segment
		(start 84.0867 -76.7207)
		(end 84.0867 -77.2795)
		(width 0.14605)
		(layer "B.Cu")
		(net "PCIE_COMP_TO_IOM_18_DP")
	)
	(segment
		(start 83.566 -77.8002)
		(end 80.772 -77.8002)
		(width 0.14605)
		(layer "B.Cu")
		(net "PCIE_COMP_TO_IOM_18_DP")
	)
	(segment
		(start 80.17002 -77.19822)
		(end 78.41107 -77.19822)
		(width 0.14605)
		(layer "B.Cu")
		(net "PCIE_COMP_TO_IOM_18_DP")
	)
	(segment
		(start 115.355624 -32.327596)
		(end 115.355624 -30.079442)
		(width 0.14605)
		(layer "B.Cu")
		(net "PCIE_COMP_TO_IOM_18_DP")
	)
	(segment
		(start 91.823032 -50.353468)
		(end 91.012264 -54.167786)
		(width 0.14605)
		(layer "B.Cu")
		(net "PCIE_COMP_TO_IOM_18_DP")
	)
	(segment
		(start 80.772 -77.8002)
		(end 80.17002 -77.19822)
		(width 0.14605)
		(layer "B.Cu")
		(net "PCIE_COMP_TO_IOM_18_DP")
	)
	(segment
		(start 91.012264 -54.167786)
		(end 91.81973 -57.968642)
		(width 0.14605)
		(layer "B.Cu")
		(net "PCIE_COMP_TO_IOM_18_DP")
	)
	(segment
		(start 115.355624 -30.079442)
		(end 111.539782 -26.2636)
		(width 0.14605)
		(layer "B.Cu")
		(net "PCIE_COMP_TO_IOM_18_DP")
	)
	(arc
		(start 115.57254 -32.544512)
		(mid 115.419157 -32.480979)
		(end 115.355624 -32.327596)
		(width 0.14605)
		(layer "B.Cu")
		(net "PCIE_COMP_TO_IOM_18_DP")
	)
	(arc
		(start 116.099844 -32.38119)
		(mid 116.052008 -32.496676)
		(end 115.936522 -32.544512)
		(width 0.14605)
		(layer "B.Cu")
		(net "PCIE_COMP_TO_IOM_18_DP")
	)
	(segment
		(start 75.475084 -77.749908)
		(end 76.603098 -77.749908)
		(width 0.14605)
		(layer "F.Cu")
		(net "PCIE_COMP_TO_IOM_18_DN")
	)
	(segment
		(start 76.603098 -77.749908)
		(end 76.843636 -77.50937)
		(width 0.14605)
		(layer "F.Cu")
		(net "PCIE_COMP_TO_IOM_18_DN")
	)
	(segment
		(start 76.843636 -77.50937)
		(end 77.424788 -77.50937)
		(width 0.14605)
		(layer "F.Cu")
		(net "PCIE_COMP_TO_IOM_18_DN")
	)
	(arc
		(start 77.424788 -77.50937)
		(mid 77.802125 -77.584427)
		(end 78.122018 -77.798168)
		(width 0.14605)
		(layer "F.Cu")
		(net "PCIE_COMP_TO_IOM_18_DN")
	)
	(segment
		(start 115.936522 -32.855662)
		(end 115.57254 -32.855662)
		(width 0.14605)
		(layer "B.Cu")
		(net "PCIE_COMP_TO_IOM_18_DN")
	)
	(segment
		(start 92.141294 -50.353468)
		(end 91.330526 -54.167786)
		(width 0.14605)
		(layer "B.Cu")
		(net "PCIE_COMP_TO_IOM_18_DN")
	)
	(segment
		(start 80.642968 -78.11135)
		(end 80.040988 -77.50937)
		(width 0.14605)
		(layer "B.Cu")
		(net "PCIE_COMP_TO_IOM_18_DN")
	)
	(segment
		(start 78.410816 -77.50937)
		(end 78.122018 -77.798168)
		(width 0.14605)
		(layer "B.Cu")
		(net "PCIE_COMP_TO_IOM_18_DN")
	)
	(segment
		(start 91.925394 -49.337722)
		(end 92.141294 -50.353468)
		(width 0.14605)
		(layer "B.Cu")
		(net "PCIE_COMP_TO_IOM_18_DN")
	)
	(segment
		(start 83.695032 -78.11135)
		(end 80.642968 -78.11135)
		(width 0.14605)
		(layer "B.Cu")
		(net "PCIE_COMP_TO_IOM_18_DN")
	)
	(segment
		(start 115.044474 -30.208474)
		(end 111.41075 -26.57475)
		(width 0.14605)
		(layer "B.Cu")
		(net "PCIE_COMP_TO_IOM_18_DN")
	)
	(segment
		(start 94.44863 -37.464238)
		(end 91.925394 -49.337722)
		(width 0.14605)
		(layer "B.Cu")
		(net "PCIE_COMP_TO_IOM_18_DN")
	)
	(segment
		(start 86.40445 -76.46035)
		(end 84.787232 -76.46035)
		(width 0.14605)
		(layer "B.Cu")
		(net "PCIE_COMP_TO_IOM_18_DN")
	)
	(segment
		(start 103.322882 -26.57475)
		(end 100.410518 -28.519628)
		(width 0.14605)
		(layer "B.Cu")
		(net "PCIE_COMP_TO_IOM_18_DN")
	)
	(segment
		(start 92.137992 -57.968388)
		(end 89.051384 -72.6313)
		(width 0.14605)
		(layer "B.Cu")
		(net "PCIE_COMP_TO_IOM_18_DN")
	)
	(segment
		(start 91.330526 -54.167786)
		(end 92.137992 -57.968388)
		(width 0.14605)
		(layer "B.Cu")
		(net "PCIE_COMP_TO_IOM_18_DN")
	)
	(segment
		(start 89.051384 -72.6313)
		(end 86.835742 -76.029058)
		(width 0.14605)
		(layer "B.Cu")
		(net "PCIE_COMP_TO_IOM_18_DN")
	)
	(segment
		(start 115.044474 -32.327596)
		(end 115.044474 -30.208474)
		(width 0.14605)
		(layer "B.Cu")
		(net "PCIE_COMP_TO_IOM_18_DN")
	)
	(segment
		(start 86.835742 -76.029058)
		(end 86.40445 -76.46035)
		(width 0.14605)
		(layer "B.Cu")
		(net "PCIE_COMP_TO_IOM_18_DN")
	)
	(segment
		(start 100.410518 -28.519628)
		(end 94.44863 -37.464238)
		(width 0.14605)
		(layer "B.Cu")
		(net "PCIE_COMP_TO_IOM_18_DN")
	)
	(segment
		(start 84.39785 -77.408532)
		(end 83.695032 -78.11135)
		(width 0.14605)
		(layer "B.Cu")
		(net "PCIE_COMP_TO_IOM_18_DN")
	)
	(segment
		(start 84.787232 -76.46035)
		(end 84.39785 -76.849732)
		(width 0.14605)
		(layer "B.Cu")
		(net "PCIE_COMP_TO_IOM_18_DN")
	)
	(segment
		(start 80.040988 -77.50937)
		(end 78.410816 -77.50937)
		(width 0.14605)
		(layer "B.Cu")
		(net "PCIE_COMP_TO_IOM_18_DN")
	)
	(segment
		(start 111.41075 -26.57475)
		(end 103.322882 -26.57475)
		(width 0.14605)
		(layer "B.Cu")
		(net "PCIE_COMP_TO_IOM_18_DN")
	)
	(segment
		(start 116.099844 -33.399984)
		(end 116.099844 -33.018984)
		(width 0.14605)
		(layer "B.Cu")
		(net "PCIE_COMP_TO_IOM_18_DN")
	)
	(segment
		(start 84.39785 -76.849732)
		(end 84.39785 -77.408532)
		(width 0.14605)
		(layer "B.Cu")
		(net "PCIE_COMP_TO_IOM_18_DN")
	)
	(arc
		(start 115.57254 -32.855662)
		(mid 115.199141 -32.700995)
		(end 115.044474 -32.327596)
		(width 0.14605)
		(layer "B.Cu")
		(net "PCIE_COMP_TO_IOM_18_DN")
	)
	(arc
		(start 116.099844 -33.018984)
		(mid 116.052008 -32.903498)
		(end 115.936522 -32.855662)
		(width 0.14605)
		(layer "B.Cu")
		(net "PCIE_COMP_TO_IOM_18_DN")
	)
	(segment
		(start 76.59878 -73.99782)
		(end 76.82738 -73.99782)
		(width 0.14605)
		(layer "F.Cu")
		(net "PCIE_COMP_TO_IOM_17_DP")
	)
	(segment
		(start 76.350876 -73.749916)
		(end 76.59878 -73.99782)
		(width 0.14605)
		(layer "F.Cu")
		(net "PCIE_COMP_TO_IOM_17_DP")
	)
	(segment
		(start 75.475084 -73.749916)
		(end 76.350876 -73.749916)
		(width 0.14605)
		(layer "F.Cu")
		(net "PCIE_COMP_TO_IOM_17_DP")
	)
	(arc
		(start 76.82738 -73.99782)
		(mid 77.09752 -73.919484)
		(end 77.283818 -73.708768)
		(width 0.14605)
		(layer "F.Cu")
		(net "PCIE_COMP_TO_IOM_17_DP")
	)
	(segment
		(start 117.155468 -33.520126)
		(end 117.155468 -29.220414)
		(width 0.14605)
		(layer "B.Cu")
		(net "PCIE_COMP_TO_IOM_17_DP")
	)
	(segment
		(start 77.94498 -73.99782)
		(end 77.57287 -73.99782)
		(width 0.14605)
		(layer "B.Cu")
		(net "PCIE_COMP_TO_IOM_17_DP")
	)
	(segment
		(start 77.57287 -73.99782)
		(end 77.283818 -73.708768)
		(width 0.14605)
		(layer "B.Cu")
		(net "PCIE_COMP_TO_IOM_17_DP")
	)
	(segment
		(start 99.369372 -27.208988)
		(end 93.073728 -36.724082)
		(width 0.14605)
		(layer "B.Cu")
		(net "PCIE_COMP_TO_IOM_17_DP")
	)
	(segment
		(start 117.899942 -33.200086)
		(end 117.899942 -33.581086)
		(width 0.14605)
		(layer "B.Cu")
		(net "PCIE_COMP_TO_IOM_17_DP")
	)
	(segment
		(start 85.14715 -74.54265)
		(end 84.57565 -74.54265)
		(width 0.14605)
		(layer "B.Cu")
		(net "PCIE_COMP_TO_IOM_17_DP")
	)
	(segment
		(start 84.33435 -74.30135)
		(end 84.33435 -73.81875)
		(width 0.14605)
		(layer "B.Cu")
		(net "PCIE_COMP_TO_IOM_17_DP")
	)
	(segment
		(start 87.639652 -72.049894)
		(end 85.14715 -74.54265)
		(width 0.14605)
		(layer "B.Cu")
		(net "PCIE_COMP_TO_IOM_17_DP")
	)
	(segment
		(start 90.601038 -57.830466)
		(end 87.639652 -72.049894)
		(width 0.14605)
		(layer "B.Cu")
		(net "PCIE_COMP_TO_IOM_17_DP")
	)
	(segment
		(start 116.230654 -28.2956)
		(end 115.824254 -28.2956)
		(width 0.14605)
		(layer "B.Cu")
		(net "PCIE_COMP_TO_IOM_17_DP")
	)
	(segment
		(start 83.5152 -72.9996)
		(end 78.9432 -72.9996)
		(width 0.14605)
		(layer "B.Cu")
		(net "PCIE_COMP_TO_IOM_17_DP")
	)
	(segment
		(start 93.073728 -36.724082)
		(end 89.619074 -53.086762)
		(width 0.14605)
		(layer "B.Cu")
		(net "PCIE_COMP_TO_IOM_17_DP")
	)
	(segment
		(start 117.155468 -29.220414)
		(end 116.230654 -28.2956)
		(width 0.14605)
		(layer "B.Cu")
		(net "PCIE_COMP_TO_IOM_17_DP")
	)
	(segment
		(start 78.9432 -72.9996)
		(end 77.94498 -73.99782)
		(width 0.14605)
		(layer "B.Cu")
		(net "PCIE_COMP_TO_IOM_17_DP")
	)
	(segment
		(start 115.824254 -28.2956)
		(end 112.623854 -25.0952)
		(width 0.14605)
		(layer "B.Cu")
		(net "PCIE_COMP_TO_IOM_17_DP")
	)
	(segment
		(start 102.539292 -25.0952)
		(end 99.369372 -27.208988)
		(width 0.14605)
		(layer "B.Cu")
		(net "PCIE_COMP_TO_IOM_17_DP")
	)
	(segment
		(start 117.736366 -33.744662)
		(end 117.380004 -33.744662)
		(width 0.14605)
		(layer "B.Cu")
		(net "PCIE_COMP_TO_IOM_17_DP")
	)
	(segment
		(start 84.33435 -73.81875)
		(end 83.5152 -72.9996)
		(width 0.14605)
		(layer "B.Cu")
		(net "PCIE_COMP_TO_IOM_17_DP")
	)
	(segment
		(start 89.619074 -53.086762)
		(end 90.601038 -57.830466)
		(width 0.14605)
		(layer "B.Cu")
		(net "PCIE_COMP_TO_IOM_17_DP")
	)
	(segment
		(start 112.623854 -25.0952)
		(end 102.539292 -25.0952)
		(width 0.14605)
		(layer "B.Cu")
		(net "PCIE_COMP_TO_IOM_17_DP")
	)
	(segment
		(start 84.57565 -74.54265)
		(end 84.33435 -74.30135)
		(width 0.14605)
		(layer "B.Cu")
		(net "PCIE_COMP_TO_IOM_17_DP")
	)
	(arc
		(start 117.899942 -33.581086)
		(mid 117.852032 -33.696752)
		(end 117.736366 -33.744662)
		(width 0.14605)
		(layer "B.Cu")
		(net "PCIE_COMP_TO_IOM_17_DP")
	)
	(arc
		(start 117.380004 -33.744662)
		(mid 117.221233 -33.678897)
		(end 117.155468 -33.520126)
		(width 0.14605)
		(layer "B.Cu")
		(net "PCIE_COMP_TO_IOM_17_DP")
	)
	(segment
		(start 76.575158 -74.30897)
		(end 76.82738 -74.30897)
		(width 0.14605)
		(layer "F.Cu")
		(net "PCIE_COMP_TO_IOM_17_DN")
	)
	(segment
		(start 76.334112 -74.550016)
		(end 76.575158 -74.30897)
		(width 0.14605)
		(layer "F.Cu")
		(net "PCIE_COMP_TO_IOM_17_DN")
	)
	(segment
		(start 75.475084 -74.550016)
		(end 76.334112 -74.550016)
		(width 0.14605)
		(layer "F.Cu")
		(net "PCIE_COMP_TO_IOM_17_DN")
	)
	(arc
		(start 76.82738 -74.30897)
		(mid 77.097462 -74.387223)
		(end 77.283818 -74.597768)
		(width 0.14605)
		(layer "F.Cu")
		(net "PCIE_COMP_TO_IOM_17_DN")
	)
	(segment
		(start 77.572616 -74.30897)
		(end 77.283818 -74.597768)
		(width 0.14605)
		(layer "B.Cu")
		(net "PCIE_COMP_TO_IOM_17_DN")
	)
	(segment
		(start 112.494822 -25.40635)
		(end 102.63378 -25.40635)
		(width 0.14605)
		(layer "B.Cu")
		(net "PCIE_COMP_TO_IOM_17_DN")
	)
	(segment
		(start 84.0232 -73.947782)
		(end 83.386168 -73.31075)
		(width 0.14605)
		(layer "B.Cu")
		(net "PCIE_COMP_TO_IOM_17_DN")
	)
	(segment
		(start 84.0232 -74.430382)
		(end 84.0232 -73.947782)
		(width 0.14605)
		(layer "B.Cu")
		(net "PCIE_COMP_TO_IOM_17_DN")
	)
	(segment
		(start 78.074012 -74.30897)
		(end 77.572616 -74.30897)
		(width 0.14605)
		(layer "B.Cu")
		(net "PCIE_COMP_TO_IOM_17_DN")
	)
	(segment
		(start 116.844318 -29.349446)
		(end 116.101622 -28.60675)
		(width 0.14605)
		(layer "B.Cu")
		(net "PCIE_COMP_TO_IOM_17_DN")
	)
	(segment
		(start 116.844318 -33.520126)
		(end 116.844318 -29.349446)
		(width 0.14605)
		(layer "B.Cu")
		(net "PCIE_COMP_TO_IOM_17_DN")
	)
	(segment
		(start 115.695222 -28.60675)
		(end 112.494822 -25.40635)
		(width 0.14605)
		(layer "B.Cu")
		(net "PCIE_COMP_TO_IOM_17_DN")
	)
	(segment
		(start 117.899942 -34.600134)
		(end 117.899942 -34.219134)
		(width 0.14605)
		(layer "B.Cu")
		(net "PCIE_COMP_TO_IOM_17_DN")
	)
	(segment
		(start 87.925402 -72.204326)
		(end 85.276182 -74.8538)
		(width 0.14605)
		(layer "B.Cu")
		(net "PCIE_COMP_TO_IOM_17_DN")
	)
	(segment
		(start 79.072232 -73.31075)
		(end 78.074012 -74.30897)
		(width 0.14605)
		(layer "B.Cu")
		(net "PCIE_COMP_TO_IOM_17_DN")
	)
	(segment
		(start 83.386168 -73.31075)
		(end 79.072232 -73.31075)
		(width 0.14605)
		(layer "B.Cu")
		(net "PCIE_COMP_TO_IOM_17_DN")
	)
	(segment
		(start 85.276182 -74.8538)
		(end 84.446618 -74.8538)
		(width 0.14605)
		(layer "B.Cu")
		(net "PCIE_COMP_TO_IOM_17_DN")
	)
	(segment
		(start 89.937082 -53.08727)
		(end 90.919046 -57.83072)
		(width 0.14605)
		(layer "B.Cu")
		(net "PCIE_COMP_TO_IOM_17_DN")
	)
	(segment
		(start 84.446618 -74.8538)
		(end 84.0232 -74.430382)
		(width 0.14605)
		(layer "B.Cu")
		(net "PCIE_COMP_TO_IOM_17_DN")
	)
	(segment
		(start 102.63378 -25.40635)
		(end 99.594416 -27.43327)
		(width 0.14605)
		(layer "B.Cu")
		(net "PCIE_COMP_TO_IOM_17_DN")
	)
	(segment
		(start 99.594416 -27.43327)
		(end 93.366082 -36.84651)
		(width 0.14605)
		(layer "B.Cu")
		(net "PCIE_COMP_TO_IOM_17_DN")
	)
	(segment
		(start 117.73662 -34.055812)
		(end 117.380004 -34.055812)
		(width 0.14605)
		(layer "B.Cu")
		(net "PCIE_COMP_TO_IOM_17_DN")
	)
	(segment
		(start 116.101622 -28.60675)
		(end 115.695222 -28.60675)
		(width 0.14605)
		(layer "B.Cu")
		(net "PCIE_COMP_TO_IOM_17_DN")
	)
	(segment
		(start 90.919046 -57.83072)
		(end 87.925402 -72.204326)
		(width 0.14605)
		(layer "B.Cu")
		(net "PCIE_COMP_TO_IOM_17_DN")
	)
	(segment
		(start 93.366082 -36.84651)
		(end 89.937082 -53.08727)
		(width 0.14605)
		(layer "B.Cu")
		(net "PCIE_COMP_TO_IOM_17_DN")
	)
	(arc
		(start 117.380004 -34.055812)
		(mid 117.001217 -33.898913)
		(end 116.844318 -33.520126)
		(width 0.14605)
		(layer "B.Cu")
		(net "PCIE_COMP_TO_IOM_17_DN")
	)
	(arc
		(start 117.899942 -34.219134)
		(mid 117.852106 -34.103648)
		(end 117.73662 -34.055812)
		(width 0.14605)
		(layer "B.Cu")
		(net "PCIE_COMP_TO_IOM_17_DN")
	)
	(segment
		(start 77.424534 -70.79742)
		(end 77.424788 -70.797166)
		(width 0.14605)
		(layer "F.Cu")
		(net "PCIE_COMP_TO_IOM_16_DP")
	)
	(segment
		(start 76.825094 -70.79742)
		(end 77.424534 -70.79742)
		(width 0.14605)
		(layer "F.Cu")
		(net "PCIE_COMP_TO_IOM_16_DP")
	)
	(segment
		(start 76.577698 -70.550024)
		(end 76.825094 -70.79742)
		(width 0.14605)
		(layer "F.Cu")
		(net "PCIE_COMP_TO_IOM_16_DP")
	)
	(segment
		(start 75.475084 -70.550024)
		(end 76.577698 -70.550024)
		(width 0.14605)
		(layer "F.Cu")
		(net "PCIE_COMP_TO_IOM_16_DP")
	)
	(arc
		(start 77.424788 -70.797166)
		(mid 77.802125 -70.722109)
		(end 78.122018 -70.508368)
		(width 0.14605)
		(layer "F.Cu")
		(net "PCIE_COMP_TO_IOM_16_DP")
	)
	(segment
		(start 113.106454 -23.9268)
		(end 102.063296 -23.9268)
		(width 0.14605)
		(layer "B.Cu")
		(net "PCIE_COMP_TO_IOM_16_DP")
	)
	(segment
		(start 118.955566 -29.369766)
		(end 116.6114 -27.0256)
		(width 0.14605)
		(layer "B.Cu")
		(net "PCIE_COMP_TO_IOM_16_DP")
	)
	(segment
		(start 116.205254 -27.0256)
		(end 113.106454 -23.9268)
		(width 0.14605)
		(layer "B.Cu")
		(net "PCIE_COMP_TO_IOM_16_DP")
	)
	(segment
		(start 78.410816 -70.797166)
		(end 78.122018 -70.508368)
		(width 0.14605)
		(layer "B.Cu")
		(net "PCIE_COMP_TO_IOM_16_DP")
	)
	(segment
		(start 89.38006 -57.596278)
		(end 87.26043 -68.18757)
		(width 0.14605)
		(layer "B.Cu")
		(net "PCIE_COMP_TO_IOM_16_DP")
	)
	(segment
		(start 88.383364 -52.783232)
		(end 89.38006 -57.596278)
		(width 0.14605)
		(layer "B.Cu")
		(net "PCIE_COMP_TO_IOM_16_DP")
	)
	(segment
		(start 85.350604 -70.09765)
		(end 79.60995 -70.09765)
		(width 0.14605)
		(layer "B.Cu")
		(net "PCIE_COMP_TO_IOM_16_DP")
	)
	(segment
		(start 118.955566 -32.327342)
		(end 118.955566 -29.369766)
		(width 0.14605)
		(layer "B.Cu")
		(net "PCIE_COMP_TO_IOM_16_DP")
	)
	(segment
		(start 79.60995 -70.09765)
		(end 78.910434 -70.797166)
		(width 0.14605)
		(layer "B.Cu")
		(net "PCIE_COMP_TO_IOM_16_DP")
	)
	(segment
		(start 87.26043 -68.18757)
		(end 85.350604 -70.09765)
		(width 0.14605)
		(layer "B.Cu")
		(net "PCIE_COMP_TO_IOM_16_DP")
	)
	(segment
		(start 88.751664 -47.307754)
		(end 89.12733 -49.067212)
		(width 0.14605)
		(layer "B.Cu")
		(net "PCIE_COMP_TO_IOM_16_DP")
	)
	(segment
		(start 90.705178 -38.115494)
		(end 88.751664 -47.307754)
		(width 0.14605)
		(layer "B.Cu")
		(net "PCIE_COMP_TO_IOM_16_DP")
	)
	(segment
		(start 89.12733 -49.067212)
		(end 88.383364 -52.783232)
		(width 0.14605)
		(layer "B.Cu")
		(net "PCIE_COMP_TO_IOM_16_DP")
	)
	(segment
		(start 119.70004 -32.00019)
		(end 119.70004 -32.38119)
		(width 0.14605)
		(layer "B.Cu")
		(net "PCIE_COMP_TO_IOM_16_DP")
	)
	(segment
		(start 116.6114 -27.0256)
		(end 116.205254 -27.0256)
		(width 0.14605)
		(layer "B.Cu")
		(net "PCIE_COMP_TO_IOM_16_DP")
	)
	(segment
		(start 119.536718 -32.544512)
		(end 119.172736 -32.544512)
		(width 0.14605)
		(layer "B.Cu")
		(net "PCIE_COMP_TO_IOM_16_DP")
	)
	(segment
		(start 98.296984 -26.430478)
		(end 90.705178 -38.115494)
		(width 0.14605)
		(layer "B.Cu")
		(net "PCIE_COMP_TO_IOM_16_DP")
	)
	(segment
		(start 78.910434 -70.797166)
		(end 78.410816 -70.797166)
		(width 0.14605)
		(layer "B.Cu")
		(net "PCIE_COMP_TO_IOM_16_DP")
	)
	(segment
		(start 102.063296 -23.9268)
		(end 98.296984 -26.430478)
		(width 0.14605)
		(layer "B.Cu")
		(net "PCIE_COMP_TO_IOM_16_DP")
	)
	(arc
		(start 119.172736 -32.544512)
		(mid 119.019174 -32.480904)
		(end 118.955566 -32.327342)
		(width 0.14605)
		(layer "B.Cu")
		(net "PCIE_COMP_TO_IOM_16_DP")
	)
	(arc
		(start 119.70004 -32.38119)
		(mid 119.652204 -32.496676)
		(end 119.536718 -32.544512)
		(width 0.14605)
		(layer "B.Cu")
		(net "PCIE_COMP_TO_IOM_16_DP")
	)
	(segment
		(start 75.475084 -71.350124)
		(end 76.602082 -71.350124)
		(width 0.14605)
		(layer "F.Cu")
		(net "PCIE_COMP_TO_IOM_16_DN")
	)
	(segment
		(start 76.843636 -71.10857)
		(end 77.424788 -71.10857)
		(width 0.14605)
		(layer "F.Cu")
		(net "PCIE_COMP_TO_IOM_16_DN")
	)
	(segment
		(start 76.602082 -71.350124)
		(end 76.843636 -71.10857)
		(width 0.14605)
		(layer "F.Cu")
		(net "PCIE_COMP_TO_IOM_16_DN")
	)
	(arc
		(start 77.424788 -71.10857)
		(mid 77.802125 -71.183627)
		(end 78.122018 -71.397368)
		(width 0.14605)
		(layer "F.Cu")
		(net "PCIE_COMP_TO_IOM_16_DN")
	)
	(segment
		(start 88.701118 -52.782216)
		(end 89.697814 -57.595262)
		(width 0.14605)
		(layer "B.Cu")
		(net "PCIE_COMP_TO_IOM_16_DN")
	)
	(segment
		(start 112.977422 -24.23795)
		(end 102.15753 -24.23795)
		(width 0.14605)
		(layer "B.Cu")
		(net "PCIE_COMP_TO_IOM_16_DN")
	)
	(segment
		(start 118.644416 -32.327342)
		(end 118.644416 -29.498798)
		(width 0.14605)
		(layer "B.Cu")
		(net "PCIE_COMP_TO_IOM_16_DN")
	)
	(segment
		(start 118.644416 -29.498798)
		(end 116.482368 -27.33675)
		(width 0.14605)
		(layer "B.Cu")
		(net "PCIE_COMP_TO_IOM_16_DN")
	)
	(segment
		(start 89.069926 -47.3075)
		(end 89.445084 -49.06518)
		(width 0.14605)
		(layer "B.Cu")
		(net "PCIE_COMP_TO_IOM_16_DN")
	)
	(segment
		(start 116.482368 -27.33675)
		(end 116.076222 -27.33675)
		(width 0.14605)
		(layer "B.Cu")
		(net "PCIE_COMP_TO_IOM_16_DN")
	)
	(segment
		(start 78.41107 -71.108316)
		(end 78.122018 -71.397368)
		(width 0.14605)
		(layer "B.Cu")
		(net "PCIE_COMP_TO_IOM_16_DN")
	)
	(segment
		(start 102.15753 -24.23795)
		(end 98.523044 -26.654252)
		(width 0.14605)
		(layer "B.Cu")
		(net "PCIE_COMP_TO_IOM_16_DN")
	)
	(segment
		(start 89.697814 -57.595262)
		(end 87.547196 -68.340986)
		(width 0.14605)
		(layer "B.Cu")
		(net "PCIE_COMP_TO_IOM_16_DN")
	)
	(segment
		(start 89.445084 -49.06518)
		(end 88.701118 -52.782216)
		(width 0.14605)
		(layer "B.Cu")
		(net "PCIE_COMP_TO_IOM_16_DN")
	)
	(segment
		(start 79.039466 -71.108316)
		(end 78.41107 -71.108316)
		(width 0.14605)
		(layer "B.Cu")
		(net "PCIE_COMP_TO_IOM_16_DN")
	)
	(segment
		(start 87.547196 -68.340986)
		(end 85.479636 -70.4088)
		(width 0.14605)
		(layer "B.Cu")
		(net "PCIE_COMP_TO_IOM_16_DN")
	)
	(segment
		(start 119.70004 -33.399984)
		(end 119.70004 -33.018984)
		(width 0.14605)
		(layer "B.Cu")
		(net "PCIE_COMP_TO_IOM_16_DN")
	)
	(segment
		(start 116.076222 -27.33675)
		(end 112.977422 -24.23795)
		(width 0.14605)
		(layer "B.Cu")
		(net "PCIE_COMP_TO_IOM_16_DN")
	)
	(segment
		(start 119.536718 -32.855662)
		(end 119.172736 -32.855662)
		(width 0.14605)
		(layer "B.Cu")
		(net "PCIE_COMP_TO_IOM_16_DN")
	)
	(segment
		(start 79.738982 -70.4088)
		(end 79.039466 -71.108316)
		(width 0.14605)
		(layer "B.Cu")
		(net "PCIE_COMP_TO_IOM_16_DN")
	)
	(segment
		(start 98.523044 -26.654252)
		(end 90.997532 -38.236652)
		(width 0.14605)
		(layer "B.Cu")
		(net "PCIE_COMP_TO_IOM_16_DN")
	)
	(segment
		(start 90.997532 -38.236652)
		(end 89.069926 -47.3075)
		(width 0.14605)
		(layer "B.Cu")
		(net "PCIE_COMP_TO_IOM_16_DN")
	)
	(segment
		(start 85.479636 -70.4088)
		(end 79.738982 -70.4088)
		(width 0.14605)
		(layer "B.Cu")
		(net "PCIE_COMP_TO_IOM_16_DN")
	)
	(arc
		(start 119.70004 -33.018984)
		(mid 119.652204 -32.903498)
		(end 119.536718 -32.855662)
		(width 0.14605)
		(layer "B.Cu")
		(net "PCIE_COMP_TO_IOM_16_DN")
	)
	(arc
		(start 119.172736 -32.855662)
		(mid 118.799157 -32.700921)
		(end 118.644416 -32.327342)
		(width 0.14605)
		(layer "B.Cu")
		(net "PCIE_COMP_TO_IOM_16_DN")
	)
	(segment
		(start 173.152308 -135.710168)
		(end 173.152308 -134.877302)
		(width 0.14605)
		(layer "F.Cu")
		(net "PCIE_COMP_TO_IOM_15_DP")
	)
	(segment
		(start 173.048676 -136.561322)
		(end 173.048676 -135.8138)
		(width 0.14605)
		(layer "F.Cu")
		(net "PCIE_COMP_TO_IOM_15_DP")
	)
	(segment
		(start 170.97883 -138.631168)
		(end 173.048676 -136.561322)
		(width 0.14605)
		(layer "F.Cu")
		(net "PCIE_COMP_TO_IOM_15_DP")
	)
	(segment
		(start 173.048676 -135.8138)
		(end 173.152308 -135.710168)
		(width 0.14605)
		(layer "F.Cu")
		(net "PCIE_COMP_TO_IOM_15_DP")
	)
	(segment
		(start 171.068492 -138.94943)
		(end 170.97883 -138.859768)
		(width 0.14605)
		(layer "F.Cu")
		(net "PCIE_COMP_TO_IOM_15_DP")
	)
	(segment
		(start 173.152308 -134.877302)
		(end 173.150022 -134.875016)
		(width 0.14605)
		(layer "F.Cu")
		(net "PCIE_COMP_TO_IOM_15_DP")
	)
	(arc
		(start 170.97883 -138.859768)
		(mid 170.931485 -138.745468)
		(end 170.97883 -138.631168)
		(width 0.14605)
		(layer "F.Cu")
		(net "PCIE_COMP_TO_IOM_15_DP")
	)
	(segment
		(start 170.749722 -138.860022)
		(end 170.541188 -139.068302)
		(width 0.14605)
		(layer "B.Cu")
		(net "PCIE_COMP_TO_IOM_15_DP")
	)
	(segment
		(start 165.370256 -136.559544)
		(end 164.026088 -129.645918)
		(width 0.14605)
		(layer "B.Cu")
		(net "PCIE_COMP_TO_IOM_15_DP")
	)
	(segment
		(start 150.414228 -24.453342)
		(end 146.72945 -21.990304)
		(width 0.14605)
		(layer "B.Cu")
		(net "PCIE_COMP_TO_IOM_15_DP")
	)
	(segment
		(start 170.75023 -138.859768)
		(end 170.749722 -138.860276)
		(width 0.14605)
		(layer "B.Cu")
		(net "PCIE_COMP_TO_IOM_15_DP")
	)
	(segment
		(start 159.821118 -40.69334)
		(end 159.735012 -40.263826)
		(width 0.14605)
		(layer "B.Cu")
		(net "PCIE_COMP_TO_IOM_15_DP")
	)
	(segment
		(start 128.700022 -33.581086)
		(end 128.700022 -33.200086)
		(width 0.14605)
		(layer "B.Cu")
		(net "PCIE_COMP_TO_IOM_15_DP")
	)
	(segment
		(start 164.026088 -129.645918)
		(end 170.79722 -95.57766)
		(width 0.14605)
		(layer "B.Cu")
		(net "PCIE_COMP_TO_IOM_15_DP")
	)
	(segment
		(start 159.238188 -38.556438)
		(end 159.357822 -38.377114)
		(width 0.14605)
		(layer "B.Cu")
		(net "PCIE_COMP_TO_IOM_15_DP")
	)
	(segment
		(start 159.701484 -40.872664)
		(end 159.821118 -40.69334)
		(width 0.14605)
		(layer "B.Cu")
		(net "PCIE_COMP_TO_IOM_15_DP")
	)
	(segment
		(start 160.198308 -42.580052)
		(end 160.018984 -42.460672)
		(width 0.14605)
		(layer "B.Cu")
		(net "PCIE_COMP_TO_IOM_15_DP")
	)
	(segment
		(start 171.068492 -138.94943)
		(end 170.97883 -138.859768)
		(width 0.14605)
		(layer "B.Cu")
		(net "PCIE_COMP_TO_IOM_15_DP")
	)
	(segment
		(start 166.82593 -138.584686)
		(end 165.370256 -136.559544)
		(width 0.14605)
		(layer "B.Cu")
		(net "PCIE_COMP_TO_IOM_15_DP")
	)
	(segment
		(start 160.052512 -41.85158)
		(end 159.96666 -41.422066)
		(width 0.14605)
		(layer "B.Cu")
		(net "PCIE_COMP_TO_IOM_15_DP")
	)
	(segment
		(start 159.787336 -41.302432)
		(end 159.701484 -40.872664)
		(width 0.14605)
		(layer "B.Cu")
		(net "PCIE_COMP_TO_IOM_15_DP")
	)
	(segment
		(start 168.68775 -139.351512)
		(end 166.82593 -138.584686)
		(width 0.14605)
		(layer "B.Cu")
		(net "PCIE_COMP_TO_IOM_15_DP")
	)
	(segment
		(start 159.735012 -40.263826)
		(end 159.555688 -40.144192)
		(width 0.14605)
		(layer "B.Cu")
		(net "PCIE_COMP_TO_IOM_15_DP")
	)
	(segment
		(start 159.933132 -42.030904)
		(end 160.052512 -41.85158)
		(width 0.14605)
		(layer "B.Cu")
		(net "PCIE_COMP_TO_IOM_15_DP")
	)
	(segment
		(start 159.503364 -39.105586)
		(end 159.32404 -38.985952)
		(width 0.14605)
		(layer "B.Cu")
		(net "PCIE_COMP_TO_IOM_15_DP")
	)
	(segment
		(start 170.79722 -95.57766)
		(end 160.198308 -42.580052)
		(width 0.14605)
		(layer "B.Cu")
		(net "PCIE_COMP_TO_IOM_15_DP")
	)
	(segment
		(start 160.018984 -42.460672)
		(end 159.933132 -42.030904)
		(width 0.14605)
		(layer "B.Cu")
		(net "PCIE_COMP_TO_IOM_15_DP")
	)
	(segment
		(start 170.749722 -138.860276)
		(end 170.749722 -138.860022)
		(width 0.14605)
		(layer "B.Cu")
		(net "PCIE_COMP_TO_IOM_15_DP")
	)
	(segment
		(start 159.32404 -38.985952)
		(end 159.238188 -38.556438)
		(width 0.14605)
		(layer "B.Cu")
		(net "PCIE_COMP_TO_IOM_15_DP")
	)
	(segment
		(start 159.168846 -37.43198)
		(end 150.414228 -24.453342)
		(width 0.14605)
		(layer "B.Cu")
		(net "PCIE_COMP_TO_IOM_15_DP")
	)
	(segment
		(start 159.58947 -39.535354)
		(end 159.503364 -39.105586)
		(width 0.14605)
		(layer "B.Cu")
		(net "PCIE_COMP_TO_IOM_15_DP")
	)
	(segment
		(start 146.72945 -21.990304)
		(end 145.15846 -21.676106)
		(width 0.14605)
		(layer "B.Cu")
		(net "PCIE_COMP_TO_IOM_15_DP")
	)
	(segment
		(start 169.856658 -139.351512)
		(end 168.68775 -139.351512)
		(width 0.14605)
		(layer "B.Cu")
		(net "PCIE_COMP_TO_IOM_15_DP")
	)
	(segment
		(start 136.107424 -21.676106)
		(end 127.936244 -29.847286)
		(width 0.14605)
		(layer "B.Cu")
		(net "PCIE_COMP_TO_IOM_15_DP")
	)
	(segment
		(start 159.96666 -41.422066)
		(end 159.787336 -41.302432)
		(width 0.14605)
		(layer "B.Cu")
		(net "PCIE_COMP_TO_IOM_15_DP")
	)
	(segment
		(start 159.357822 -38.377114)
		(end 159.168846 -37.43198)
		(width 0.14605)
		(layer "B.Cu")
		(net "PCIE_COMP_TO_IOM_15_DP")
	)
	(segment
		(start 145.15846 -21.676106)
		(end 136.107424 -21.676106)
		(width 0.14605)
		(layer "B.Cu")
		(net "PCIE_COMP_TO_IOM_15_DP")
	)
	(segment
		(start 127.936244 -29.847286)
		(end 127.936244 -33.500822)
		(width 0.14605)
		(layer "B.Cu")
		(net "PCIE_COMP_TO_IOM_15_DP")
	)
	(segment
		(start 159.469836 -39.714678)
		(end 159.58947 -39.535354)
		(width 0.14605)
		(layer "B.Cu")
		(net "PCIE_COMP_TO_IOM_15_DP")
	)
	(segment
		(start 128.180084 -33.744662)
		(end 128.536446 -33.744662)
		(width 0.14605)
		(layer "B.Cu")
		(net "PCIE_COMP_TO_IOM_15_DP")
	)
	(segment
		(start 159.555688 -40.144192)
		(end 159.469836 -39.714678)
		(width 0.14605)
		(layer "B.Cu")
		(net "PCIE_COMP_TO_IOM_15_DP")
	)
	(arc
		(start 128.536446 -33.744662)
		(mid 128.652112 -33.696752)
		(end 128.700022 -33.581086)
		(width 0.14605)
		(layer "B.Cu")
		(net "PCIE_COMP_TO_IOM_15_DP")
	)
	(arc
		(start 170.97883 -138.859768)
		(mid 170.86453 -138.812423)
		(end 170.75023 -138.859768)
		(width 0.14605)
		(layer "B.Cu")
		(net "PCIE_COMP_TO_IOM_15_DP")
	)
	(arc
		(start 127.936244 -33.500822)
		(mid 128.007663 -33.673243)
		(end 128.180084 -33.744662)
		(width 0.14605)
		(layer "B.Cu")
		(net "PCIE_COMP_TO_IOM_15_DP")
	)
	(arc
		(start 170.541188 -139.068302)
		(mid 170.227093 -139.277988)
		(end 169.856658 -139.351512)
		(width 0.14605)
		(layer "B.Cu")
		(net "PCIE_COMP_TO_IOM_15_DP")
	)
	(segment
		(start 170.440096 -138.321034)
		(end 170.529758 -138.410696)
		(width 0.14605)
		(layer "F.Cu")
		(net "PCIE_COMP_TO_IOM_15_DN")
	)
	(segment
		(start 172.649896 -135.71982)
		(end 172.649896 -134.875016)
		(width 0.14605)
		(layer "F.Cu")
		(net "PCIE_COMP_TO_IOM_15_DN")
	)
	(segment
		(start 172.737526 -135.80745)
		(end 172.649896 -135.71982)
		(width 0.14605)
		(layer "F.Cu")
		(net "PCIE_COMP_TO_IOM_15_DN")
	)
	(segment
		(start 172.737526 -136.432036)
		(end 172.737526 -135.80745)
		(width 0.14605)
		(layer "F.Cu")
		(net "PCIE_COMP_TO_IOM_15_DN")
	)
	(segment
		(start 170.758866 -138.410696)
		(end 172.737526 -136.432036)
		(width 0.14605)
		(layer "F.Cu")
		(net "PCIE_COMP_TO_IOM_15_DN")
	)
	(arc
		(start 170.529758 -138.410696)
		(mid 170.644312 -138.458146)
		(end 170.758866 -138.410696)
		(width 0.14605)
		(layer "F.Cu")
		(net "PCIE_COMP_TO_IOM_15_DN")
	)
	(segment
		(start 145.189448 -21.364956)
		(end 135.978392 -21.364956)
		(width 0.14605)
		(layer "B.Cu")
		(net "PCIE_COMP_TO_IOM_15_DN")
	)
	(segment
		(start 159.66313 -38.3159)
		(end 159.66313 -38.316154)
		(width 0.14605)
		(layer "B.Cu")
		(net "PCIE_COMP_TO_IOM_15_DN")
	)
	(segment
		(start 167.026844 -138.330686)
		(end 165.662864 -136.433052)
		(width 0.14605)
		(layer "B.Cu")
		(net "PCIE_COMP_TO_IOM_15_DN")
	)
	(segment
		(start 148.744432 -22.96287)
		(end 146.851116 -21.697188)
		(width 0.14605)
		(layer "B.Cu")
		(net "PCIE_COMP_TO_IOM_15_DN")
	)
	(segment
		(start 146.851116 -21.697188)
		(end 145.189448 -21.364956)
		(width 0.14605)
		(layer "B.Cu")
		(net "PCIE_COMP_TO_IOM_15_DN")
	)
	(segment
		(start 127.625094 -29.718254)
		(end 127.625094 -33.500822)
		(width 0.14605)
		(layer "B.Cu")
		(net "PCIE_COMP_TO_IOM_15_DN")
	)
	(segment
		(start 128.180084 -34.055812)
		(end 128.5367 -34.055812)
		(width 0.14605)
		(layer "B.Cu")
		(net "PCIE_COMP_TO_IOM_15_DN")
	)
	(segment
		(start 169.856912 -139.040362)
		(end 168.749472 -139.040362)
		(width 0.14605)
		(layer "B.Cu")
		(net "PCIE_COMP_TO_IOM_15_DN")
	)
	(segment
		(start 128.700022 -34.219134)
		(end 128.700022 -34.600134)
		(width 0.14605)
		(layer "B.Cu")
		(net "PCIE_COMP_TO_IOM_15_DN")
	)
	(segment
		(start 170.440096 -138.321034)
		(end 170.529758 -138.410696)
		(width 0.14605)
		(layer "B.Cu")
		(net "PCIE_COMP_TO_IOM_15_DN")
	)
	(segment
		(start 171.11472 -95.577406)
		(end 160.478216 -42.3926)
		(width 0.14605)
		(layer "B.Cu")
		(net "PCIE_COMP_TO_IOM_15_DN")
	)
	(segment
		(start 159.461962 -37.309552)
		(end 150.638002 -24.228552)
		(width 0.14605)
		(layer "B.Cu")
		(net "PCIE_COMP_TO_IOM_15_DN")
	)
	(segment
		(start 135.978392 -21.364956)
		(end 127.625094 -29.718254)
		(width 0.14605)
		(layer "B.Cu")
		(net "PCIE_COMP_TO_IOM_15_DN")
	)
	(segment
		(start 159.66313 -38.316154)
		(end 159.461962 -37.309552)
		(width 0.14605)
		(layer "B.Cu")
		(net "PCIE_COMP_TO_IOM_15_DN")
	)
	(segment
		(start 165.662864 -136.433052)
		(end 164.343334 -129.64668)
		(width 0.14605)
		(layer "B.Cu")
		(net "PCIE_COMP_TO_IOM_15_DN")
	)
	(segment
		(start 160.478216 -42.3926)
		(end 160.47847 -42.3926)
		(width 0.14605)
		(layer "B.Cu")
		(net "PCIE_COMP_TO_IOM_15_DN")
	)
	(segment
		(start 150.638002 -24.228552)
		(end 148.744432 -22.96287)
		(width 0.14605)
		(layer "B.Cu")
		(net "PCIE_COMP_TO_IOM_15_DN")
	)
	(segment
		(start 160.47847 -42.3926)
		(end 159.66313 -38.3159)
		(width 0.14605)
		(layer "B.Cu")
		(net "PCIE_COMP_TO_IOM_15_DN")
	)
	(segment
		(start 170.529758 -138.639804)
		(end 170.321224 -138.848084)
		(width 0.14605)
		(layer "B.Cu")
		(net "PCIE_COMP_TO_IOM_15_DN")
	)
	(segment
		(start 164.343334 -129.64668)
		(end 171.11472 -95.577406)
		(width 0.14605)
		(layer "B.Cu")
		(net "PCIE_COMP_TO_IOM_15_DN")
	)
	(segment
		(start 168.749472 -139.040362)
		(end 167.026844 -138.330686)
		(width 0.14605)
		(layer "B.Cu")
		(net "PCIE_COMP_TO_IOM_15_DN")
	)
	(arc
		(start 127.625094 -33.500822)
		(mid 127.787647 -33.893259)
		(end 128.180084 -34.055812)
		(width 0.14605)
		(layer "B.Cu")
		(net "PCIE_COMP_TO_IOM_15_DN")
	)
	(arc
		(start 170.321224 -138.848084)
		(mid 170.108196 -138.990425)
		(end 169.856912 -139.040362)
		(width 0.14605)
		(layer "B.Cu")
		(net "PCIE_COMP_TO_IOM_15_DN")
	)
	(arc
		(start 170.529758 -138.410696)
		(mid 170.577208 -138.52525)
		(end 170.529758 -138.639804)
		(width 0.14605)
		(layer "B.Cu")
		(net "PCIE_COMP_TO_IOM_15_DN")
	)
	(arc
		(start 128.5367 -34.055812)
		(mid 128.652186 -34.103648)
		(end 128.700022 -34.219134)
		(width 0.14605)
		(layer "B.Cu")
		(net "PCIE_COMP_TO_IOM_15_DN")
	)
	(segment
		(start 175.262286 -140.27531)
		(end 175.59274 -140.27531)
		(width 0.14605)
		(layer "F.Cu")
		(net "PCIE_COMP_TO_IOM_14_DP")
	)
	(segment
		(start 176.055528 -135.806942)
		(end 176.150016 -135.712454)
		(width 0.14605)
		(layer "F.Cu")
		(net "PCIE_COMP_TO_IOM_14_DP")
	)
	(segment
		(start 174.833026 -140.543026)
		(end 174.986442 -140.38961)
		(width 0.14605)
		(layer "F.Cu")
		(net "PCIE_COMP_TO_IOM_14_DP")
	)
	(segment
		(start 176.055528 -136.365488)
		(end 176.055528 -135.806942)
		(width 0.14605)
		(layer "F.Cu")
		(net "PCIE_COMP_TO_IOM_14_DP")
	)
	(segment
		(start 176.221898 -136.531858)
		(end 176.055528 -136.365488)
		(width 0.14605)
		(layer "F.Cu")
		(net "PCIE_COMP_TO_IOM_14_DP")
	)
	(segment
		(start 176.150016 -135.712454)
		(end 176.150016 -134.875016)
		(width 0.14605)
		(layer "F.Cu")
		(net "PCIE_COMP_TO_IOM_14_DP")
	)
	(segment
		(start 174.922688 -140.861288)
		(end 174.833026 -140.771626)
		(width 0.14605)
		(layer "F.Cu")
		(net "PCIE_COMP_TO_IOM_14_DP")
	)
	(segment
		(start 176.221898 -139.646152)
		(end 176.221898 -136.531858)
		(width 0.14605)
		(layer "F.Cu")
		(net "PCIE_COMP_TO_IOM_14_DP")
	)
	(arc
		(start 175.59274 -140.27531)
		(mid 176.037622 -140.091034)
		(end 176.221898 -139.646152)
		(width 0.14605)
		(layer "F.Cu")
		(net "PCIE_COMP_TO_IOM_14_DP")
	)
	(arc
		(start 174.833026 -140.771626)
		(mid 174.785681 -140.657326)
		(end 174.833026 -140.543026)
		(width 0.14605)
		(layer "F.Cu")
		(net "PCIE_COMP_TO_IOM_14_DP")
	)
	(arc
		(start 174.986442 -140.38961)
		(mid 175.113 -140.305046)
		(end 175.262286 -140.27531)
		(width 0.14605)
		(layer "F.Cu")
		(net "PCIE_COMP_TO_IOM_14_DP")
	)
	(segment
		(start 129.755646 -29.654754)
		(end 129.755646 -32.327596)
		(width 0.14605)
		(layer "B.Cu")
		(net "PCIE_COMP_TO_IOM_14_DP")
	)
	(segment
		(start 157.79115 -39.433754)
		(end 157.705298 -39.003986)
		(width 0.14605)
		(layer "B.Cu")
		(net "PCIE_COMP_TO_IOM_14_DP")
	)
	(segment
		(start 145.391124 -23.261574)
		(end 144.448276 -23.073106)
		(width 0.14605)
		(layer "B.Cu")
		(net "PCIE_COMP_TO_IOM_14_DP")
	)
	(segment
		(start 130.499866 -32.38119)
		(end 130.499866 -32.00019)
		(width 0.14605)
		(layer "B.Cu")
		(net "PCIE_COMP_TO_IOM_14_DP")
	)
	(segment
		(start 136.337294 -23.073106)
		(end 129.755646 -29.654754)
		(width 0.14605)
		(layer "B.Cu")
		(net "PCIE_COMP_TO_IOM_14_DP")
	)
	(segment
		(start 158.05658 -39.982902)
		(end 157.970474 -39.553134)
		(width 0.14605)
		(layer "B.Cu")
		(net "PCIE_COMP_TO_IOM_14_DP")
	)
	(segment
		(start 158.519622 -42.299128)
		(end 158.43377 -41.869614)
		(width 0.14605)
		(layer "B.Cu")
		(net "PCIE_COMP_TO_IOM_14_DP")
	)
	(segment
		(start 165.400482 -139.081002)
		(end 164.130482 -137.198354)
		(width 0.14605)
		(layer "B.Cu")
		(net "PCIE_COMP_TO_IOM_14_DP")
	)
	(segment
		(start 158.665164 -43.0276)
		(end 158.486094 -42.90822)
		(width 0.14605)
		(layer "B.Cu")
		(net "PCIE_COMP_TO_IOM_14_DP")
	)
	(segment
		(start 158.43377 -41.869614)
		(end 158.254446 -41.74998)
		(width 0.14605)
		(layer "B.Cu")
		(net "PCIE_COMP_TO_IOM_14_DP")
	)
	(segment
		(start 162.57905 -129.217674)
		(end 169.2402 -95.905574)
		(width 0.14605)
		(layer "B.Cu")
		(net "PCIE_COMP_TO_IOM_14_DP")
	)
	(segment
		(start 146.33321 -23.449788)
		(end 146.148806 -23.412958)
		(width 0.14605)
		(layer "B.Cu")
		(net "PCIE_COMP_TO_IOM_14_DP")
	)
	(segment
		(start 164.130482 -137.198354)
		(end 162.57905 -129.217674)
		(width 0.14605)
		(layer "B.Cu")
		(net "PCIE_COMP_TO_IOM_14_DP")
	)
	(segment
		(start 174.604426 -140.771626)
		(end 174.603918 -140.772134)
		(width 0.14605)
		(layer "B.Cu")
		(net "PCIE_COMP_TO_IOM_14_DP")
	)
	(segment
		(start 158.254446 -41.74998)
		(end 158.168594 -41.320466)
		(width 0.14605)
		(layer "B.Cu")
		(net "PCIE_COMP_TO_IOM_14_DP")
	)
	(segment
		(start 169.2402 -95.905574)
		(end 158.665164 -43.0276)
		(width 0.14605)
		(layer "B.Cu")
		(net "PCIE_COMP_TO_IOM_14_DP")
	)
	(segment
		(start 172.488098 -141.278102)
		(end 167.118538 -140.240512)
		(width 0.14605)
		(layer "B.Cu")
		(net "PCIE_COMP_TO_IOM_14_DP")
	)
	(segment
		(start 158.202122 -40.711374)
		(end 158.022798 -40.59174)
		(width 0.14605)
		(layer "B.Cu")
		(net "PCIE_COMP_TO_IOM_14_DP")
	)
	(segment
		(start 158.288228 -41.141142)
		(end 158.202122 -40.711374)
		(width 0.14605)
		(layer "B.Cu")
		(net "PCIE_COMP_TO_IOM_14_DP")
	)
	(segment
		(start 149.335236 -25.467056)
		(end 146.33321 -23.449788)
		(width 0.14605)
		(layer "B.Cu")
		(net "PCIE_COMP_TO_IOM_14_DP")
	)
	(segment
		(start 173.675294 -141.278102)
		(end 172.488098 -141.278102)
		(width 0.14605)
		(layer "B.Cu")
		(net "PCIE_COMP_TO_IOM_14_DP")
	)
	(segment
		(start 157.605476 -37.727382)
		(end 149.335236 -25.467056)
		(width 0.14605)
		(layer "B.Cu")
		(net "PCIE_COMP_TO_IOM_14_DP")
	)
	(segment
		(start 146.148806 -23.412958)
		(end 145.391124 -23.261574)
		(width 0.14605)
		(layer "B.Cu")
		(net "PCIE_COMP_TO_IOM_14_DP")
	)
	(segment
		(start 174.603918 -140.77188)
		(end 174.395384 -140.98016)
		(width 0.14605)
		(layer "B.Cu")
		(net "PCIE_COMP_TO_IOM_14_DP")
	)
	(segment
		(start 129.972562 -32.544512)
		(end 130.336544 -32.544512)
		(width 0.14605)
		(layer "B.Cu")
		(net "PCIE_COMP_TO_IOM_14_DP")
	)
	(segment
		(start 158.022798 -40.59174)
		(end 157.936946 -40.162226)
		(width 0.14605)
		(layer "B.Cu")
		(net "PCIE_COMP_TO_IOM_14_DP")
	)
	(segment
		(start 167.118538 -140.240512)
		(end 165.400482 -139.081002)
		(width 0.14605)
		(layer "B.Cu")
		(net "PCIE_COMP_TO_IOM_14_DP")
	)
	(segment
		(start 157.970474 -39.553134)
		(end 157.79115 -39.433754)
		(width 0.14605)
		(layer "B.Cu")
		(net "PCIE_COMP_TO_IOM_14_DP")
	)
	(segment
		(start 157.705298 -39.003986)
		(end 157.824932 -38.824662)
		(width 0.14605)
		(layer "B.Cu")
		(net "PCIE_COMP_TO_IOM_14_DP")
	)
	(segment
		(start 158.486094 -42.90822)
		(end 158.400242 -42.478452)
		(width 0.14605)
		(layer "B.Cu")
		(net "PCIE_COMP_TO_IOM_14_DP")
	)
	(segment
		(start 158.400242 -42.478452)
		(end 158.519622 -42.299128)
		(width 0.14605)
		(layer "B.Cu")
		(net "PCIE_COMP_TO_IOM_14_DP")
	)
	(segment
		(start 157.936946 -40.162226)
		(end 158.05658 -39.982902)
		(width 0.14605)
		(layer "B.Cu")
		(net "PCIE_COMP_TO_IOM_14_DP")
	)
	(segment
		(start 174.922688 -140.861288)
		(end 174.833026 -140.771626)
		(width 0.14605)
		(layer "B.Cu")
		(net "PCIE_COMP_TO_IOM_14_DP")
	)
	(segment
		(start 158.168594 -41.320466)
		(end 158.288228 -41.141142)
		(width 0.14605)
		(layer "B.Cu")
		(net "PCIE_COMP_TO_IOM_14_DP")
	)
	(segment
		(start 157.824932 -38.824662)
		(end 157.605476 -37.727382)
		(width 0.14605)
		(layer "B.Cu")
		(net "PCIE_COMP_TO_IOM_14_DP")
	)
	(segment
		(start 144.448276 -23.073106)
		(end 136.337294 -23.073106)
		(width 0.14605)
		(layer "B.Cu")
		(net "PCIE_COMP_TO_IOM_14_DP")
	)
	(segment
		(start 174.603918 -140.772134)
		(end 174.603918 -140.77188)
		(width 0.14605)
		(layer "B.Cu")
		(net "PCIE_COMP_TO_IOM_14_DP")
	)
	(arc
		(start 130.336544 -32.544512)
		(mid 130.45203 -32.496676)
		(end 130.499866 -32.38119)
		(width 0.14605)
		(layer "B.Cu")
		(net "PCIE_COMP_TO_IOM_14_DP")
	)
	(arc
		(start 174.395384 -140.98016)
		(mid 174.064974 -141.200747)
		(end 173.675294 -141.278102)
		(width 0.14605)
		(layer "B.Cu")
		(net "PCIE_COMP_TO_IOM_14_DP")
	)
	(arc
		(start 129.755646 -32.327596)
		(mid 129.819179 -32.480979)
		(end 129.972562 -32.544512)
		(width 0.14605)
		(layer "B.Cu")
		(net "PCIE_COMP_TO_IOM_14_DP")
	)
	(arc
		(start 174.833026 -140.771626)
		(mid 174.718726 -140.724281)
		(end 174.604426 -140.771626)
		(width 0.14605)
		(layer "B.Cu")
		(net "PCIE_COMP_TO_IOM_14_DP")
	)
	(segment
		(start 174.613062 -140.322808)
		(end 174.766224 -140.169392)
		(width 0.14605)
		(layer "F.Cu")
		(net "PCIE_COMP_TO_IOM_14_DN")
	)
	(segment
		(start 175.262032 -139.96416)
		(end 175.59274 -139.96416)
		(width 0.14605)
		(layer "F.Cu")
		(net "PCIE_COMP_TO_IOM_14_DN")
	)
	(segment
		(start 174.613062 -140.322554)
		(end 174.613062 -140.322808)
		(width 0.14605)
		(layer "F.Cu")
		(net "PCIE_COMP_TO_IOM_14_DN")
	)
	(segment
		(start 175.64989 -135.71982)
		(end 175.64989 -134.875016)
		(width 0.14605)
		(layer "F.Cu")
		(net "PCIE_COMP_TO_IOM_14_DN")
	)
	(segment
		(start 174.766224 -140.169392)
		(end 174.766478 -140.169392)
		(width 0.14605)
		(layer "F.Cu")
		(net "PCIE_COMP_TO_IOM_14_DN")
	)
	(segment
		(start 175.910748 -136.66089)
		(end 175.744378 -136.49452)
		(width 0.14605)
		(layer "F.Cu")
		(net "PCIE_COMP_TO_IOM_14_DN")
	)
	(segment
		(start 175.744378 -135.814308)
		(end 175.64989 -135.71982)
		(width 0.14605)
		(layer "F.Cu")
		(net "PCIE_COMP_TO_IOM_14_DN")
	)
	(segment
		(start 175.910748 -139.646152)
		(end 175.910748 -136.66089)
		(width 0.14605)
		(layer "F.Cu")
		(net "PCIE_COMP_TO_IOM_14_DN")
	)
	(segment
		(start 175.744378 -136.49452)
		(end 175.744378 -135.814308)
		(width 0.14605)
		(layer "F.Cu")
		(net "PCIE_COMP_TO_IOM_14_DN")
	)
	(segment
		(start 174.294292 -140.232892)
		(end 174.383954 -140.322554)
		(width 0.14605)
		(layer "F.Cu")
		(net "PCIE_COMP_TO_IOM_14_DN")
	)
	(arc
		(start 175.59274 -139.96416)
		(mid 175.817606 -139.871018)
		(end 175.910748 -139.646152)
		(width 0.14605)
		(layer "F.Cu")
		(net "PCIE_COMP_TO_IOM_14_DN")
	)
	(arc
		(start 174.766478 -140.169392)
		(mid 174.993854 -140.017498)
		(end 175.262032 -139.96416)
		(width 0.14605)
		(layer "F.Cu")
		(net "PCIE_COMP_TO_IOM_14_DN")
	)
	(arc
		(start 174.383954 -140.322554)
		(mid 174.498508 -140.370004)
		(end 174.613062 -140.322554)
		(width 0.14605)
		(layer "F.Cu")
		(net "PCIE_COMP_TO_IOM_14_DN")
	)
	(segment
		(start 158.13024 -38.763448)
		(end 157.898592 -37.604954)
		(width 0.14605)
		(layer "B.Cu")
		(net "PCIE_COMP_TO_IOM_14_DN")
	)
	(segment
		(start 173.675548 -140.966952)
		(end 172.51807 -140.966952)
		(width 0.14605)
		(layer "B.Cu")
		(net "PCIE_COMP_TO_IOM_14_DN")
	)
	(segment
		(start 174.294292 -140.232892)
		(end 174.383954 -140.322554)
		(width 0.14605)
		(layer "B.Cu")
		(net "PCIE_COMP_TO_IOM_14_DN")
	)
	(segment
		(start 158.945326 -42.840148)
		(end 158.94558 -42.840148)
		(width 0.14605)
		(layer "B.Cu")
		(net "PCIE_COMP_TO_IOM_14_DN")
	)
	(segment
		(start 130.499866 -33.018984)
		(end 130.499866 -33.399984)
		(width 0.14605)
		(layer "B.Cu")
		(net "PCIE_COMP_TO_IOM_14_DN")
	)
	(segment
		(start 146.45513 -23.156672)
		(end 144.479264 -22.761956)
		(width 0.14605)
		(layer "B.Cu")
		(net "PCIE_COMP_TO_IOM_14_DN")
	)
	(segment
		(start 165.624764 -138.856974)
		(end 164.424106 -137.076688)
		(width 0.14605)
		(layer "B.Cu")
		(net "PCIE_COMP_TO_IOM_14_DN")
	)
	(segment
		(start 169.5577 -95.905574)
		(end 158.945326 -42.840148)
		(width 0.14605)
		(layer "B.Cu")
		(net "PCIE_COMP_TO_IOM_14_DN")
	)
	(segment
		(start 164.424106 -137.076688)
		(end 162.896296 -129.218436)
		(width 0.14605)
		(layer "B.Cu")
		(net "PCIE_COMP_TO_IOM_14_DN")
	)
	(segment
		(start 157.898592 -37.604954)
		(end 149.559264 -25.24252)
		(width 0.14605)
		(layer "B.Cu")
		(net "PCIE_COMP_TO_IOM_14_DN")
	)
	(segment
		(start 162.89655 -129.218436)
		(end 169.5577 -95.905574)
		(width 0.14605)
		(layer "B.Cu")
		(net "PCIE_COMP_TO_IOM_14_DN")
	)
	(segment
		(start 158.94558 -42.840148)
		(end 158.13024 -38.763448)
		(width 0.14605)
		(layer "B.Cu")
		(net "PCIE_COMP_TO_IOM_14_DN")
	)
	(segment
		(start 174.383954 -140.551662)
		(end 174.17542 -140.759942)
		(width 0.14605)
		(layer "B.Cu")
		(net "PCIE_COMP_TO_IOM_14_DN")
	)
	(segment
		(start 144.479264 -22.761956)
		(end 136.208262 -22.761956)
		(width 0.14605)
		(layer "B.Cu")
		(net "PCIE_COMP_TO_IOM_14_DN")
	)
	(segment
		(start 172.51807 -140.966952)
		(end 167.23995 -139.946888)
		(width 0.14605)
		(layer "B.Cu")
		(net "PCIE_COMP_TO_IOM_14_DN")
	)
	(segment
		(start 167.23995 -139.946888)
		(end 165.624764 -138.856974)
		(width 0.14605)
		(layer "B.Cu")
		(net "PCIE_COMP_TO_IOM_14_DN")
	)
	(segment
		(start 136.208262 -22.761956)
		(end 129.444496 -29.525722)
		(width 0.14605)
		(layer "B.Cu")
		(net "PCIE_COMP_TO_IOM_14_DN")
	)
	(segment
		(start 129.444496 -29.525722)
		(end 129.444496 -32.327596)
		(width 0.14605)
		(layer "B.Cu")
		(net "PCIE_COMP_TO_IOM_14_DN")
	)
	(segment
		(start 162.896296 -129.218436)
		(end 162.89655 -129.218436)
		(width 0.14605)
		(layer "B.Cu")
		(net "PCIE_COMP_TO_IOM_14_DN")
	)
	(segment
		(start 129.972562 -32.855662)
		(end 130.336544 -32.855662)
		(width 0.14605)
		(layer "B.Cu")
		(net "PCIE_COMP_TO_IOM_14_DN")
	)
	(segment
		(start 149.559264 -25.24252)
		(end 146.45513 -23.156672)
		(width 0.14605)
		(layer "B.Cu")
		(net "PCIE_COMP_TO_IOM_14_DN")
	)
	(arc
		(start 130.336544 -32.855662)
		(mid 130.45203 -32.903498)
		(end 130.499866 -33.018984)
		(width 0.14605)
		(layer "B.Cu")
		(net "PCIE_COMP_TO_IOM_14_DN")
	)
	(arc
		(start 129.444496 -32.327596)
		(mid 129.599163 -32.700995)
		(end 129.972562 -32.855662)
		(width 0.14605)
		(layer "B.Cu")
		(net "PCIE_COMP_TO_IOM_14_DN")
	)
	(arc
		(start 174.383954 -140.322554)
		(mid 174.431404 -140.437108)
		(end 174.383954 -140.551662)
		(width 0.14605)
		(layer "B.Cu")
		(net "PCIE_COMP_TO_IOM_14_DN")
	)
	(arc
		(start 174.17542 -140.759942)
		(mid 173.946077 -140.913184)
		(end 173.675548 -140.966952)
		(width 0.14605)
		(layer "B.Cu")
		(net "PCIE_COMP_TO_IOM_14_DN")
	)
	(segment
		(start 180.374036 -138.805412)
		(end 180.373782 -138.805412)
		(width 0.14605)
		(layer "F.Cu")
		(net "PCIE_COMP_TO_IOM_13_DP")
	)
	(segment
		(start 179.152296 -134.877302)
		(end 179.15001 -134.875016)
		(width 0.14605)
		(layer "F.Cu")
		(net "PCIE_COMP_TO_IOM_13_DP")
	)
	(segment
		(start 179.152296 -135.710168)
		(end 179.152296 -134.877302)
		(width 0.14605)
		(layer "F.Cu")
		(net "PCIE_COMP_TO_IOM_13_DP")
	)
	(segment
		(start 180.758592 -139.189968)
		(end 180.374036 -138.805412)
		(width 0.14605)
		(layer "F.Cu")
		(net "PCIE_COMP_TO_IOM_13_DP")
	)
	(segment
		(start 180.543962 -140.479018)
		(end 180.758592 -140.264388)
		(width 0.14605)
		(layer "F.Cu")
		(net "PCIE_COMP_TO_IOM_13_DP")
	)
	(segment
		(start 180.633624 -140.79728)
		(end 180.543962 -140.707618)
		(width 0.14605)
		(layer "F.Cu")
		(net "PCIE_COMP_TO_IOM_13_DP")
	)
	(segment
		(start 179.048664 -137.480294)
		(end 179.048664 -135.8138)
		(width 0.14605)
		(layer "F.Cu")
		(net "PCIE_COMP_TO_IOM_13_DP")
	)
	(segment
		(start 180.373782 -138.805412)
		(end 179.048664 -137.480294)
		(width 0.14605)
		(layer "F.Cu")
		(net "PCIE_COMP_TO_IOM_13_DP")
	)
	(segment
		(start 179.048664 -135.8138)
		(end 179.152296 -135.710168)
		(width 0.14605)
		(layer "F.Cu")
		(net "PCIE_COMP_TO_IOM_13_DP")
	)
	(arc
		(start 180.543962 -140.707618)
		(mid 180.496617 -140.593318)
		(end 180.543962 -140.479018)
		(width 0.14605)
		(layer "F.Cu")
		(net "PCIE_COMP_TO_IOM_13_DP")
	)
	(arc
		(start 180.758592 -140.264388)
		(mid 180.981112 -139.727178)
		(end 180.758592 -139.189968)
		(width 0.14605)
		(layer "F.Cu")
		(net "PCIE_COMP_TO_IOM_13_DP")
	)
	(segment
		(start 155.952952 -38.472872)
		(end 147.793964 -26.375868)
		(width 0.14605)
		(layer "B.Cu")
		(net "PCIE_COMP_TO_IOM_13_DP")
	)
	(segment
		(start 164.191188 -139.655804)
		(end 162.996118 -137.884408)
		(width 0.14605)
		(layer "B.Cu")
		(net "PCIE_COMP_TO_IOM_13_DP")
	)
	(segment
		(start 131.780026 -33.744662)
		(end 132.136388 -33.744662)
		(width 0.14605)
		(layer "B.Cu")
		(net "PCIE_COMP_TO_IOM_13_DP")
	)
	(segment
		(start 156.419804 -40.807132)
		(end 156.333698 -40.377618)
		(width 0.14605)
		(layer "B.Cu")
		(net "PCIE_COMP_TO_IOM_13_DP")
	)
	(segment
		(start 156.068522 -39.82847)
		(end 156.188156 -39.649146)
		(width 0.14605)
		(layer "B.Cu")
		(net "PCIE_COMP_TO_IOM_13_DP")
	)
	(segment
		(start 131.55549 -29.50591)
		(end 131.55549 -33.520126)
		(width 0.14605)
		(layer "B.Cu")
		(net "PCIE_COMP_TO_IOM_13_DP")
	)
	(segment
		(start 167.020748 -141.563598)
		(end 166.286688 -141.068552)
		(width 0.14605)
		(layer "B.Cu")
		(net "PCIE_COMP_TO_IOM_13_DP")
	)
	(segment
		(start 156.763466 -43.302936)
		(end 156.8831 -43.123612)
		(width 0.14605)
		(layer "B.Cu")
		(net "PCIE_COMP_TO_IOM_13_DP")
	)
	(segment
		(start 156.565346 -41.535858)
		(end 156.386022 -41.416224)
		(width 0.14605)
		(layer "B.Cu")
		(net "PCIE_COMP_TO_IOM_13_DP")
	)
	(segment
		(start 156.386022 -41.416224)
		(end 156.30017 -40.986456)
		(width 0.14605)
		(layer "B.Cu")
		(net "PCIE_COMP_TO_IOM_13_DP")
	)
	(segment
		(start 156.333698 -40.377618)
		(end 156.154374 -40.257984)
		(width 0.14605)
		(layer "B.Cu")
		(net "PCIE_COMP_TO_IOM_13_DP")
	)
	(segment
		(start 180.315362 -140.707618)
		(end 180.314854 -140.708126)
		(width 0.14605)
		(layer "B.Cu")
		(net "PCIE_COMP_TO_IOM_13_DP")
	)
	(segment
		(start 147.793964 -26.375868)
		(end 145.51533 -24.854154)
		(width 0.14605)
		(layer "B.Cu")
		(net "PCIE_COMP_TO_IOM_13_DP")
	)
	(segment
		(start 156.651452 -41.965372)
		(end 156.565346 -41.535858)
		(width 0.14605)
		(layer "B.Cu")
		(net "PCIE_COMP_TO_IOM_13_DP")
	)
	(segment
		(start 167.681402 -97.112582)
		(end 157.028642 -43.852084)
		(width 0.14605)
		(layer "B.Cu")
		(net "PCIE_COMP_TO_IOM_13_DP")
	)
	(segment
		(start 156.8831 -43.123612)
		(end 156.796994 -42.693844)
		(width 0.14605)
		(layer "B.Cu")
		(net "PCIE_COMP_TO_IOM_13_DP")
	)
	(segment
		(start 156.30017 -40.986456)
		(end 156.419804 -40.807132)
		(width 0.14605)
		(layer "B.Cu")
		(net "PCIE_COMP_TO_IOM_13_DP")
	)
	(segment
		(start 145.51533 -24.854154)
		(end 142.38732 -24.228806)
		(width 0.14605)
		(layer "B.Cu")
		(net "PCIE_COMP_TO_IOM_13_DP")
	)
	(segment
		(start 142.38732 -24.228806)
		(end 136.832594 -24.228806)
		(width 0.14605)
		(layer "B.Cu")
		(net "PCIE_COMP_TO_IOM_13_DP")
	)
	(segment
		(start 162.996118 -137.884408)
		(end 162.143694 -133.551168)
		(width 0.14605)
		(layer "B.Cu")
		(net "PCIE_COMP_TO_IOM_13_DP")
	)
	(segment
		(start 165.604952 -140.609066)
		(end 164.191188 -139.655804)
		(width 0.14605)
		(layer "B.Cu")
		(net "PCIE_COMP_TO_IOM_13_DP")
	)
	(segment
		(start 179.99329 -141.188948)
		(end 179.99329 -141.667738)
		(width 0.14605)
		(layer "B.Cu")
		(net "PCIE_COMP_TO_IOM_13_DP")
	)
	(segment
		(start 156.796994 -42.693844)
		(end 156.61767 -42.574464)
		(width 0.14605)
		(layer "B.Cu")
		(net "PCIE_COMP_TO_IOM_13_DP")
	)
	(segment
		(start 132.299964 -33.581086)
		(end 132.299964 -33.200086)
		(width 0.14605)
		(layer "B.Cu")
		(net "PCIE_COMP_TO_IOM_13_DP")
	)
	(segment
		(start 180.314854 -140.707872)
		(end 180.10632 -140.916152)
		(width 0.14605)
		(layer "B.Cu")
		(net "PCIE_COMP_TO_IOM_13_DP")
	)
	(segment
		(start 161.716212 -131.377436)
		(end 161.276538 -129.142998)
		(width 0.14605)
		(layer "B.Cu")
		(net "PCIE_COMP_TO_IOM_13_DP")
	)
	(segment
		(start 136.832594 -24.228806)
		(end 131.55549 -29.50591)
		(width 0.14605)
		(layer "B.Cu")
		(net "PCIE_COMP_TO_IOM_13_DP")
	)
	(segment
		(start 156.849318 -43.73245)
		(end 156.763466 -43.302936)
		(width 0.14605)
		(layer "B.Cu")
		(net "PCIE_COMP_TO_IOM_13_DP")
	)
	(segment
		(start 156.61767 -42.574464)
		(end 156.531818 -42.144696)
		(width 0.14605)
		(layer "B.Cu")
		(net "PCIE_COMP_TO_IOM_13_DP")
	)
	(segment
		(start 157.028642 -43.852084)
		(end 156.849318 -43.73245)
		(width 0.14605)
		(layer "B.Cu")
		(net "PCIE_COMP_TO_IOM_13_DP")
	)
	(segment
		(start 180.314854 -140.708126)
		(end 180.314854 -140.707872)
		(width 0.14605)
		(layer "B.Cu")
		(net "PCIE_COMP_TO_IOM_13_DP")
	)
	(segment
		(start 180.633624 -140.79728)
		(end 180.543962 -140.707618)
		(width 0.14605)
		(layer "B.Cu")
		(net "PCIE_COMP_TO_IOM_13_DP")
	)
	(segment
		(start 162.143694 -133.551168)
		(end 161.716212 -131.377436)
		(width 0.14605)
		(layer "B.Cu")
		(net "PCIE_COMP_TO_IOM_13_DP")
	)
	(segment
		(start 156.531818 -42.144696)
		(end 156.651452 -41.965372)
		(width 0.14605)
		(layer "B.Cu")
		(net "PCIE_COMP_TO_IOM_13_DP")
	)
	(segment
		(start 156.154374 -40.257984)
		(end 156.068522 -39.82847)
		(width 0.14605)
		(layer "B.Cu")
		(net "PCIE_COMP_TO_IOM_13_DP")
	)
	(segment
		(start 166.286688 -141.068552)
		(end 165.604952 -140.609066)
		(width 0.14605)
		(layer "B.Cu")
		(net "PCIE_COMP_TO_IOM_13_DP")
	)
	(segment
		(start 179.603908 -142.244826)
		(end 174.997872 -143.11503)
		(width 0.14605)
		(layer "B.Cu")
		(net "PCIE_COMP_TO_IOM_13_DP")
	)
	(segment
		(start 174.997872 -143.11503)
		(end 167.020748 -141.563598)
		(width 0.14605)
		(layer "B.Cu")
		(net "PCIE_COMP_TO_IOM_13_DP")
	)
	(segment
		(start 156.188156 -39.649146)
		(end 155.952952 -38.472872)
		(width 0.14605)
		(layer "B.Cu")
		(net "PCIE_COMP_TO_IOM_13_DP")
	)
	(segment
		(start 179.99329 -141.667738)
		(end 179.603908 -142.244826)
		(width 0.14605)
		(layer "B.Cu")
		(net "PCIE_COMP_TO_IOM_13_DP")
	)
	(segment
		(start 161.276538 -129.142998)
		(end 167.681402 -97.112582)
		(width 0.14605)
		(layer "B.Cu")
		(net "PCIE_COMP_TO_IOM_13_DP")
	)
	(arc
		(start 180.543962 -140.707618)
		(mid 180.429662 -140.660273)
		(end 180.315362 -140.707618)
		(width 0.14605)
		(layer "B.Cu")
		(net "PCIE_COMP_TO_IOM_13_DP")
	)
	(arc
		(start 131.55549 -33.520126)
		(mid 131.621255 -33.678897)
		(end 131.780026 -33.744662)
		(width 0.14605)
		(layer "B.Cu")
		(net "PCIE_COMP_TO_IOM_13_DP")
	)
	(arc
		(start 132.136388 -33.744662)
		(mid 132.252054 -33.696752)
		(end 132.299964 -33.581086)
		(width 0.14605)
		(layer "B.Cu")
		(net "PCIE_COMP_TO_IOM_13_DP")
	)
	(arc
		(start 180.10632 -140.916152)
		(mid 180.022691 -141.041312)
		(end 179.99329 -141.188948)
		(width 0.14605)
		(layer "B.Cu")
		(net "PCIE_COMP_TO_IOM_13_DP")
	)
	(segment
		(start 180.323998 -140.258546)
		(end 180.538374 -140.04417)
		(width 0.14605)
		(layer "F.Cu")
		(net "PCIE_COMP_TO_IOM_13_DN")
	)
	(segment
		(start 178.737514 -137.609326)
		(end 178.737514 -135.80745)
		(width 0.14605)
		(layer "F.Cu")
		(net "PCIE_COMP_TO_IOM_13_DN")
	)
	(segment
		(start 180.005228 -140.168884)
		(end 180.09489 -140.258546)
		(width 0.14605)
		(layer "F.Cu")
		(net "PCIE_COMP_TO_IOM_13_DN")
	)
	(segment
		(start 178.737514 -135.80745)
		(end 178.649884 -135.71982)
		(width 0.14605)
		(layer "F.Cu")
		(net "PCIE_COMP_TO_IOM_13_DN")
	)
	(segment
		(start 178.649884 -135.71982)
		(end 178.649884 -134.875016)
		(width 0.14605)
		(layer "F.Cu")
		(net "PCIE_COMP_TO_IOM_13_DN")
	)
	(segment
		(start 180.538374 -139.410186)
		(end 178.737514 -137.609326)
		(width 0.14605)
		(layer "F.Cu")
		(net "PCIE_COMP_TO_IOM_13_DN")
	)
	(arc
		(start 180.538374 -140.04417)
		(mid 180.669676 -139.727178)
		(end 180.538374 -139.410186)
		(width 0.14605)
		(layer "F.Cu")
		(net "PCIE_COMP_TO_IOM_13_DN")
	)
	(arc
		(start 180.09489 -140.258546)
		(mid 180.209444 -140.305996)
		(end 180.323998 -140.258546)
		(width 0.14605)
		(layer "F.Cu")
		(net "PCIE_COMP_TO_IOM_13_DN")
	)
	(segment
		(start 142.418308 -23.917656)
		(end 136.703562 -23.917656)
		(width 0.14605)
		(layer "B.Cu")
		(net "PCIE_COMP_TO_IOM_13_DN")
	)
	(segment
		(start 145.636742 -24.561038)
		(end 142.418308 -23.917656)
		(width 0.14605)
		(layer "B.Cu")
		(net "PCIE_COMP_TO_IOM_13_DN")
	)
	(segment
		(start 167.998902 -97.112582)
		(end 157.33395 -43.791124)
		(width 0.14605)
		(layer "B.Cu")
		(net "PCIE_COMP_TO_IOM_13_DN")
	)
	(segment
		(start 180.09489 -140.487654)
		(end 179.886356 -140.695934)
		(width 0.14605)
		(layer "B.Cu")
		(net "PCIE_COMP_TO_IOM_13_DN")
	)
	(segment
		(start 157.33395 -43.791124)
		(end 157.33395 -43.79087)
		(width 0.14605)
		(layer "B.Cu")
		(net "PCIE_COMP_TO_IOM_13_DN")
	)
	(segment
		(start 174.998634 -142.798038)
		(end 167.142414 -141.269974)
		(width 0.14605)
		(layer "B.Cu")
		(net "PCIE_COMP_TO_IOM_13_DN")
	)
	(segment
		(start 131.780026 -34.055812)
		(end 132.136642 -34.055812)
		(width 0.14605)
		(layer "B.Cu")
		(net "PCIE_COMP_TO_IOM_13_DN")
	)
	(segment
		(start 163.289488 -137.762488)
		(end 162.449256 -133.49097)
		(width 0.14605)
		(layer "B.Cu")
		(net "PCIE_COMP_TO_IOM_13_DN")
	)
	(segment
		(start 167.142414 -141.269974)
		(end 164.41547 -139.431522)
		(width 0.14605)
		(layer "B.Cu")
		(net "PCIE_COMP_TO_IOM_13_DN")
	)
	(segment
		(start 132.299964 -34.219134)
		(end 132.299964 -34.600134)
		(width 0.14605)
		(layer "B.Cu")
		(net "PCIE_COMP_TO_IOM_13_DN")
	)
	(segment
		(start 179.68214 -141.188694)
		(end 179.68214 -141.572488)
		(width 0.14605)
		(layer "B.Cu")
		(net "PCIE_COMP_TO_IOM_13_DN")
	)
	(segment
		(start 148.017738 -26.151078)
		(end 145.636742 -24.561038)
		(width 0.14605)
		(layer "B.Cu")
		(net "PCIE_COMP_TO_IOM_13_DN")
	)
	(segment
		(start 179.418488 -141.96314)
		(end 174.998634 -142.798038)
		(width 0.14605)
		(layer "B.Cu")
		(net "PCIE_COMP_TO_IOM_13_DN")
	)
	(segment
		(start 162.449256 -133.49097)
		(end 161.593784 -129.143506)
		(width 0.14605)
		(layer "B.Cu")
		(net "PCIE_COMP_TO_IOM_13_DN")
	)
	(segment
		(start 131.24434 -29.376878)
		(end 131.24434 -33.520126)
		(width 0.14605)
		(layer "B.Cu")
		(net "PCIE_COMP_TO_IOM_13_DN")
	)
	(segment
		(start 179.68214 -141.572488)
		(end 179.418488 -141.96314)
		(width 0.14605)
		(layer "B.Cu")
		(net "PCIE_COMP_TO_IOM_13_DN")
	)
	(segment
		(start 161.593784 -129.143506)
		(end 167.998902 -97.112582)
		(width 0.14605)
		(layer "B.Cu")
		(net "PCIE_COMP_TO_IOM_13_DN")
	)
	(segment
		(start 157.33395 -43.79087)
		(end 156.493464 -39.58844)
		(width 0.14605)
		(layer "B.Cu")
		(net "PCIE_COMP_TO_IOM_13_DN")
	)
	(segment
		(start 180.005228 -140.168884)
		(end 180.09489 -140.258546)
		(width 0.14605)
		(layer "B.Cu")
		(net "PCIE_COMP_TO_IOM_13_DN")
	)
	(segment
		(start 164.41547 -139.431522)
		(end 163.289488 -137.762488)
		(width 0.14605)
		(layer "B.Cu")
		(net "PCIE_COMP_TO_IOM_13_DN")
	)
	(segment
		(start 156.493464 -39.58844)
		(end 156.246068 -38.350444)
		(width 0.14605)
		(layer "B.Cu")
		(net "PCIE_COMP_TO_IOM_13_DN")
	)
	(segment
		(start 136.703562 -23.917656)
		(end 131.24434 -29.376878)
		(width 0.14605)
		(layer "B.Cu")
		(net "PCIE_COMP_TO_IOM_13_DN")
	)
	(segment
		(start 156.246068 -38.350444)
		(end 148.017738 -26.151078)
		(width 0.14605)
		(layer "B.Cu")
		(net "PCIE_COMP_TO_IOM_13_DN")
	)
	(arc
		(start 132.136642 -34.055812)
		(mid 132.252128 -34.103648)
		(end 132.299964 -34.219134)
		(width 0.14605)
		(layer "B.Cu")
		(net "PCIE_COMP_TO_IOM_13_DN")
	)
	(arc
		(start 180.09489 -140.258546)
		(mid 180.14234 -140.3731)
		(end 180.09489 -140.487654)
		(width 0.14605)
		(layer "B.Cu")
		(net "PCIE_COMP_TO_IOM_13_DN")
	)
	(arc
		(start 131.24434 -33.520126)
		(mid 131.401239 -33.898913)
		(end 131.780026 -34.055812)
		(width 0.14605)
		(layer "B.Cu")
		(net "PCIE_COMP_TO_IOM_13_DN")
	)
	(arc
		(start 179.886356 -140.695934)
		(mid 179.735211 -140.921999)
		(end 179.68214 -141.188694)
		(width 0.14605)
		(layer "B.Cu")
		(net "PCIE_COMP_TO_IOM_13_DN")
	)
	(segment
		(start 182.048658 -136.169908)
		(end 182.048658 -135.8138)
		(width 0.14605)
		(layer "F.Cu")
		(net "PCIE_COMP_TO_IOM_12_DP")
	)
	(segment
		(start 182.048658 -135.8138)
		(end 182.150004 -135.712454)
		(width 0.14605)
		(layer "F.Cu")
		(net "PCIE_COMP_TO_IOM_12_DP")
	)
	(segment
		(start 185.713624 -140.31468)
		(end 185.623962 -140.225018)
		(width 0.14605)
		(layer "F.Cu")
		(net "PCIE_COMP_TO_IOM_12_DP")
	)
	(segment
		(start 185.623962 -139.996418)
		(end 185.838592 -139.781788)
		(width 0.14605)
		(layer "F.Cu")
		(net "PCIE_COMP_TO_IOM_12_DP")
	)
	(segment
		(start 185.838592 -138.809476)
		(end 185.581798 -138.552682)
		(width 0.14605)
		(layer "F.Cu")
		(net "PCIE_COMP_TO_IOM_12_DP")
	)
	(segment
		(start 185.581544 -138.552682)
		(end 183.822848 -136.793986)
		(width 0.14605)
		(layer "F.Cu")
		(net "PCIE_COMP_TO_IOM_12_DP")
	)
	(segment
		(start 182.150004 -135.712454)
		(end 182.150004 -134.875016)
		(width 0.14605)
		(layer "F.Cu")
		(net "PCIE_COMP_TO_IOM_12_DP")
	)
	(segment
		(start 182.672736 -136.793986)
		(end 182.048658 -136.169908)
		(width 0.14605)
		(layer "F.Cu")
		(net "PCIE_COMP_TO_IOM_12_DP")
	)
	(segment
		(start 183.822848 -136.793986)
		(end 182.672736 -136.793986)
		(width 0.14605)
		(layer "F.Cu")
		(net "PCIE_COMP_TO_IOM_12_DP")
	)
	(segment
		(start 185.581798 -138.552682)
		(end 185.581544 -138.552682)
		(width 0.14605)
		(layer "F.Cu")
		(net "PCIE_COMP_TO_IOM_12_DP")
	)
	(arc
		(start 185.838592 -139.781788)
		(mid 186.039964 -139.295632)
		(end 185.838592 -138.809476)
		(width 0.14605)
		(layer "F.Cu")
		(net "PCIE_COMP_TO_IOM_12_DP")
	)
	(arc
		(start 185.623962 -140.225018)
		(mid 185.576617 -140.110718)
		(end 185.623962 -139.996418)
		(width 0.14605)
		(layer "F.Cu")
		(net "PCIE_COMP_TO_IOM_12_DP")
	)
	(segment
		(start 155.520136 -44.556172)
		(end 155.340812 -44.436538)
		(width 0.14605)
		(layer "B.Cu")
		(net "PCIE_COMP_TO_IOM_12_DP")
	)
	(segment
		(start 154.646122 -40.962072)
		(end 154.560016 -40.532304)
		(width 0.14605)
		(layer "B.Cu")
		(net "PCIE_COMP_TO_IOM_12_DP")
	)
	(segment
		(start 155.25496 -44.00677)
		(end 155.374594 -43.827446)
		(width 0.14605)
		(layer "B.Cu")
		(net "PCIE_COMP_TO_IOM_12_DP")
	)
	(segment
		(start 154.34564 -38.683184)
		(end 146.729704 -27.259026)
		(width 0.14605)
		(layer "B.Cu")
		(net "PCIE_COMP_TO_IOM_12_DP")
	)
	(segment
		(start 185.394854 -140.225526)
		(end 185.394854 -140.225272)
		(width 0.14605)
		(layer "B.Cu")
		(net "PCIE_COMP_TO_IOM_12_DP")
	)
	(segment
		(start 159.9565 -129.013458)
		(end 166.157656 -97.743518)
		(width 0.14605)
		(layer "B.Cu")
		(net "PCIE_COMP_TO_IOM_12_DP")
	)
	(segment
		(start 184.303162 -141.856714)
		(end 182.847488 -142.838932)
		(width 0.14605)
		(layer "B.Cu")
		(net "PCIE_COMP_TO_IOM_12_DP")
	)
	(segment
		(start 144.608296 -25.8445)
		(end 142.305532 -25.384252)
		(width 0.14605)
		(layer "B.Cu")
		(net "PCIE_COMP_TO_IOM_12_DP")
	)
	(segment
		(start 155.109164 -43.278298)
		(end 155.023312 -42.848784)
		(width 0.14605)
		(layer "B.Cu")
		(net "PCIE_COMP_TO_IOM_12_DP")
	)
	(segment
		(start 185.29046 -140.329412)
		(end 185.18632 -140.433552)
		(width 0.14605)
		(layer "B.Cu")
		(net "PCIE_COMP_TO_IOM_12_DP")
	)
	(segment
		(start 155.05684 -42.239692)
		(end 154.877516 -42.120058)
		(width 0.14605)
		(layer "B.Cu")
		(net "PCIE_COMP_TO_IOM_12_DP")
	)
	(segment
		(start 133.572758 -32.544512)
		(end 133.93674 -32.544512)
		(width 0.14605)
		(layer "B.Cu")
		(net "PCIE_COMP_TO_IOM_12_DP")
	)
	(segment
		(start 182.847488 -142.838932)
		(end 175.181006 -144.328642)
		(width 0.14605)
		(layer "B.Cu")
		(net "PCIE_COMP_TO_IOM_12_DP")
	)
	(segment
		(start 154.877516 -42.120058)
		(end 154.791664 -41.690544)
		(width 0.14605)
		(layer "B.Cu")
		(net "PCIE_COMP_TO_IOM_12_DP")
	)
	(segment
		(start 155.023312 -42.848784)
		(end 155.142946 -42.66946)
		(width 0.14605)
		(layer "B.Cu")
		(net "PCIE_COMP_TO_IOM_12_DP")
	)
	(segment
		(start 185.395362 -140.225018)
		(end 185.394854 -140.225526)
		(width 0.14605)
		(layer "B.Cu")
		(net "PCIE_COMP_TO_IOM_12_DP")
	)
	(segment
		(start 185.394854 -140.225272)
		(end 185.29046 -140.329412)
		(width 0.14605)
		(layer "B.Cu")
		(net "PCIE_COMP_TO_IOM_12_DP")
	)
	(segment
		(start 155.374594 -43.827446)
		(end 155.288488 -43.397932)
		(width 0.14605)
		(layer "B.Cu")
		(net "PCIE_COMP_TO_IOM_12_DP")
	)
	(segment
		(start 133.355588 -29.473652)
		(end 133.355588 -32.327342)
		(width 0.14605)
		(layer "B.Cu")
		(net "PCIE_COMP_TO_IOM_12_DP")
	)
	(segment
		(start 184.88787 -141.272006)
		(end 184.303162 -141.856714)
		(width 0.14605)
		(layer "B.Cu")
		(net "PCIE_COMP_TO_IOM_12_DP")
	)
	(segment
		(start 175.181006 -144.328642)
		(end 166.15029 -142.573248)
		(width 0.14605)
		(layer "B.Cu")
		(net "PCIE_COMP_TO_IOM_12_DP")
	)
	(segment
		(start 154.791664 -41.690544)
		(end 154.911298 -41.51122)
		(width 0.14605)
		(layer "B.Cu")
		(net "PCIE_COMP_TO_IOM_12_DP")
	)
	(segment
		(start 154.560016 -40.532304)
		(end 154.67965 -40.35298)
		(width 0.14605)
		(layer "B.Cu")
		(net "PCIE_COMP_TO_IOM_12_DP")
	)
	(segment
		(start 166.15029 -142.573248)
		(end 163.357814 -140.689838)
		(width 0.14605)
		(layer "B.Cu")
		(net "PCIE_COMP_TO_IOM_12_DP")
	)
	(segment
		(start 155.288488 -43.397932)
		(end 155.109164 -43.278298)
		(width 0.14605)
		(layer "B.Cu")
		(net "PCIE_COMP_TO_IOM_12_DP")
	)
	(segment
		(start 154.67965 -40.35298)
		(end 154.34564 -38.683184)
		(width 0.14605)
		(layer "B.Cu")
		(net "PCIE_COMP_TO_IOM_12_DP")
	)
	(segment
		(start 146.729704 -27.259026)
		(end 144.608296 -25.8445)
		(width 0.14605)
		(layer "B.Cu")
		(net "PCIE_COMP_TO_IOM_12_DP")
	)
	(segment
		(start 154.825446 -41.081452)
		(end 154.646122 -40.962072)
		(width 0.14605)
		(layer "B.Cu")
		(net "PCIE_COMP_TO_IOM_12_DP")
	)
	(segment
		(start 163.357814 -140.689838)
		(end 161.767012 -138.33094)
		(width 0.14605)
		(layer "B.Cu")
		(net "PCIE_COMP_TO_IOM_12_DP")
	)
	(segment
		(start 166.157656 -97.743518)
		(end 155.520136 -44.556172)
		(width 0.14605)
		(layer "B.Cu")
		(net "PCIE_COMP_TO_IOM_12_DP")
	)
	(segment
		(start 154.911298 -41.51122)
		(end 154.825446 -41.081452)
		(width 0.14605)
		(layer "B.Cu")
		(net "PCIE_COMP_TO_IOM_12_DP")
	)
	(segment
		(start 155.142946 -42.66946)
		(end 155.05684 -42.239692)
		(width 0.14605)
		(layer "B.Cu")
		(net "PCIE_COMP_TO_IOM_12_DP")
	)
	(segment
		(start 161.767012 -138.33094)
		(end 159.9565 -129.013458)
		(width 0.14605)
		(layer "B.Cu")
		(net "PCIE_COMP_TO_IOM_12_DP")
	)
	(segment
		(start 185.713624 -140.31468)
		(end 185.623962 -140.225018)
		(width 0.14605)
		(layer "B.Cu")
		(net "PCIE_COMP_TO_IOM_12_DP")
	)
	(segment
		(start 137.444988 -25.384252)
		(end 133.355588 -29.473652)
		(width 0.14605)
		(layer "B.Cu")
		(net "PCIE_COMP_TO_IOM_12_DP")
	)
	(segment
		(start 185.0644 -140.727938)
		(end 185.0644 -140.845794)
		(width 0.14605)
		(layer "B.Cu")
		(net "PCIE_COMP_TO_IOM_12_DP")
	)
	(segment
		(start 142.305532 -25.384252)
		(end 137.444988 -25.384252)
		(width 0.14605)
		(layer "B.Cu")
		(net "PCIE_COMP_TO_IOM_12_DP")
	)
	(segment
		(start 155.340812 -44.436538)
		(end 155.25496 -44.00677)
		(width 0.14605)
		(layer "B.Cu")
		(net "PCIE_COMP_TO_IOM_12_DP")
	)
	(segment
		(start 134.100062 -32.38119)
		(end 134.100062 -32.00019)
		(width 0.14605)
		(layer "B.Cu")
		(net "PCIE_COMP_TO_IOM_12_DP")
	)
	(arc
		(start 133.93674 -32.544512)
		(mid 134.052226 -32.496676)
		(end 134.100062 -32.38119)
		(width 0.14605)
		(layer "B.Cu")
		(net "PCIE_COMP_TO_IOM_12_DP")
	)
	(arc
		(start 185.18632 -140.433552)
		(mid 185.096072 -140.568617)
		(end 185.0644 -140.727938)
		(width 0.14605)
		(layer "B.Cu")
		(net "PCIE_COMP_TO_IOM_12_DP")
	)
	(arc
		(start 133.355588 -32.327342)
		(mid 133.419196 -32.480904)
		(end 133.572758 -32.544512)
		(width 0.14605)
		(layer "B.Cu")
		(net "PCIE_COMP_TO_IOM_12_DP")
	)
	(arc
		(start 185.623962 -140.225018)
		(mid 185.509662 -140.177673)
		(end 185.395362 -140.225018)
		(width 0.14605)
		(layer "B.Cu")
		(net "PCIE_COMP_TO_IOM_12_DP")
	)
	(arc
		(start 185.0644 -140.845794)
		(mid 185.018534 -141.076468)
		(end 184.88787 -141.272006)
		(width 0.14605)
		(layer "B.Cu")
		(net "PCIE_COMP_TO_IOM_12_DP")
	)
	(segment
		(start 185.618374 -139.029694)
		(end 183.693816 -137.105136)
		(width 0.14605)
		(layer "F.Cu")
		(net "PCIE_COMP_TO_IOM_12_DN")
	)
	(segment
		(start 185.085228 -139.686284)
		(end 185.17489 -139.775946)
		(width 0.14605)
		(layer "F.Cu")
		(net "PCIE_COMP_TO_IOM_12_DN")
	)
	(segment
		(start 181.737508 -135.80745)
		(end 181.649878 -135.71982)
		(width 0.14605)
		(layer "F.Cu")
		(net "PCIE_COMP_TO_IOM_12_DN")
	)
	(segment
		(start 183.693816 -137.105136)
		(end 182.543704 -137.105136)
		(width 0.14605)
		(layer "F.Cu")
		(net "PCIE_COMP_TO_IOM_12_DN")
	)
	(segment
		(start 181.737508 -136.29894)
		(end 181.737508 -135.80745)
		(width 0.14605)
		(layer "F.Cu")
		(net "PCIE_COMP_TO_IOM_12_DN")
	)
	(segment
		(start 182.543704 -137.105136)
		(end 181.737508 -136.29894)
		(width 0.14605)
		(layer "F.Cu")
		(net "PCIE_COMP_TO_IOM_12_DN")
	)
	(segment
		(start 181.649878 -135.71982)
		(end 181.649878 -134.875016)
		(width 0.14605)
		(layer "F.Cu")
		(net "PCIE_COMP_TO_IOM_12_DN")
	)
	(segment
		(start 185.403998 -139.775946)
		(end 185.618374 -139.56157)
		(width 0.14605)
		(layer "F.Cu")
		(net "PCIE_COMP_TO_IOM_12_DN")
	)
	(arc
		(start 185.17489 -139.775946)
		(mid 185.289444 -139.823396)
		(end 185.403998 -139.775946)
		(width 0.14605)
		(layer "F.Cu")
		(net "PCIE_COMP_TO_IOM_12_DN")
	)
	(arc
		(start 185.618374 -139.56157)
		(mid 185.728529 -139.295632)
		(end 185.618374 -139.029694)
		(width 0.14605)
		(layer "F.Cu")
		(net "PCIE_COMP_TO_IOM_12_DN")
	)
	(segment
		(start 184.667652 -141.051788)
		(end 184.54751 -141.172184)
		(width 0.14605)
		(layer "B.Cu")
		(net "PCIE_COMP_TO_IOM_12_DN")
	)
	(segment
		(start 162.060636 -138.209274)
		(end 160.273746 -129.013966)
		(width 0.14605)
		(layer "B.Cu")
		(net "PCIE_COMP_TO_IOM_12_DN")
	)
	(segment
		(start 184.10428 -141.615414)
		(end 182.725822 -142.545308)
		(width 0.14605)
		(layer "B.Cu")
		(net "PCIE_COMP_TO_IOM_12_DN")
	)
	(segment
		(start 184.54751 -141.172184)
		(end 184.10428 -141.615414)
		(width 0.14605)
		(layer "B.Cu")
		(net "PCIE_COMP_TO_IOM_12_DN")
	)
	(segment
		(start 163.582096 -140.465556)
		(end 162.060636 -138.209274)
		(width 0.14605)
		(layer "B.Cu")
		(net "PCIE_COMP_TO_IOM_12_DN")
	)
	(segment
		(start 185.17489 -140.0048)
		(end 184.966102 -140.213334)
		(width 0.14605)
		(layer "B.Cu")
		(net "PCIE_COMP_TO_IOM_12_DN")
	)
	(segment
		(start 166.271956 -142.279624)
		(end 163.582096 -140.465556)
		(width 0.14605)
		(layer "B.Cu")
		(net "PCIE_COMP_TO_IOM_12_DN")
	)
	(segment
		(start 137.315956 -25.073102)
		(end 133.044438 -29.34462)
		(width 0.14605)
		(layer "B.Cu")
		(net "PCIE_COMP_TO_IOM_12_DN")
	)
	(segment
		(start 142.33652 -25.073102)
		(end 137.315956 -25.073102)
		(width 0.14605)
		(layer "B.Cu")
		(net "PCIE_COMP_TO_IOM_12_DN")
	)
	(segment
		(start 154.638756 -38.561772)
		(end 146.95424 -27.03449)
		(width 0.14605)
		(layer "B.Cu")
		(net "PCIE_COMP_TO_IOM_12_DN")
	)
	(segment
		(start 166.475156 -97.743264)
		(end 154.638756 -38.561772)
		(width 0.14605)
		(layer "B.Cu")
		(net "PCIE_COMP_TO_IOM_12_DN")
	)
	(segment
		(start 182.725822 -142.545308)
		(end 175.181006 -144.01165)
		(width 0.14605)
		(layer "B.Cu")
		(net "PCIE_COMP_TO_IOM_12_DN")
	)
	(segment
		(start 184.75325 -140.728192)
		(end 184.75325 -140.84554)
		(width 0.14605)
		(layer "B.Cu")
		(net "PCIE_COMP_TO_IOM_12_DN")
	)
	(segment
		(start 134.100062 -33.018984)
		(end 134.100062 -33.399984)
		(width 0.14605)
		(layer "B.Cu")
		(net "PCIE_COMP_TO_IOM_12_DN")
	)
	(segment
		(start 160.273746 -129.013966)
		(end 166.475156 -97.743264)
		(width 0.14605)
		(layer "B.Cu")
		(net "PCIE_COMP_TO_IOM_12_DN")
	)
	(segment
		(start 133.044438 -29.34462)
		(end 133.044438 -32.327342)
		(width 0.14605)
		(layer "B.Cu")
		(net "PCIE_COMP_TO_IOM_12_DN")
	)
	(segment
		(start 144.729708 -25.551384)
		(end 142.33652 -25.073102)
		(width 0.14605)
		(layer "B.Cu")
		(net "PCIE_COMP_TO_IOM_12_DN")
	)
	(segment
		(start 175.181006 -144.01165)
		(end 166.271956 -142.279624)
		(width 0.14605)
		(layer "B.Cu")
		(net "PCIE_COMP_TO_IOM_12_DN")
	)
	(segment
		(start 146.95424 -27.03449)
		(end 144.729708 -25.551384)
		(width 0.14605)
		(layer "B.Cu")
		(net "PCIE_COMP_TO_IOM_12_DN")
	)
	(segment
		(start 185.085228 -139.686284)
		(end 185.17489 -139.775946)
		(width 0.14605)
		(layer "B.Cu")
		(net "PCIE_COMP_TO_IOM_12_DN")
	)
	(segment
		(start 133.572758 -32.855662)
		(end 133.93674 -32.855662)
		(width 0.14605)
		(layer "B.Cu")
		(net "PCIE_COMP_TO_IOM_12_DN")
	)
	(arc
		(start 184.966102 -140.213334)
		(mid 184.808432 -140.449583)
		(end 184.75325 -140.728192)
		(width 0.14605)
		(layer "B.Cu")
		(net "PCIE_COMP_TO_IOM_12_DN")
	)
	(arc
		(start 185.17489 -139.775946)
		(mid 185.222414 -139.89041)
		(end 185.17489 -140.0048)
		(width 0.14605)
		(layer "B.Cu")
		(net "PCIE_COMP_TO_IOM_12_DN")
	)
	(arc
		(start 133.93674 -32.855662)
		(mid 134.052226 -32.903498)
		(end 134.100062 -33.018984)
		(width 0.14605)
		(layer "B.Cu")
		(net "PCIE_COMP_TO_IOM_12_DN")
	)
	(arc
		(start 184.75325 -140.84554)
		(mid 184.730952 -140.957171)
		(end 184.667652 -141.051788)
		(width 0.14605)
		(layer "B.Cu")
		(net "PCIE_COMP_TO_IOM_12_DN")
	)
	(arc
		(start 133.044438 -32.327342)
		(mid 133.199179 -32.700921)
		(end 133.572758 -32.855662)
		(width 0.14605)
		(layer "B.Cu")
		(net "PCIE_COMP_TO_IOM_12_DN")
	)
	(segment
		(start 198.152258 -135.710168)
		(end 198.152258 -134.877302)
		(width 0.14605)
		(layer "F.Cu")
		(net "PCIE_COMP_TO_IOM_11_DP")
	)
	(segment
		(start 198.152258 -134.877302)
		(end 198.149972 -134.875016)
		(width 0.14605)
		(layer "F.Cu")
		(net "PCIE_COMP_TO_IOM_11_DP")
	)
	(segment
		(start 198.048626 -136.884156)
		(end 198.048626 -135.8138)
		(width 0.14605)
		(layer "F.Cu")
		(net "PCIE_COMP_TO_IOM_11_DP")
	)
	(segment
		(start 196.152008 -139.92606)
		(end 196.152008 -138.78052)
		(width 0.14605)
		(layer "F.Cu")
		(net "PCIE_COMP_TO_IOM_11_DP")
	)
	(segment
		(start 198.048626 -135.8138)
		(end 198.152258 -135.710168)
		(width 0.14605)
		(layer "F.Cu")
		(net "PCIE_COMP_TO_IOM_11_DP")
	)
	(segment
		(start 195.677536 -140.711936)
		(end 195.93179 -140.457682)
		(width 0.14605)
		(layer "F.Cu")
		(net "PCIE_COMP_TO_IOM_11_DP")
	)
	(segment
		(start 196.668136 -138.264392)
		(end 198.048626 -136.884156)
		(width 0.14605)
		(layer "F.Cu")
		(net "PCIE_COMP_TO_IOM_11_DP")
	)
	(segment
		(start 196.152008 -138.78052)
		(end 196.668136 -138.264392)
		(width 0.14605)
		(layer "F.Cu")
		(net "PCIE_COMP_TO_IOM_11_DP")
	)
	(segment
		(start 195.767198 -141.030198)
		(end 195.677536 -140.940536)
		(width 0.14605)
		(layer "F.Cu")
		(net "PCIE_COMP_TO_IOM_11_DP")
	)
	(arc
		(start 195.93179 -140.457682)
		(mid 196.094766 -140.213772)
		(end 196.152008 -139.92606)
		(width 0.14605)
		(layer "F.Cu")
		(net "PCIE_COMP_TO_IOM_11_DP")
	)
	(arc
		(start 195.677536 -140.940536)
		(mid 195.630191 -140.826236)
		(end 195.677536 -140.711936)
		(width 0.14605)
		(layer "F.Cu")
		(net "PCIE_COMP_TO_IOM_11_DP")
	)
	(segment
		(start 195.767198 -141.030198)
		(end 195.677536 -140.940536)
		(width 0.14605)
		(layer "B.Cu")
		(net "PCIE_COMP_TO_IOM_11_DP")
	)
	(segment
		(start 142.470124 -26.612342)
		(end 142.04569 -26.527252)
		(width 0.14605)
		(layer "B.Cu")
		(net "PCIE_COMP_TO_IOM_11_DP")
	)
	(segment
		(start 162.310826 -141.59357)
		(end 160.759394 -139.2936)
		(width 0.14605)
		(layer "B.Cu")
		(net "PCIE_COMP_TO_IOM_11_DP")
	)
	(segment
		(start 152.89022 -40.18534)
		(end 153.0096 -40.006016)
		(width 0.14605)
		(layer "B.Cu")
		(net "PCIE_COMP_TO_IOM_11_DP")
	)
	(segment
		(start 153.353262 -42.501566)
		(end 153.472896 -42.322242)
		(width 0.14605)
		(layer "B.Cu")
		(net "PCIE_COMP_TO_IOM_11_DP")
	)
	(segment
		(start 165.240716 -143.570452)
		(end 162.310826 -141.59357)
		(width 0.14605)
		(layer "B.Cu")
		(net "PCIE_COMP_TO_IOM_11_DP")
	)
	(segment
		(start 145.706592 -28.175966)
		(end 143.744696 -26.867866)
		(width 0.14605)
		(layer "B.Cu")
		(net "PCIE_COMP_TO_IOM_11_DP")
	)
	(segment
		(start 153.121614 -41.34358)
		(end 153.241248 -41.164256)
		(width 0.14605)
		(layer "B.Cu")
		(net "PCIE_COMP_TO_IOM_11_DP")
	)
	(segment
		(start 158.588202 -128.126744)
		(end 164.58565 -97.884996)
		(width 0.14605)
		(layer "B.Cu")
		(net "PCIE_COMP_TO_IOM_11_DP")
	)
	(segment
		(start 138.133582 -26.527252)
		(end 135.155686 -29.505148)
		(width 0.14605)
		(layer "B.Cu")
		(net "PCIE_COMP_TO_IOM_11_DP")
	)
	(segment
		(start 153.472896 -42.322242)
		(end 153.387044 -41.892728)
		(width 0.14605)
		(layer "B.Cu")
		(net "PCIE_COMP_TO_IOM_11_DP")
	)
	(segment
		(start 143.744696 -26.867866)
		(end 142.682722 -26.655014)
		(width 0.14605)
		(layer "B.Cu")
		(net "PCIE_COMP_TO_IOM_11_DP")
	)
	(segment
		(start 153.439368 -42.931334)
		(end 153.353262 -42.501566)
		(width 0.14605)
		(layer "B.Cu")
		(net "PCIE_COMP_TO_IOM_11_DP")
	)
	(segment
		(start 153.387044 -41.892728)
		(end 153.20772 -41.773094)
		(width 0.14605)
		(layer "B.Cu")
		(net "PCIE_COMP_TO_IOM_11_DP")
	)
	(segment
		(start 195.448682 -140.940536)
		(end 193.951606 -142.437612)
		(width 0.14605)
		(layer "B.Cu")
		(net "PCIE_COMP_TO_IOM_11_DP")
	)
	(segment
		(start 152.759918 -38.757352)
		(end 145.706592 -28.175966)
		(width 0.14605)
		(layer "B.Cu")
		(net "PCIE_COMP_TO_IOM_11_DP")
	)
	(segment
		(start 153.0096 -40.006016)
		(end 152.759918 -38.757352)
		(width 0.14605)
		(layer "B.Cu")
		(net "PCIE_COMP_TO_IOM_11_DP")
	)
	(segment
		(start 153.671016 -44.089574)
		(end 153.58491 -43.659806)
		(width 0.14605)
		(layer "B.Cu")
		(net "PCIE_COMP_TO_IOM_11_DP")
	)
	(segment
		(start 135.379968 -33.744662)
		(end 135.73633 -33.744662)
		(width 0.14605)
		(layer "B.Cu")
		(net "PCIE_COMP_TO_IOM_11_DP")
	)
	(segment
		(start 176.67986 -145.793714)
		(end 165.240716 -143.570452)
		(width 0.14605)
		(layer "B.Cu")
		(net "PCIE_COMP_TO_IOM_11_DP")
	)
	(segment
		(start 153.704544 -43.480482)
		(end 153.618692 -43.050968)
		(width 0.14605)
		(layer "B.Cu")
		(net "PCIE_COMP_TO_IOM_11_DP")
	)
	(segment
		(start 135.899906 -33.581086)
		(end 135.899906 -33.200086)
		(width 0.14605)
		(layer "B.Cu")
		(net "PCIE_COMP_TO_IOM_11_DP")
	)
	(segment
		(start 153.850086 -44.2087)
		(end 153.671016 -44.089574)
		(width 0.14605)
		(layer "B.Cu")
		(net "PCIE_COMP_TO_IOM_11_DP")
	)
	(segment
		(start 153.155396 -40.734488)
		(end 152.976072 -40.614854)
		(width 0.14605)
		(layer "B.Cu")
		(net "PCIE_COMP_TO_IOM_11_DP")
	)
	(segment
		(start 193.951606 -142.437612)
		(end 176.67986 -145.793714)
		(width 0.14605)
		(layer "B.Cu")
		(net "PCIE_COMP_TO_IOM_11_DP")
	)
	(segment
		(start 160.759394 -139.2936)
		(end 158.588202 -128.126744)
		(width 0.14605)
		(layer "B.Cu")
		(net "PCIE_COMP_TO_IOM_11_DP")
	)
	(segment
		(start 135.155686 -29.505148)
		(end 135.155686 -33.52038)
		(width 0.14605)
		(layer "B.Cu")
		(net "PCIE_COMP_TO_IOM_11_DP")
	)
	(segment
		(start 153.58491 -43.659806)
		(end 153.704544 -43.480482)
		(width 0.14605)
		(layer "B.Cu")
		(net "PCIE_COMP_TO_IOM_11_DP")
	)
	(segment
		(start 153.241248 -41.164256)
		(end 153.155396 -40.734488)
		(width 0.14605)
		(layer "B.Cu")
		(net "PCIE_COMP_TO_IOM_11_DP")
	)
	(segment
		(start 153.618692 -43.050968)
		(end 153.439368 -42.931334)
		(width 0.14605)
		(layer "B.Cu")
		(net "PCIE_COMP_TO_IOM_11_DP")
	)
	(segment
		(start 142.04569 -26.527252)
		(end 138.133582 -26.527252)
		(width 0.14605)
		(layer "B.Cu")
		(net "PCIE_COMP_TO_IOM_11_DP")
	)
	(segment
		(start 142.682722 -26.655014)
		(end 142.470124 -26.612342)
		(width 0.14605)
		(layer "B.Cu")
		(net "PCIE_COMP_TO_IOM_11_DP")
	)
	(segment
		(start 164.58565 -97.884996)
		(end 153.850086 -44.2087)
		(width 0.14605)
		(layer "B.Cu")
		(net "PCIE_COMP_TO_IOM_11_DP")
	)
	(segment
		(start 152.976072 -40.614854)
		(end 152.89022 -40.18534)
		(width 0.14605)
		(layer "B.Cu")
		(net "PCIE_COMP_TO_IOM_11_DP")
	)
	(segment
		(start 153.20772 -41.773094)
		(end 153.121614 -41.34358)
		(width 0.14605)
		(layer "B.Cu")
		(net "PCIE_COMP_TO_IOM_11_DP")
	)
	(arc
		(start 135.73633 -33.744662)
		(mid 135.851996 -33.696752)
		(end 135.899906 -33.581086)
		(width 0.14605)
		(layer "B.Cu")
		(net "PCIE_COMP_TO_IOM_11_DP")
	)
	(arc
		(start 195.677536 -140.940536)
		(mid 195.563146 -140.893266)
		(end 195.448682 -140.940536)
		(width 0.14605)
		(layer "B.Cu")
		(net "PCIE_COMP_TO_IOM_11_DP")
	)
	(arc
		(start 135.155686 -33.52038)
		(mid 135.221377 -33.678971)
		(end 135.379968 -33.744662)
		(width 0.14605)
		(layer "B.Cu")
		(net "PCIE_COMP_TO_IOM_11_DP")
	)
	(segment
		(start 197.737476 -135.80745)
		(end 197.649846 -135.71982)
		(width 0.14605)
		(layer "F.Cu")
		(net "PCIE_COMP_TO_IOM_11_DN")
	)
	(segment
		(start 195.138802 -140.401802)
		(end 195.228464 -140.491464)
		(width 0.14605)
		(layer "F.Cu")
		(net "PCIE_COMP_TO_IOM_11_DN")
	)
	(segment
		(start 195.711572 -140.237464)
		(end 195.711572 -140.237718)
		(width 0.14605)
		(layer "F.Cu")
		(net "PCIE_COMP_TO_IOM_11_DN")
	)
	(segment
		(start 197.649846 -135.71982)
		(end 197.649846 -134.875016)
		(width 0.14605)
		(layer "F.Cu")
		(net "PCIE_COMP_TO_IOM_11_DN")
	)
	(segment
		(start 197.737476 -136.755124)
		(end 197.737476 -135.80745)
		(width 0.14605)
		(layer "F.Cu")
		(net "PCIE_COMP_TO_IOM_11_DN")
	)
	(segment
		(start 195.457572 -140.491718)
		(end 195.711572 -140.237464)
		(width 0.14605)
		(layer "F.Cu")
		(net "PCIE_COMP_TO_IOM_11_DN")
	)
	(segment
		(start 195.457572 -140.491464)
		(end 195.457572 -140.491718)
		(width 0.14605)
		(layer "F.Cu")
		(net "PCIE_COMP_TO_IOM_11_DN")
	)
	(segment
		(start 196.447918 -138.044428)
		(end 197.737476 -136.755124)
		(width 0.14605)
		(layer "F.Cu")
		(net "PCIE_COMP_TO_IOM_11_DN")
	)
	(segment
		(start 195.840858 -138.651488)
		(end 196.447918 -138.044428)
		(width 0.14605)
		(layer "F.Cu")
		(net "PCIE_COMP_TO_IOM_11_DN")
	)
	(segment
		(start 195.840858 -139.925806)
		(end 195.840858 -138.651488)
		(width 0.14605)
		(layer "F.Cu")
		(net "PCIE_COMP_TO_IOM_11_DN")
	)
	(arc
		(start 195.228464 -140.491464)
		(mid 195.343018 -140.538914)
		(end 195.457572 -140.491464)
		(width 0.14605)
		(layer "F.Cu")
		(net "PCIE_COMP_TO_IOM_11_DN")
	)
	(arc
		(start 195.711572 -140.237718)
		(mid 195.8073 -140.09464)
		(end 195.840858 -139.925806)
		(width 0.14605)
		(layer "F.Cu")
		(net "PCIE_COMP_TO_IOM_11_DN")
	)
	(segment
		(start 193.798698 -142.150084)
		(end 176.67986 -145.476722)
		(width 0.14605)
		(layer "B.Cu")
		(net "PCIE_COMP_TO_IOM_11_DN")
	)
	(segment
		(start 142.076678 -26.216102)
		(end 138.00455 -26.216102)
		(width 0.14605)
		(layer "B.Cu")
		(net "PCIE_COMP_TO_IOM_11_DN")
	)
	(segment
		(start 153.053034 -38.63594)
		(end 145.931128 -27.95143)
		(width 0.14605)
		(layer "B.Cu")
		(net "PCIE_COMP_TO_IOM_11_DN")
	)
	(segment
		(start 135.379968 -34.055812)
		(end 135.736584 -34.055812)
		(width 0.14605)
		(layer "B.Cu")
		(net "PCIE_COMP_TO_IOM_11_DN")
	)
	(segment
		(start 195.138802 -140.401802)
		(end 195.228464 -140.491464)
		(width 0.14605)
		(layer "B.Cu")
		(net "PCIE_COMP_TO_IOM_11_DN")
	)
	(segment
		(start 134.844536 -29.376116)
		(end 134.844536 -33.52038)
		(width 0.14605)
		(layer "B.Cu")
		(net "PCIE_COMP_TO_IOM_11_DN")
	)
	(segment
		(start 195.228464 -140.720318)
		(end 193.798698 -142.150084)
		(width 0.14605)
		(layer "B.Cu")
		(net "PCIE_COMP_TO_IOM_11_DN")
	)
	(segment
		(start 143.805656 -26.562558)
		(end 142.95628 -26.392124)
		(width 0.14605)
		(layer "B.Cu")
		(net "PCIE_COMP_TO_IOM_11_DN")
	)
	(segment
		(start 145.931128 -27.95143)
		(end 143.866108 -26.57475)
		(width 0.14605)
		(layer "B.Cu")
		(net "PCIE_COMP_TO_IOM_11_DN")
	)
	(segment
		(start 162.535108 -141.369288)
		(end 161.053018 -139.171934)
		(width 0.14605)
		(layer "B.Cu")
		(net "PCIE_COMP_TO_IOM_11_DN")
	)
	(segment
		(start 143.866108 -26.57475)
		(end 143.805656 -26.562558)
		(width 0.14605)
		(layer "B.Cu")
		(net "PCIE_COMP_TO_IOM_11_DN")
	)
	(segment
		(start 161.053018 -139.171934)
		(end 158.905448 -128.127252)
		(width 0.14605)
		(layer "B.Cu")
		(net "PCIE_COMP_TO_IOM_11_DN")
	)
	(segment
		(start 135.899906 -34.219134)
		(end 135.899906 -34.600134)
		(width 0.14605)
		(layer "B.Cu")
		(net "PCIE_COMP_TO_IOM_11_DN")
	)
	(segment
		(start 164.90315 -97.884742)
		(end 153.053034 -38.63594)
		(width 0.14605)
		(layer "B.Cu")
		(net "PCIE_COMP_TO_IOM_11_DN")
	)
	(segment
		(start 165.362382 -143.276828)
		(end 162.535108 -141.369288)
		(width 0.14605)
		(layer "B.Cu")
		(net "PCIE_COMP_TO_IOM_11_DN")
	)
	(segment
		(start 176.67986 -145.476722)
		(end 165.362382 -143.276828)
		(width 0.14605)
		(layer "B.Cu")
		(net "PCIE_COMP_TO_IOM_11_DN")
	)
	(segment
		(start 138.00455 -26.216102)
		(end 134.844536 -29.376116)
		(width 0.14605)
		(layer "B.Cu")
		(net "PCIE_COMP_TO_IOM_11_DN")
	)
	(segment
		(start 142.95628 -26.392124)
		(end 142.076678 -26.216102)
		(width 0.14605)
		(layer "B.Cu")
		(net "PCIE_COMP_TO_IOM_11_DN")
	)
	(segment
		(start 158.905448 -128.127252)
		(end 164.90315 -97.884742)
		(width 0.14605)
		(layer "B.Cu")
		(net "PCIE_COMP_TO_IOM_11_DN")
	)
	(arc
		(start 195.228464 -140.491464)
		(mid 195.275988 -140.605928)
		(end 195.228464 -140.720318)
		(width 0.14605)
		(layer "B.Cu")
		(net "PCIE_COMP_TO_IOM_11_DN")
	)
	(arc
		(start 134.844536 -33.52038)
		(mid 135.00136 -33.898988)
		(end 135.379968 -34.055812)
		(width 0.14605)
		(layer "B.Cu")
		(net "PCIE_COMP_TO_IOM_11_DN")
	)
	(arc
		(start 135.736584 -34.055812)
		(mid 135.85207 -34.103648)
		(end 135.899906 -34.219134)
		(width 0.14605)
		(layer "B.Cu")
		(net "PCIE_COMP_TO_IOM_11_DN")
	)
	(segment
		(start 201.152252 -135.710168)
		(end 201.152252 -134.877302)
		(width 0.14605)
		(layer "F.Cu")
		(net "PCIE_COMP_TO_IOM_10_DP")
	)
	(segment
		(start 201.04862 -138.04138)
		(end 201.04862 -135.8138)
		(width 0.14605)
		(layer "F.Cu")
		(net "PCIE_COMP_TO_IOM_10_DP")
	)
	(segment
		(start 200.787 -139.80668)
		(end 200.787 -138.303)
		(width 0.14605)
		(layer "F.Cu")
		(net "PCIE_COMP_TO_IOM_10_DP")
	)
	(segment
		(start 201.04862 -135.8138)
		(end 201.152252 -135.710168)
		(width 0.14605)
		(layer "F.Cu")
		(net "PCIE_COMP_TO_IOM_10_DP")
	)
	(segment
		(start 200.847198 -141.538198)
		(end 200.757536 -141.448536)
		(width 0.14605)
		(layer "F.Cu")
		(net "PCIE_COMP_TO_IOM_10_DP")
	)
	(segment
		(start 200.757536 -141.219936)
		(end 200.960736 -141.016736)
		(width 0.14605)
		(layer "F.Cu")
		(net "PCIE_COMP_TO_IOM_10_DP")
	)
	(segment
		(start 201.152252 -134.877302)
		(end 201.149966 -134.875016)
		(width 0.14605)
		(layer "F.Cu")
		(net "PCIE_COMP_TO_IOM_10_DP")
	)
	(segment
		(start 200.960736 -139.980416)
		(end 200.787 -139.80668)
		(width 0.14605)
		(layer "F.Cu")
		(net "PCIE_COMP_TO_IOM_10_DP")
	)
	(segment
		(start 200.787 -138.303)
		(end 201.04862 -138.04138)
		(width 0.14605)
		(layer "F.Cu")
		(net "PCIE_COMP_TO_IOM_10_DP")
	)
	(arc
		(start 200.960736 -141.016736)
		(mid 201.175365 -140.498576)
		(end 200.960736 -139.980416)
		(width 0.14605)
		(layer "F.Cu")
		(net "PCIE_COMP_TO_IOM_10_DP")
	)
	(arc
		(start 200.757536 -141.448536)
		(mid 200.710191 -141.334236)
		(end 200.757536 -141.219936)
		(width 0.14605)
		(layer "F.Cu")
		(net "PCIE_COMP_TO_IOM_10_DP")
	)
	(segment
		(start 199.219566 -143.197072)
		(end 178.258978 -147.272502)
		(width 0.14605)
		(layer "B.Cu")
		(net "PCIE_COMP_TO_IOM_10_DP")
	)
	(segment
		(start 152.658572 -47.100744)
		(end 152.472898 -46.976792)
		(width 0.14605)
		(layer "B.Cu")
		(net "PCIE_COMP_TO_IOM_10_DP")
	)
	(segment
		(start 151.014938 -38.858952)
		(end 144.298416 -28.786074)
		(width 0.14605)
		(layer "B.Cu")
		(net "PCIE_COMP_TO_IOM_10_DP")
	)
	(segment
		(start 137.700004 -32.38119)
		(end 137.700004 -32.00019)
		(width 0.14605)
		(layer "B.Cu")
		(net "PCIE_COMP_TO_IOM_10_DP")
	)
	(segment
		(start 200.152 -142.0368)
		(end 200.152 -142.441422)
		(width 0.14605)
		(layer "B.Cu")
		(net "PCIE_COMP_TO_IOM_10_DP")
	)
	(segment
		(start 151.807418 -42.821606)
		(end 151.014938 -38.858952)
		(width 0.14605)
		(layer "B.Cu")
		(net "PCIE_COMP_TO_IOM_10_DP")
	)
	(segment
		(start 151.957024 -43.56989)
		(end 151.765762 -43.442382)
		(width 0.14605)
		(layer "B.Cu")
		(net "PCIE_COMP_TO_IOM_10_DP")
	)
	(segment
		(start 151.915368 -44.19092)
		(end 152.042876 -43.999658)
		(width 0.14605)
		(layer "B.Cu")
		(net "PCIE_COMP_TO_IOM_10_DP")
	)
	(segment
		(start 159.684974 -139.827762)
		(end 157.308804 -127.602488)
		(width 0.14605)
		(layer "B.Cu")
		(net "PCIE_COMP_TO_IOM_10_DP")
	)
	(segment
		(start 143.354298 -28.156662)
		(end 142.623794 -28.010612)
		(width 0.14605)
		(layer "B.Cu")
		(net "PCIE_COMP_TO_IOM_10_DP")
	)
	(segment
		(start 162.928808 -98.449638)
		(end 152.65908 -47.102014)
		(width 0.14605)
		(layer "B.Cu")
		(net "PCIE_COMP_TO_IOM_10_DP")
	)
	(segment
		(start 157.308804 -127.602488)
		(end 162.928808 -98.449638)
		(width 0.14605)
		(layer "B.Cu")
		(net "PCIE_COMP_TO_IOM_10_DP")
	)
	(segment
		(start 141.893036 -27.8638)
		(end 139.022582 -27.8638)
		(width 0.14605)
		(layer "B.Cu")
		(net "PCIE_COMP_TO_IOM_10_DP")
	)
	(segment
		(start 137.1727 -32.544512)
		(end 137.536682 -32.544512)
		(width 0.14605)
		(layer "B.Cu")
		(net "PCIE_COMP_TO_IOM_10_DP")
	)
	(segment
		(start 199.763634 -142.829788)
		(end 199.219566 -143.197072)
		(width 0.14605)
		(layer "B.Cu")
		(net "PCIE_COMP_TO_IOM_10_DP")
	)
	(segment
		(start 152.192736 -44.747942)
		(end 152.001474 -44.620434)
		(width 0.14605)
		(layer "B.Cu")
		(net "PCIE_COMP_TO_IOM_10_DP")
	)
	(segment
		(start 152.237186 -45.798486)
		(end 152.15108 -45.368972)
		(width 0.14605)
		(layer "B.Cu")
		(net "PCIE_COMP_TO_IOM_10_DP")
	)
	(segment
		(start 151.765762 -43.442382)
		(end 151.679656 -43.012868)
		(width 0.14605)
		(layer "B.Cu")
		(net "PCIE_COMP_TO_IOM_10_DP")
	)
	(segment
		(start 178.258978 -147.272502)
		(end 178.199796 -147.283932)
		(width 0.14605)
		(layer "B.Cu")
		(net "PCIE_COMP_TO_IOM_10_DP")
	)
	(segment
		(start 164.832792 -144.687036)
		(end 161.401252 -142.371826)
		(width 0.14605)
		(layer "B.Cu")
		(net "PCIE_COMP_TO_IOM_10_DP")
	)
	(segment
		(start 200.847198 -141.538198)
		(end 200.757536 -141.448536)
		(width 0.14605)
		(layer "B.Cu")
		(net "PCIE_COMP_TO_IOM_10_DP")
	)
	(segment
		(start 152.5143 -46.355762)
		(end 152.428448 -45.925994)
		(width 0.14605)
		(layer "B.Cu")
		(net "PCIE_COMP_TO_IOM_10_DP")
	)
	(segment
		(start 200.310496 -141.666214)
		(end 200.301606 -141.675104)
		(width 0.14605)
		(layer "B.Cu")
		(net "PCIE_COMP_TO_IOM_10_DP")
	)
	(segment
		(start 152.65908 -47.102014)
		(end 152.658826 -47.102014)
		(width 0.14605)
		(layer "B.Cu")
		(net "PCIE_COMP_TO_IOM_10_DP")
	)
	(segment
		(start 139.022582 -27.8638)
		(end 136.95553 -29.930852)
		(width 0.14605)
		(layer "B.Cu")
		(net "PCIE_COMP_TO_IOM_10_DP")
	)
	(segment
		(start 161.401252 -142.371826)
		(end 159.684974 -139.827762)
		(width 0.14605)
		(layer "B.Cu")
		(net "PCIE_COMP_TO_IOM_10_DP")
	)
	(segment
		(start 152.386792 -46.547024)
		(end 152.5143 -46.355762)
		(width 0.14605)
		(layer "B.Cu")
		(net "PCIE_COMP_TO_IOM_10_DP")
	)
	(segment
		(start 152.278588 -45.17771)
		(end 152.192736 -44.747942)
		(width 0.14605)
		(layer "B.Cu")
		(net "PCIE_COMP_TO_IOM_10_DP")
	)
	(segment
		(start 152.001474 -44.620434)
		(end 151.915368 -44.19092)
		(width 0.14605)
		(layer "B.Cu")
		(net "PCIE_COMP_TO_IOM_10_DP")
	)
	(segment
		(start 152.15108 -45.368972)
		(end 152.278588 -45.17771)
		(width 0.14605)
		(layer "B.Cu")
		(net "PCIE_COMP_TO_IOM_10_DP")
	)
	(segment
		(start 151.679656 -43.012868)
		(end 151.807418 -42.821606)
		(width 0.14605)
		(layer "B.Cu")
		(net "PCIE_COMP_TO_IOM_10_DP")
	)
	(segment
		(start 152.472898 -46.976792)
		(end 152.386792 -46.547024)
		(width 0.14605)
		(layer "B.Cu")
		(net "PCIE_COMP_TO_IOM_10_DP")
	)
	(segment
		(start 152.428448 -45.925994)
		(end 152.237186 -45.798486)
		(width 0.14605)
		(layer "B.Cu")
		(net "PCIE_COMP_TO_IOM_10_DP")
	)
	(segment
		(start 152.042876 -43.999658)
		(end 151.957024 -43.56989)
		(width 0.14605)
		(layer "B.Cu")
		(net "PCIE_COMP_TO_IOM_10_DP")
	)
	(segment
		(start 200.152 -142.441422)
		(end 199.763634 -142.829788)
		(width 0.14605)
		(layer "B.Cu")
		(net "PCIE_COMP_TO_IOM_10_DP")
	)
	(segment
		(start 200.528682 -141.448536)
		(end 200.310496 -141.666214)
		(width 0.14605)
		(layer "B.Cu")
		(net "PCIE_COMP_TO_IOM_10_DP")
	)
	(segment
		(start 142.623794 -28.010612)
		(end 141.893036 -27.8638)
		(width 0.14605)
		(layer "B.Cu")
		(net "PCIE_COMP_TO_IOM_10_DP")
	)
	(segment
		(start 144.298416 -28.786074)
		(end 143.354298 -28.156662)
		(width 0.14605)
		(layer "B.Cu")
		(net "PCIE_COMP_TO_IOM_10_DP")
	)
	(segment
		(start 178.199796 -147.283932)
		(end 164.832792 -144.687036)
		(width 0.14605)
		(layer "B.Cu")
		(net "PCIE_COMP_TO_IOM_10_DP")
	)
	(segment
		(start 136.95553 -29.930852)
		(end 136.95553 -32.327342)
		(width 0.14605)
		(layer "B.Cu")
		(net "PCIE_COMP_TO_IOM_10_DP")
	)
	(segment
		(start 152.658826 -47.102014)
		(end 152.658572 -47.100744)
		(width 0.14605)
		(layer "B.Cu")
		(net "PCIE_COMP_TO_IOM_10_DP")
	)
	(arc
		(start 137.536682 -32.544512)
		(mid 137.652168 -32.496676)
		(end 137.700004 -32.38119)
		(width 0.14605)
		(layer "B.Cu")
		(net "PCIE_COMP_TO_IOM_10_DP")
	)
	(arc
		(start 200.301606 -141.675104)
		(mid 200.190806 -141.841067)
		(end 200.152 -142.0368)
		(width 0.14605)
		(layer "B.Cu")
		(net "PCIE_COMP_TO_IOM_10_DP")
	)
	(arc
		(start 136.95553 -32.327342)
		(mid 137.019138 -32.480904)
		(end 137.1727 -32.544512)
		(width 0.14605)
		(layer "B.Cu")
		(net "PCIE_COMP_TO_IOM_10_DP")
	)
	(arc
		(start 200.757536 -141.448536)
		(mid 200.643146 -141.401266)
		(end 200.528682 -141.448536)
		(width 0.14605)
		(layer "B.Cu")
		(net "PCIE_COMP_TO_IOM_10_DP")
	)
	(segment
		(start 200.73747 -135.80745)
		(end 200.64984 -135.71982)
		(width 0.14605)
		(layer "F.Cu")
		(net "PCIE_COMP_TO_IOM_10_DN")
	)
	(segment
		(start 200.64984 -135.71982)
		(end 200.64984 -134.875016)
		(width 0.14605)
		(layer "F.Cu")
		(net "PCIE_COMP_TO_IOM_10_DN")
	)
	(segment
		(start 200.218802 -140.909802)
		(end 200.308464 -140.999464)
		(width 0.14605)
		(layer "F.Cu")
		(net "PCIE_COMP_TO_IOM_10_DN")
	)
	(segment
		(start 200.47585 -138.173968)
		(end 200.73747 -137.912348)
		(width 0.14605)
		(layer "F.Cu")
		(net "PCIE_COMP_TO_IOM_10_DN")
	)
	(segment
		(start 200.73747 -137.912348)
		(end 200.73747 -135.80745)
		(width 0.14605)
		(layer "F.Cu")
		(net "PCIE_COMP_TO_IOM_10_DN")
	)
	(segment
		(start 200.740518 -140.200634)
		(end 200.47585 -139.935966)
		(width 0.14605)
		(layer "F.Cu")
		(net "PCIE_COMP_TO_IOM_10_DN")
	)
	(segment
		(start 200.47585 -139.935966)
		(end 200.47585 -138.173968)
		(width 0.14605)
		(layer "F.Cu")
		(net "PCIE_COMP_TO_IOM_10_DN")
	)
	(segment
		(start 200.537572 -140.999464)
		(end 200.740518 -140.796518)
		(width 0.14605)
		(layer "F.Cu")
		(net "PCIE_COMP_TO_IOM_10_DN")
	)
	(arc
		(start 200.308464 -140.999464)
		(mid 200.423018 -141.046914)
		(end 200.537572 -140.999464)
		(width 0.14605)
		(layer "F.Cu")
		(net "PCIE_COMP_TO_IOM_10_DN")
	)
	(arc
		(start 200.740518 -140.796518)
		(mid 200.86393 -140.498576)
		(end 200.740518 -140.200634)
		(width 0.14605)
		(layer "F.Cu")
		(net "PCIE_COMP_TO_IOM_10_DN")
	)
	(segment
		(start 161.625534 -142.147544)
		(end 159.978598 -139.706096)
		(width 0.14605)
		(layer "B.Cu")
		(net "PCIE_COMP_TO_IOM_10_DN")
	)
	(segment
		(start 152.11298 -42.761154)
		(end 152.112726 -42.761154)
		(width 0.14605)
		(layer "B.Cu")
		(net "PCIE_COMP_TO_IOM_10_DN")
	)
	(segment
		(start 200.308464 -141.228318)
		(end 200.099676 -141.436852)
		(width 0.14605)
		(layer "B.Cu")
		(net "PCIE_COMP_TO_IOM_10_DN")
	)
	(segment
		(start 163.246054 -98.448622)
		(end 152.96515 -47.04461)
		(width 0.14605)
		(layer "B.Cu")
		(net "PCIE_COMP_TO_IOM_10_DN")
	)
	(segment
		(start 199.564752 -142.588488)
		(end 199.0979 -142.903448)
		(width 0.14605)
		(layer "B.Cu")
		(net "PCIE_COMP_TO_IOM_10_DN")
	)
	(segment
		(start 164.954458 -144.393412)
		(end 161.625534 -142.147544)
		(width 0.14605)
		(layer "B.Cu")
		(net "PCIE_COMP_TO_IOM_10_DN")
	)
	(segment
		(start 136.64438 -29.80182)
		(end 136.64438 -32.327342)
		(width 0.14605)
		(layer "B.Cu")
		(net "PCIE_COMP_TO_IOM_10_DN")
	)
	(segment
		(start 178.199796 -146.96694)
		(end 164.954458 -144.393412)
		(width 0.14605)
		(layer "B.Cu")
		(net "PCIE_COMP_TO_IOM_10_DN")
	)
	(segment
		(start 152.96515 -47.04461)
		(end 152.968706 -47.039784)
		(width 0.14605)
		(layer "B.Cu")
		(net "PCIE_COMP_TO_IOM_10_DN")
	)
	(segment
		(start 200.218802 -140.909802)
		(end 200.308464 -140.999464)
		(width 0.14605)
		(layer "B.Cu")
		(net "PCIE_COMP_TO_IOM_10_DN")
	)
	(segment
		(start 144.522952 -28.561538)
		(end 143.47571 -27.863546)
		(width 0.14605)
		(layer "B.Cu")
		(net "PCIE_COMP_TO_IOM_10_DN")
	)
	(segment
		(start 199.84085 -142.31239)
		(end 199.564752 -142.588488)
		(width 0.14605)
		(layer "B.Cu")
		(net "PCIE_COMP_TO_IOM_10_DN")
	)
	(segment
		(start 143.47571 -27.863546)
		(end 141.924024 -27.55265)
		(width 0.14605)
		(layer "B.Cu")
		(net "PCIE_COMP_TO_IOM_10_DN")
	)
	(segment
		(start 152.112726 -42.761154)
		(end 151.308054 -38.73754)
		(width 0.14605)
		(layer "B.Cu")
		(net "PCIE_COMP_TO_IOM_10_DN")
	)
	(segment
		(start 152.968706 -47.039784)
		(end 152.11298 -42.761154)
		(width 0.14605)
		(layer "B.Cu")
		(net "PCIE_COMP_TO_IOM_10_DN")
	)
	(segment
		(start 141.924024 -27.55265)
		(end 138.89355 -27.55265)
		(width 0.14605)
		(layer "B.Cu")
		(net "PCIE_COMP_TO_IOM_10_DN")
	)
	(segment
		(start 199.84085 -142.037054)
		(end 199.84085 -142.31239)
		(width 0.14605)
		(layer "B.Cu")
		(net "PCIE_COMP_TO_IOM_10_DN")
	)
	(segment
		(start 137.700004 -33.018984)
		(end 137.700004 -33.399984)
		(width 0.14605)
		(layer "B.Cu")
		(net "PCIE_COMP_TO_IOM_10_DN")
	)
	(segment
		(start 200.099676 -141.436852)
		(end 200.081388 -141.45514)
		(width 0.14605)
		(layer "B.Cu")
		(net "PCIE_COMP_TO_IOM_10_DN")
	)
	(segment
		(start 159.978598 -139.706096)
		(end 157.625796 -127.602234)
		(width 0.14605)
		(layer "B.Cu")
		(net "PCIE_COMP_TO_IOM_10_DN")
	)
	(segment
		(start 138.89355 -27.55265)
		(end 136.64438 -29.80182)
		(width 0.14605)
		(layer "B.Cu")
		(net "PCIE_COMP_TO_IOM_10_DN")
	)
	(segment
		(start 157.625796 -127.602234)
		(end 163.246054 -98.448622)
		(width 0.14605)
		(layer "B.Cu")
		(net "PCIE_COMP_TO_IOM_10_DN")
	)
	(segment
		(start 199.0979 -142.903448)
		(end 178.199796 -146.96694)
		(width 0.14605)
		(layer "B.Cu")
		(net "PCIE_COMP_TO_IOM_10_DN")
	)
	(segment
		(start 151.308054 -38.73754)
		(end 144.522952 -28.561538)
		(width 0.14605)
		(layer "B.Cu")
		(net "PCIE_COMP_TO_IOM_10_DN")
	)
	(segment
		(start 137.1727 -32.855662)
		(end 137.536682 -32.855662)
		(width 0.14605)
		(layer "B.Cu")
		(net "PCIE_COMP_TO_IOM_10_DN")
	)
	(arc
		(start 200.081388 -141.45514)
		(mid 199.903297 -141.722184)
		(end 199.84085 -142.037054)
		(width 0.14605)
		(layer "B.Cu")
		(net "PCIE_COMP_TO_IOM_10_DN")
	)
	(arc
		(start 200.308464 -140.999464)
		(mid 200.355988 -141.113928)
		(end 200.308464 -141.228318)
		(width 0.14605)
		(layer "B.Cu")
		(net "PCIE_COMP_TO_IOM_10_DN")
	)
	(arc
		(start 136.64438 -32.327342)
		(mid 136.799121 -32.700921)
		(end 137.1727 -32.855662)
		(width 0.14605)
		(layer "B.Cu")
		(net "PCIE_COMP_TO_IOM_10_DN")
	)
	(arc
		(start 137.536682 -32.855662)
		(mid 137.652168 -32.903498)
		(end 137.700004 -33.018984)
		(width 0.14605)
		(layer "B.Cu")
		(net "PCIE_COMP_TO_IOM_10_DN")
	)
	(segment
		(start 211.988654 -89.386156)
		(end 211.47659 -89.89822)
		(width 0.254)
		(layer "F.Cu")
		(net "P3V3_PG")
	)
	(segment
		(start 212.386164 -90.42019)
		(end 212.386164 -89.386156)
		(width 0.254)
		(layer "F.Cu")
		(net "P3V3_PG")
	)
	(segment
		(start 212.386164 -89.386156)
		(end 211.988654 -89.386156)
		(width 0.254)
		(layer "F.Cu")
		(net "P3V3_PG")
	)
	(segment
		(start 212.392006 -90.426032)
		(end 212.386164 -90.42019)
		(width 0.254)
		(layer "F.Cu")
		(net "P3V3_PG")
	)
	(segment
		(start 211.47659 -89.89822)
		(end 210.853782 -89.89822)
		(width 0.254)
		(layer "F.Cu")
		(net "P3V3_PG")
	)
	(via
		(at 210.853782 -89.89822)
		(size 0.508)
		(drill 0.254)
		(layers "F.Cu" "B.Cu")
		(net "P3V3_PG")
	)
	(via
		(at 212.416136 -89.621868)
		(size 0.6096)
		(drill 0.3048)
		(layers "F.Cu" "B.Cu")
		(net "P3V3_PG")
	)
	(segment
		(start 212.416136 -89.621868)
		(end 212.139784 -89.89822)
		(width 0.254)
		(layer "B.Cu")
		(net "P3V3_PG")
	)
	(segment
		(start 212.139784 -89.89822)
		(end 210.853782 -89.89822)
		(width 0.254)
		(layer "B.Cu")
		(net "P3V3_PG")
	)
	(segment
		(start 212.805264 -88.357456)
		(end 212.805264 -89.23274)
		(width 0.254)
		(layer "B.Cu")
		(net "P3V3_PG")
	)
	(segment
		(start 210.853782 -89.89822)
		(end 210.705446 -89.89822)
		(width 0.254)
		(layer "B.Cu")
		(net "P3V3_PG")
	)
	(segment
		(start 210.379564 -89.572338)
		(end 210.379564 -88.954356)
		(width 0.254)
		(layer "B.Cu")
		(net "P3V3_PG")
	)
	(segment
		(start 210.705446 -89.89822)
		(end 210.379564 -89.572338)
		(width 0.254)
		(layer "B.Cu")
		(net "P3V3_PG")
	)
	(segment
		(start 212.805264 -89.23274)
		(end 212.416136 -89.621868)
		(width 0.254)
		(layer "B.Cu")
		(net "P3V3_PG")
	)
	(segment
		(start 217.53068 -105.275888)
		(end 219.28328 -103.523288)
		(width 0.254)
		(layer "F.Cu")
		(net "P3V3_M2_VREG")
	)
	(segment
		(start 219.28328 -103.523288)
		(end 219.28328 -103.040688)
		(width 0.254)
		(layer "F.Cu")
		(net "P3V3_M2_VREG")
	)
	(segment
		(start 214.999824 -89.917778)
		(end 214.999824 -89.106756)
		(width 0.254)
		(layer "F.Cu")
		(net "P3V3_M2_VREG")
	)
	(segment
		(start 217.25128 -105.275888)
		(end 217.53068 -105.275888)
		(width 0.254)
		(layer "F.Cu")
		(net "P3V3_M2_VREG")
	)
	(segment
		(start 219.28328 -103.040688)
		(end 219.28328 -102.183438)
		(width 0.254)
		(layer "F.Cu")
		(net "P3V3_M2_VREG")
	)
	(segment
		(start 219.28328 -102.183438)
		(end 219.49283 -101.973888)
		(width 0.254)
		(layer "F.Cu")
		(net "P3V3_M2_VREG")
	)
	(segment
		(start 219.49283 -101.973888)
		(end 219.49283 -99.832668)
		(width 0.254)
		(layer "F.Cu")
		(net "P3V3_M2_VREG")
	)
	(via
		(at 217.25128 -105.275888)
		(size 0.508)
		(drill 0.254)
		(layers "F.Cu" "B.Cu")
		(net "P3V3_M2_VREG")
	)
	(via
		(at 214.999824 -89.106756)
		(size 0.508)
		(drill 0.254)
		(layers "F.Cu" "B.Cu")
		(net "P3V3_M2_VREG")
	)
	(via
		(at 213.269322 -99.2632)
		(size 0.6096)
		(drill 0.3048)
		(layers "F.Cu" "B.Cu")
		(net "P3V3_M2_VREG")
	)
	(segment
		(start 213.269322 -99.2632)
		(end 213.269322 -100.16363)
		(width 0.254)
		(layer "B.Cu")
		(net "P3V3_M2_VREG")
	)
	(segment
		(start 213.269322 -99.2632)
		(end 213.269322 -95.40621)
		(width 0.254)
		(layer "B.Cu")
		(net "P3V3_M2_VREG")
	)
	(segment
		(start 213.269322 -95.40621)
		(end 214.89797 -93.777562)
		(width 0.254)
		(layer "B.Cu")
		(net "P3V3_M2_VREG")
	)
	(segment
		(start 216.712546 -104.737154)
		(end 216.712546 -103.606854)
		(width 0.254)
		(layer "B.Cu")
		(net "P3V3_M2_VREG")
	)
	(segment
		(start 216.712546 -103.606854)
		(end 215.60028 -102.494588)
		(width 0.254)
		(layer "B.Cu")
		(net "P3V3_M2_VREG")
	)
	(segment
		(start 214.89797 -89.20861)
		(end 214.999824 -89.106756)
		(width 0.254)
		(layer "B.Cu")
		(net "P3V3_M2_VREG")
	)
	(segment
		(start 217.25128 -105.275888)
		(end 216.712546 -104.737154)
		(width 0.254)
		(layer "B.Cu")
		(net "P3V3_M2_VREG")
	)
	(segment
		(start 213.269322 -100.16363)
		(end 215.60028 -102.494588)
		(width 0.254)
		(layer "B.Cu")
		(net "P3V3_M2_VREG")
	)
	(segment
		(start 214.89797 -93.777562)
		(end 214.89797 -89.20861)
		(width 0.254)
		(layer "B.Cu")
		(net "P3V3_M2_VREG")
	)
	(segment
		(start 212.085936 -95.127826)
		(end 212.085936 -95.280988)
		(width 0.254)
		(layer "F.Cu")
		(net "P3V3_M2_VFB")
	)
	(segment
		(start 214.410798 -95.420688)
		(end 215.34628 -95.420688)
		(width 0.254)
		(layer "F.Cu")
		(net "P3V3_M2_VFB")
	)
	(segment
		(start 214.117936 -95.127826)
		(end 213.098888 -95.127826)
		(width 0.254)
		(layer "F.Cu")
		(net "P3V3_M2_VFB")
	)
	(segment
		(start 214.117936 -95.127826)
		(end 214.410798 -95.420688)
		(width 0.254)
		(layer "F.Cu")
		(net "P3V3_M2_VFB")
	)
	(segment
		(start 212.085936 -95.280988)
		(end 213.011258 -96.20631)
		(width 0.254)
		(layer "F.Cu")
		(net "P3V3_M2_VFB")
	)
	(segment
		(start 215.774016 -95.420688)
		(end 216.26068 -94.934024)
		(width 0.254)
		(layer "F.Cu")
		(net "P3V3_M2_VFB")
	)
	(segment
		(start 213.098888 -95.127826)
		(end 212.085936 -95.127826)
		(width 0.254)
		(layer "F.Cu")
		(net "P3V3_M2_VFB")
	)
	(segment
		(start 216.26068 -94.934024)
		(end 217.492834 -94.934024)
		(width 0.254)
		(layer "F.Cu")
		(net "P3V3_M2_VFB")
	)
	(segment
		(start 215.34628 -95.420688)
		(end 215.774016 -95.420688)
		(width 0.254)
		(layer "F.Cu")
		(net "P3V3_M2_VFB")
	)
	(via
		(at 215.34628 -95.420688)
		(size 0.6604)
		(drill 0.3302)
		(layers "F.Cu" "B.Cu")
		(net "P3V3_M2_VFB")
	)
	(via
		(at 218.823794 -89.626694)
		(size 0.6096)
		(drill 0.3048)
		(layers "F.Cu" "B.Cu")
		(net "P3V3_M2_VBST_RC")
	)
	(segment
		(start 218.833192 -88.57361)
		(end 218.823794 -88.583008)
		(width 0.508)
		(layer "B.Cu")
		(net "P3V3_M2_VBST_RC")
	)
	(segment
		(start 218.823794 -90.719402)
		(end 218.823794 -89.626694)
		(width 0.508)
		(layer "B.Cu")
		(net "P3V3_M2_VBST_RC")
	)
	(segment
		(start 218.823794 -88.583008)
		(end 218.823794 -89.626694)
		(width 0.508)
		(layer "B.Cu")
		(net "P3V3_M2_VBST_RC")
	)
	(segment
		(start 218.80068 -93.286326)
		(end 218.992958 -93.478604)
		(width 0.508)
		(layer "F.Cu")
		(net "P3V3_M2_VBST")
	)
	(segment
		(start 218.992958 -93.478604)
		(end 218.992958 -93.538548)
		(width 0.508)
		(layer "F.Cu")
		(net "P3V3_M2_VBST")
	)
	(segment
		(start 218.992958 -93.538548)
		(end 218.992958 -94.934024)
		(width 0.254)
		(layer "F.Cu")
		(net "P3V3_M2_VBST")
	)
	(via
		(at 218.80068 -93.286326)
		(size 0.508)
		(drill 0.254)
		(layers "F.Cu" "B.Cu")
		(net "P3V3_M2_VBST")
	)
	(segment
		(start 218.823794 -93.263212)
		(end 218.823794 -92.243402)
		(width 0.508)
		(layer "B.Cu")
		(net "P3V3_M2_VBST")
	)
	(segment
		(start 218.80068 -93.286326)
		(end 218.823794 -93.263212)
		(width 0.508)
		(layer "B.Cu")
		(net "P3V3_M2_VBST")
	)
	(segment
		(start 217.546936 -100.855526)
		(end 217.175842 -100.855526)
		(width 0.254)
		(layer "F.Cu")
		(net "P3V3_M2_TRIP")
	)
	(segment
		(start 216.431876 -101.599492)
		(end 215.62314 -101.599492)
		(width 0.254)
		(layer "F.Cu")
		(net "P3V3_M2_TRIP")
	)
	(segment
		(start 217.99296 -100.409502)
		(end 217.546936 -100.855526)
		(width 0.254)
		(layer "F.Cu")
		(net "P3V3_M2_TRIP")
	)
	(segment
		(start 217.99296 -99.832668)
		(end 217.99296 -100.409502)
		(width 0.254)
		(layer "F.Cu")
		(net "P3V3_M2_TRIP")
	)
	(segment
		(start 216.589864 -101.441504)
		(end 216.431876 -101.599492)
		(width 0.254)
		(layer "F.Cu")
		(net "P3V3_M2_TRIP")
	)
	(segment
		(start 217.175842 -100.855526)
		(end 216.589864 -101.441504)
		(width 0.254)
		(layer "F.Cu")
		(net "P3V3_M2_TRIP")
	)
	(via
		(at 216.589864 -101.441504)
		(size 0.6604)
		(drill 0.3302)
		(layers "F.Cu" "B.Cu")
		(net "P3V3_M2_TRIP")
	)
	(segment
		(start 226.222306 -95.239586)
		(end 226.304602 -95.321882)
		(width 0.508)
		(layer "F.Cu")
		(net "P3V3_M2_SNB")
	)
	(segment
		(start 226.222306 -94.26194)
		(end 226.222306 -95.239586)
		(width 0.508)
		(layer "F.Cu")
		(net "P3V3_M2_SNB")
	)
	(segment
		(start 226.356164 -96.854264)
		(end 226.356164 -95.373444)
		(width 0.508)
		(layer "F.Cu")
		(net "P3V3_M2_SNB")
	)
	(segment
		(start 226.356164 -95.373444)
		(end 226.304602 -95.321882)
		(width 0.508)
		(layer "F.Cu")
		(net "P3V3_M2_SNB")
	)
	(via
		(at 226.304602 -95.321882)
		(size 0.6604)
		(drill 0.3302)
		(layers "F.Cu" "B.Cu")
		(net "P3V3_M2_SNB")
	)
	(segment
		(start 215.62314 -100.583492)
		(end 215.62314 -99.892866)
		(width 0.254)
		(layer "F.Cu")
		(net "P3V3_M2_RF")
	)
	(segment
		(start 215.62314 -99.892866)
		(end 215.297766 -99.567492)
		(width 0.254)
		(layer "F.Cu")
		(net "P3V3_M2_RF")
	)
	(segment
		(start 215.62314 -100.583492)
		(end 216.02954 -100.177092)
		(width 0.254)
		(layer "F.Cu")
		(net "P3V3_M2_RF")
	)
	(segment
		(start 216.02954 -100.177092)
		(end 216.67724 -100.177092)
		(width 0.254)
		(layer "F.Cu")
		(net "P3V3_M2_RF")
	)
	(segment
		(start 216.67724 -100.177092)
		(end 217.021664 -99.832668)
		(width 0.254)
		(layer "F.Cu")
		(net "P3V3_M2_RF")
	)
	(segment
		(start 217.021664 -99.832668)
		(end 217.492834 -99.832668)
		(width 0.254)
		(layer "F.Cu")
		(net "P3V3_M2_RF")
	)
	(via
		(at 215.297766 -99.567492)
		(size 0.508)
		(drill 0.254)
		(layers "F.Cu" "B.Cu")
		(net "P3V3_M2_RF")
	)
	(via
		(at 215.60028 -100.475288)
		(size 0.6096)
		(drill 0.3048)
		(layers "F.Cu" "B.Cu")
		(net "P3V3_M2_RF")
	)
	(segment
		(start 215.60028 -99.870006)
		(end 215.297766 -99.567492)
		(width 0.254)
		(layer "B.Cu")
		(net "P3V3_M2_RF")
	)
	(segment
		(start 215.60028 -101.605588)
		(end 215.60028 -100.475288)
		(width 0.254)
		(layer "B.Cu")
		(net "P3V3_M2_RF")
	)
	(segment
		(start 215.60028 -100.475288)
		(end 215.60028 -99.870006)
		(width 0.254)
		(layer "B.Cu")
		(net "P3V3_M2_RF")
	)
	(segment
		(start 215.62314 -102.615492)
		(end 215.68664 -102.678992)
		(width 0.254)
		(layer "F.Cu")
		(net "P3V3_M2_MODE")
	)
	(segment
		(start 218.01328 -101.389688)
		(end 218.01328 -101.024182)
		(width 0.254)
		(layer "F.Cu")
		(net "P3V3_M2_MODE")
	)
	(segment
		(start 215.68664 -102.678992)
		(end 216.67724 -102.678992)
		(width 0.254)
		(layer "F.Cu")
		(net "P3V3_M2_MODE")
	)
	(segment
		(start 216.67724 -102.678992)
		(end 216.723976 -102.678992)
		(width 0.254)
		(layer "F.Cu")
		(net "P3V3_M2_MODE")
	)
	(segment
		(start 218.01328 -101.024182)
		(end 218.492832 -100.54463)
		(width 0.254)
		(layer "F.Cu")
		(net "P3V3_M2_MODE")
	)
	(segment
		(start 218.492832 -100.54463)
		(end 218.492832 -99.832668)
		(width 0.254)
		(layer "F.Cu")
		(net "P3V3_M2_MODE")
	)
	(segment
		(start 216.723976 -102.678992)
		(end 217.857324 -101.545644)
		(width 0.254)
		(layer "F.Cu")
		(net "P3V3_M2_MODE")
	)
	(segment
		(start 217.857324 -101.545644)
		(end 218.01328 -101.389688)
		(width 0.254)
		(layer "F.Cu")
		(net "P3V3_M2_MODE")
	)
	(via
		(at 217.857324 -101.545644)
		(size 0.6604)
		(drill 0.3302)
		(layers "F.Cu" "B.Cu")
		(net "P3V3_M2_MODE")
	)
	(segment
		(start 214.117936 -94.115128)
		(end 214.117936 -94.238826)
		(width 0.254)
		(layer "F.Cu")
		(net "P3V3_M2_LL_R")
	)
	(segment
		(start 209.897726 -87.442294)
		(end 209.897726 -92.06484)
		(width 0.254)
		(layer "F.Cu")
		(net "P3V3_M2_LL_R")
	)
	(segment
		(start 214.504524 -87.18296)
		(end 214.504524 -86.42096)
		(width 0.254)
		(layer "F.Cu")
		(net "P3V3_M2_LL_R")
	)
	(segment
		(start 213.919308 -85.835744)
		(end 212.894926 -85.835744)
		(width 0.254)
		(layer "F.Cu")
		(net "P3V3_M2_LL_R")
	)
	(segment
		(start 211.504276 -85.835744)
		(end 209.897726 -87.442294)
		(width 0.254)
		(layer "F.Cu")
		(net "P3V3_M2_LL_R")
	)
	(segment
		(start 209.897726 -92.06484)
		(end 210.547712 -92.714826)
		(width 0.254)
		(layer "F.Cu")
		(net "P3V3_M2_LL_R")
	)
	(segment
		(start 212.717634 -92.714826)
		(end 214.117936 -94.115128)
		(width 0.254)
		(layer "F.Cu")
		(net "P3V3_M2_LL_R")
	)
	(segment
		(start 214.885524 -87.56396)
		(end 214.504524 -87.18296)
		(width 0.254)
		(layer "F.Cu")
		(net "P3V3_M2_LL_R")
	)
	(segment
		(start 210.547712 -92.714826)
		(end 212.717634 -92.714826)
		(width 0.254)
		(layer "F.Cu")
		(net "P3V3_M2_LL_R")
	)
	(segment
		(start 214.504524 -86.42096)
		(end 213.919308 -85.835744)
		(width 0.254)
		(layer "F.Cu")
		(net "P3V3_M2_LL_R")
	)
	(segment
		(start 212.894926 -85.835744)
		(end 211.504276 -85.835744)
		(width 0.254)
		(layer "F.Cu")
		(net "P3V3_M2_LL_R")
	)
	(via
		(at 212.894926 -85.835744)
		(size 0.6604)
		(drill 0.3302)
		(layers "F.Cu" "B.Cu")
		(net "P3V3_M2_LL_R")
	)
	(segment
		(start 222.442024 -87.30996)
		(end 222.873824 -87.74176)
		(width 0.254)
		(layer "F.Cu")
		(net "P3V3_M2_LL")
	)
	(segment
		(start 216.028524 -87.30996)
		(end 222.442024 -87.30996)
		(width 0.254)
		(layer "F.Cu")
		(net "P3V3_M2_LL")
	)
	(segment
		(start 222.873824 -87.74176)
		(end 222.873824 -90.681048)
		(width 0.254)
		(layer "F.Cu")
		(net "P3V3_M2_LL")
	)
	(segment
		(start 215.774524 -87.56396)
		(end 216.028524 -87.30996)
		(width 0.254)
		(layer "F.Cu")
		(net "P3V3_M2_LL")
	)
	(via
		(at 220.581982 -88.680036)
		(size 0.508)
		(drill 0.254)
		(layers "F.Cu" "B.Cu")
		(net "P3V3_M2_LL")
	)
	(via
		(at 224.21723 -93.950028)
		(size 0.6604)
		(drill 0.3302)
		(layers "F.Cu" "B.Cu")
		(net "P3V3_M2_LL")
	)
	(segment
		(start 220.475556 -88.57361)
		(end 220.581982 -88.680036)
		(width 0.508)
		(layer "B.Cu")
		(net "P3V3_M2_LL")
	)
	(segment
		(start 219.722192 -88.57361)
		(end 220.475556 -88.57361)
		(width 0.508)
		(layer "B.Cu")
		(net "P3V3_M2_LL")
	)
	(segment
		(start 213.896702 -91.518994)
		(end 213.274402 -91.518994)
		(width 0.254)
		(layer "F.Cu")
		(net "P3V3_M2_EN")
	)
	(segment
		(start 215.219026 -91.966034)
		(end 216.36228 -93.109288)
		(width 0.254)
		(layer "F.Cu")
		(net "P3V3_M2_EN")
	)
	(segment
		(start 216.768172 -93.109288)
		(end 217.99296 -94.334076)
		(width 0.254)
		(layer "F.Cu")
		(net "P3V3_M2_EN")
	)
	(segment
		(start 217.99296 -94.334076)
		(end 217.99296 -94.934024)
		(width 0.254)
		(layer "F.Cu")
		(net "P3V3_M2_EN")
	)
	(segment
		(start 213.274402 -91.518994)
		(end 213.274402 -90.432636)
		(width 0.254)
		(layer "F.Cu")
		(net "P3V3_M2_EN")
	)
	(segment
		(start 214.343742 -91.966034)
		(end 213.896702 -91.518994)
		(width 0.254)
		(layer "F.Cu")
		(net "P3V3_M2_EN")
	)
	(segment
		(start 216.36228 -93.109288)
		(end 216.768172 -93.109288)
		(width 0.254)
		(layer "F.Cu")
		(net "P3V3_M2_EN")
	)
	(segment
		(start 214.658194 -91.966034)
		(end 215.219026 -91.966034)
		(width 0.254)
		(layer "F.Cu")
		(net "P3V3_M2_EN")
	)
	(segment
		(start 214.658194 -91.966034)
		(end 214.343742 -91.966034)
		(width 0.254)
		(layer "F.Cu")
		(net "P3V3_M2_EN")
	)
	(segment
		(start 213.274402 -90.432636)
		(end 213.281006 -90.426032)
		(width 0.254)
		(layer "F.Cu")
		(net "P3V3_M2_EN")
	)
	(via
		(at 214.658194 -91.966034)
		(size 0.6604)
		(drill 0.3302)
		(layers "F.Cu" "B.Cu")
		(net "P3V3_M2_EN")
	)
	(segment
		(start 112.483646 -27.703526)
		(end 112.483646 -27.737054)
		(width 0.254)
		(layer "F.Cu")
		(net "P3V3_M2")
	)
	(segment
		(start 170.63339 -121.049542)
		(end 170.116246 -120.532398)
		(width 0.508)
		(layer "F.Cu")
		(net "P3V3_M2")
	)
	(segment
		(start 170.116246 -120.532398)
		(end 170.116246 -116.337588)
		(width 0.508)
		(layer "F.Cu")
		(net "P3V3_M2")
	)
	(segment
		(start 182.884318 -120.691656)
		(end 183.8452 -120.691656)
		(width 0.508)
		(layer "F.Cu")
		(net "P3V3_M2")
	)
	(segment
		(start 209.226912 -119.342662)
		(end 209.226912 -120.2817)
		(width 0.508)
		(layer "F.Cu")
		(net "P3V3_M2")
	)
	(segment
		(start 112.4839 -27.703272)
		(end 112.483646 -27.703526)
		(width 0.254)
		(layer "F.Cu")
		(net "P3V3_M2")
	)
	(segment
		(start 216.282524 -86.67496)
		(end 216.028524 -86.42096)
		(width 0.254)
		(layer "F.Cu")
		(net "P3V3_M2")
	)
	(segment
		(start 208.424272 -94.238826)
		(end 207.518 -94.238826)
		(width 0.254)
		(layer "F.Cu")
		(net "P3V3_M2")
	)
	(segment
		(start 222.873824 -81.88706)
		(end 222.873824 -86.26856)
		(width 0.254)
		(layer "F.Cu")
		(net "P3V3_M2")
	)
	(segment
		(start 222.467424 -86.67496)
		(end 216.282524 -86.67496)
		(width 0.254)
		(layer "F.Cu")
		(net "P3V3_M2")
	)
	(segment
		(start 209.22234 -119.33809)
		(end 209.226912 -119.342662)
		(width 0.508)
		(layer "F.Cu")
		(net "P3V3_M2")
	)
	(segment
		(start 112.4839 -27.4193)
		(end 112.4839 -27.703272)
		(width 0.254)
		(layer "F.Cu")
		(net "P3V3_M2")
	)
	(segment
		(start 222.873824 -86.26856)
		(end 222.467424 -86.67496)
		(width 0.254)
		(layer "F.Cu")
		(net "P3V3_M2")
	)
	(segment
		(start 207.518 -94.238826)
		(end 207.517238 -94.239588)
		(width 0.254)
		(layer "F.Cu")
		(net "P3V3_M2")
	)
	(segment
		(start 116.713 -24.257)
		(end 115.6462 -24.257)
		(width 0.254)
		(layer "F.Cu")
		(net "P3V3_M2")
	)
	(segment
		(start 115.6462 -24.257)
		(end 112.4839 -27.4193)
		(width 0.254)
		(layer "F.Cu")
		(net "P3V3_M2")
	)
	(segment
		(start 112.483646 -27.737054)
		(end 112.0394 -28.1813)
		(width 0.254)
		(layer "F.Cu")
		(net "P3V3_M2")
	)
	(segment
		(start 170.63339 -121.86539)
		(end 170.63339 -121.049542)
		(width 0.508)
		(layer "F.Cu")
		(net "P3V3_M2")
	)
	(via
		(at 171.407328 -125.5014)
		(size 0.7112)
		(drill 0.4064)
		(layers "F.Cu" "B.Cu")
		(net "P3V3_M2")
	)
	(via
		(at 183.8452 -120.691656)
		(size 0.508)
		(drill 0.254)
		(layers "F.Cu" "B.Cu")
		(net "P3V3_M2")
	)
	(via
		(at 201.2442 -127.5588)
		(size 0.6096)
		(drill 0.3048)
		(layers "F.Cu" "B.Cu")
		(net "P3V3_M2")
	)
	(via
		(at 182.010812 -129.479548)
		(size 0.7112)
		(drill 0.4064)
		(layers "F.Cu" "B.Cu")
		(net "P3V3_M2")
	)
	(via
		(at 219.508578 -76.279756)
		(size 0.7112)
		(drill 0.4064)
		(layers "F.Cu" "B.Cu")
		(net "P3V3_M2")
	)
	(via
		(at 207.517238 -94.239588)
		(size 0.508)
		(drill 0.254)
		(layers "F.Cu" "B.Cu")
		(net "P3V3_M2")
	)
	(via
		(at 112.0394 -28.1813)
		(size 0.508)
		(drill 0.254)
		(layers "F.Cu" "B.Cu")
		(net "P3V3_M2")
	)
	(via
		(at 221.837504 -68.913502)
		(size 0.7112)
		(drill 0.4064)
		(layers "F.Cu" "B.Cu")
		(net "P3V3_M2")
	)
	(via
		(at 219.508578 -73.739756)
		(size 0.7112)
		(drill 0.4064)
		(layers "F.Cu" "B.Cu")
		(net "P3V3_M2")
	)
	(via
		(at 212.349842 -129.063496)
		(size 0.7112)
		(drill 0.4064)
		(layers "F.Cu" "B.Cu")
		(net "P3V3_M2")
	)
	(via
		(at 213.374478 -125.55728)
		(size 0.7112)
		(drill 0.4064)
		(layers "F.Cu" "B.Cu")
		(net "P3V3_M2")
	)
	(via
		(at 208.320894 -129.020316)
		(size 0.7112)
		(drill 0.4064)
		(layers "F.Cu" "B.Cu")
		(net "P3V3_M2")
	)
	(via
		(at 100.661724 -177.477928)
		(size 0.508)
		(drill 0.254)
		(layers "F.Cu" "B.Cu")
		(net "P3V3_M2")
	)
	(via
		(at 219.508578 -75.009756)
		(size 0.7112)
		(drill 0.4064)
		(layers "F.Cu" "B.Cu")
		(net "P3V3_M2")
	)
	(via
		(at 186.999118 -125.390656)
		(size 0.7112)
		(drill 0.4064)
		(layers "F.Cu" "B.Cu")
		(net "P3V3_M2")
	)
	(via
		(at 218.289378 -78.718156)
		(size 0.7112)
		(drill 0.4064)
		(layers "F.Cu" "B.Cu")
		(net "P3V3_M2")
	)
	(via
		(at 172.677328 -124.2314)
		(size 0.7112)
		(drill 0.4064)
		(layers "F.Cu" "B.Cu")
		(net "P3V3_M2")
	)
	(via
		(at 109.796326 -5.07492)
		(size 0.508)
		(drill 0.254)
		(layers "F.Cu" "B.Cu")
		(net "P3V3_M2")
	)
	(via
		(at 221.124272 -76.847192)
		(size 0.6096)
		(drill 0.3048)
		(layers "F.Cu" "B.Cu")
		(net "P3V3_M2")
	)
	(via
		(at 196.001132 -124.30252)
		(size 0.7112)
		(drill 0.4064)
		(layers "F.Cu" "B.Cu")
		(net "P3V3_M2")
	)
	(via
		(at 173.4312 -122.0978)
		(size 0.7112)
		(drill 0.4064)
		(layers "F.Cu" "B.Cu")
		(net "P3V3_M2")
	)
	(via
		(at 171.4246 -122.7582)
		(size 0.7112)
		(drill 0.4064)
		(layers "F.Cu" "B.Cu")
		(net "P3V3_M2")
	)
	(via
		(at 191.160908 -131.5339)
		(size 0.7112)
		(drill 0.4064)
		(layers "F.Cu" "B.Cu")
		(net "P3V3_M2")
	)
	(via
		(at 209.590894 -129.020316)
		(size 0.7112)
		(drill 0.4064)
		(layers "F.Cu" "B.Cu")
		(net "P3V3_M2")
	)
	(via
		(at 204.719682 -129.106422)
		(size 0.7112)
		(drill 0.4064)
		(layers "F.Cu" "B.Cu")
		(net "P3V3_M2")
	)
	(via
		(at 218.289378 -75.009756)
		(size 0.7112)
		(drill 0.4064)
		(layers "F.Cu" "B.Cu")
		(net "P3V3_M2")
	)
	(via
		(at 202.8444 -127.635)
		(size 0.6096)
		(drill 0.3048)
		(layers "F.Cu" "B.Cu")
		(net "P3V3_M2")
	)
	(via
		(at 170.116246 -116.337588)
		(size 0.508)
		(drill 0.254)
		(layers "F.Cu" "B.Cu")
		(net "P3V3_M2")
	)
	(via
		(at 219.508578 -77.498956)
		(size 0.7112)
		(drill 0.4064)
		(layers "F.Cu" "B.Cu")
		(net "P3V3_M2")
	)
	(via
		(at 201.42581 -128.97739)
		(size 0.7112)
		(drill 0.4064)
		(layers "F.Cu" "B.Cu")
		(net "P3V3_M2")
	)
	(via
		(at 198.541132 -125.57252)
		(size 0.7112)
		(drill 0.4064)
		(layers "F.Cu" "B.Cu")
		(net "P3V3_M2")
	)
	(via
		(at 218.289378 -73.739756)
		(size 0.7112)
		(drill 0.4064)
		(layers "F.Cu" "B.Cu")
		(net "P3V3_M2")
	)
	(via
		(at 220.567504 -68.913502)
		(size 0.7112)
		(drill 0.4064)
		(layers "F.Cu" "B.Cu")
		(net "P3V3_M2")
	)
	(via
		(at 197.271132 -125.57252)
		(size 0.7112)
		(drill 0.4064)
		(layers "F.Cu" "B.Cu")
		(net "P3V3_M2")
	)
	(via
		(at 207.050894 -129.020316)
		(size 0.7112)
		(drill 0.4064)
		(layers "F.Cu" "B.Cu")
		(net "P3V3_M2")
	)
	(via
		(at 173.101 -127.254)
		(size 0.6096)
		(drill 0.3048)
		(layers "F.Cu" "B.Cu")
		(net "P3V3_M2")
	)
	(via
		(at 197.271132 -124.30252)
		(size 0.7112)
		(drill 0.4064)
		(layers "F.Cu" "B.Cu")
		(net "P3V3_M2")
	)
	(via
		(at 183.28386 -129.961386)
		(size 0.7112)
		(drill 0.4064)
		(layers "F.Cu" "B.Cu")
		(net "P3V3_M2")
	)
	(via
		(at 185.82132 -128.964436)
		(size 0.7112)
		(drill 0.4064)
		(layers "F.Cu" "B.Cu")
		(net "P3V3_M2")
	)
	(via
		(at 172.4914 -122.7582)
		(size 0.7112)
		(drill 0.4064)
		(layers "F.Cu" "B.Cu")
		(net "P3V3_M2")
	)
	(via
		(at 209.22234 -119.33809)
		(size 0.508)
		(drill 0.254)
		(layers "F.Cu" "B.Cu")
		(net "P3V3_M2")
	)
	(via
		(at 50.6984 -164.1602)
		(size 0.508)
		(drill 0.254)
		(layers "F.Cu" "B.Cu")
		(net "P3V3_M2")
	)
	(via
		(at 184.55386 -129.961386)
		(size 0.7112)
		(drill 0.4064)
		(layers "F.Cu" "B.Cu")
		(net "P3V3_M2")
	)
	(via
		(at 221.093538 -71.499222)
		(size 0.6096)
		(drill 0.3048)
		(layers "F.Cu" "B.Cu")
		(net "P3V3_M2")
	)
	(via
		(at 212.104478 -125.55728)
		(size 0.7112)
		(drill 0.4064)
		(layers "F.Cu" "B.Cu")
		(net "P3V3_M2")
	)
	(via
		(at 217.92311 -69.3801)
		(size 0.7112)
		(drill 0.4064)
		(layers "F.Cu" "B.Cu")
		(net "P3V3_M2")
	)
	(via
		(at 218.289378 -76.279756)
		(size 0.7112)
		(drill 0.4064)
		(layers "F.Cu" "B.Cu")
		(net "P3V3_M2")
	)
	(via
		(at 200.15581 -128.97739)
		(size 0.7112)
		(drill 0.4064)
		(layers "F.Cu" "B.Cu")
		(net "P3V3_M2")
	)
	(via
		(at 173.5074 -123.2408)
		(size 0.7112)
		(drill 0.4064)
		(layers "F.Cu" "B.Cu")
		(net "P3V3_M2")
	)
	(via
		(at 171.407328 -124.2314)
		(size 0.7112)
		(drill 0.4064)
		(layers "F.Cu" "B.Cu")
		(net "P3V3_M2")
	)
	(via
		(at 98.1075 -80.8355)
		(size 0.508)
		(drill 0.254)
		(layers "F.Cu" "B.Cu")
		(net "P3V3_M2")
	)
	(via
		(at 198.541132 -124.30252)
		(size 0.7112)
		(drill 0.4064)
		(layers "F.Cu" "B.Cu")
		(net "P3V3_M2")
	)
	(via
		(at 219.508578 -78.718156)
		(size 0.7112)
		(drill 0.4064)
		(layers "F.Cu" "B.Cu")
		(net "P3V3_M2")
	)
	(via
		(at 183.957468 -128.197102)
		(size 0.6096)
		(drill 0.3048)
		(layers "F.Cu" "B.Cu")
		(net "P3V3_M2")
	)
	(via
		(at 218.289378 -77.498956)
		(size 0.7112)
		(drill 0.4064)
		(layers "F.Cu" "B.Cu")
		(net "P3V3_M2")
	)
	(via
		(at 116.713 -24.257)
		(size 0.508)
		(drill 0.254)
		(layers "F.Cu" "B.Cu")
		(net "P3V3_M2")
	)
	(via
		(at 191.726566 -127.563372)
		(size 0.6096)
		(drill 0.3048)
		(layers "F.Cu" "B.Cu")
		(net "P3V3_M2")
	)
	(via
		(at 144.1958 -7.17296)
		(size 0.7112)
		(drill 0.4064)
		(layers "F.Cu" "B.Cu")
		(net "P3V3_M2")
	)
	(via
		(at 172.332396 -121.41327)
		(size 0.6604)
		(drill 0.3302)
		(layers "F.Cu" "B.Cu")
		(net "P3V3_M2")
	)
	(via
		(at 198.88581 -128.97739)
		(size 0.7112)
		(drill 0.4064)
		(layers "F.Cu" "B.Cu")
		(net "P3V3_M2")
	)
	(via
		(at 219.508578 -72.469756)
		(size 0.7112)
		(drill 0.4064)
		(layers "F.Cu" "B.Cu")
		(net "P3V3_M2")
	)
	(via
		(at 189.890908 -131.5339)
		(size 0.7112)
		(drill 0.4064)
		(layers "F.Cu" "B.Cu")
		(net "P3V3_M2")
	)
	(via
		(at 188.269118 -125.390656)
		(size 0.7112)
		(drill 0.4064)
		(layers "F.Cu" "B.Cu")
		(net "P3V3_M2")
	)
	(via
		(at 187.09132 -128.964436)
		(size 0.7112)
		(drill 0.4064)
		(layers "F.Cu" "B.Cu")
		(net "P3V3_M2")
	)
	(via
		(at 218.289378 -72.469756)
		(size 0.7112)
		(drill 0.4064)
		(layers "F.Cu" "B.Cu")
		(net "P3V3_M2")
	)
	(via
		(at 49.657 -177.0126)
		(size 0.508)
		(drill 0.254)
		(layers "F.Cu" "B.Cu")
		(net "P3V3_M2")
	)
	(via
		(at 196.001132 -125.57252)
		(size 0.7112)
		(drill 0.4064)
		(layers "F.Cu" "B.Cu")
		(net "P3V3_M2")
	)
	(via
		(at 172.677328 -125.5014)
		(size 0.7112)
		(drill 0.4064)
		(layers "F.Cu" "B.Cu")
		(net "P3V3_M2")
	)
	(segment
		(start 50.9524 -164.1602)
		(end 51.7017 -163.4109)
		(width 0.254)
		(layer "B.Cu")
		(net "P3V3_M2")
	)
	(segment
		(start 100.661724 -177.477928)
		(end 101.3206 -176.819052)
		(width 0.254)
		(layer "B.Cu")
		(net "P3V3_M2")
	)
	(segment
		(start 224.545144 -68.192396)
		(end 224.315782 -67.963034)
		(width 0.254)
		(layer "B.Cu")
		(net "P3V3_M2")
	)
	(segment
		(start 207.417924 -94.140274)
		(end 207.517238 -94.239588)
		(width 0.254)
		(layer "B.Cu")
		(net "P3V3_M2")
	)
	(segment
		(start 101.3206 -176.819052)
		(end 101.3206 -171.0436)
		(width 0.254)
		(layer "B.Cu")
		(net "P3V3_M2")
	)
	(segment
		(start 125.8062 -4.2672)
		(end 110.604046 -4.2672)
		(width 0.254)
		(layer "B.Cu")
		(net "P3V3_M2")
	)
	(segment
		(start 224.545144 -68.51523)
		(end 224.545144 -68.192396)
		(width 0.254)
		(layer "B.Cu")
		(net "P3V3_M2")
	)
	(segment
		(start 205.181962 -84.861654)
		(end 205.181962 -91.929204)
		(width 0.254)
		(layer "B.Cu")
		(net "P3V3_M2")
	)
	(segment
		(start 110.604046 -4.2672)
		(end 109.796326 -5.07492)
		(width 0.254)
		(layer "B.Cu")
		(net "P3V3_M2")
	)
	(segment
		(start 215.060784 -74.982832)
		(end 205.181962 -84.861654)
		(width 0.254)
		(layer "B.Cu")
		(net "P3V3_M2")
	)
	(segment
		(start 216.479374 -67.963034)
		(end 215.060784 -69.381624)
		(width 0.254)
		(layer "B.Cu")
		(net "P3V3_M2")
	)
	(segment
		(start 102.6033 -85.3313)
		(end 98.1075 -80.8355)
		(width 0.254)
		(layer "B.Cu")
		(net "P3V3_M2")
	)
	(segment
		(start 102.7684 -132.08)
		(end 102.6033 -131.9149)
		(width 0.254)
		(layer "B.Cu")
		(net "P3V3_M2")
	)
	(segment
		(start 101.3206 -171.0436)
		(end 102.7684 -169.5958)
		(width 0.254)
		(layer "B.Cu")
		(net "P3V3_M2")
	)
	(segment
		(start 51.7017 -163.4109)
		(end 51.7017 -163.1442)
		(width 0.254)
		(layer "B.Cu")
		(net "P3V3_M2")
	)
	(segment
		(start 144.1958 -7.17296)
		(end 141.49324 -4.4704)
		(width 0.254)
		(layer "B.Cu")
		(net "P3V3_M2")
	)
	(segment
		(start 126.9238 -5.3848)
		(end 125.8062 -4.2672)
		(width 0.254)
		(layer "B.Cu")
		(net "P3V3_M2")
	)
	(segment
		(start 224.315782 -67.963034)
		(end 216.479374 -67.963034)
		(width 0.254)
		(layer "B.Cu")
		(net "P3V3_M2")
	)
	(segment
		(start 132.8166 -4.4704)
		(end 131.9022 -5.3848)
		(width 0.254)
		(layer "B.Cu")
		(net "P3V3_M2")
	)
	(segment
		(start 131.9022 -5.3848)
		(end 126.9238 -5.3848)
		(width 0.254)
		(layer "B.Cu")
		(net "P3V3_M2")
	)
	(segment
		(start 102.7684 -169.5958)
		(end 102.7684 -132.08)
		(width 0.254)
		(layer "B.Cu")
		(net "P3V3_M2")
	)
	(segment
		(start 141.49324 -4.4704)
		(end 132.8166 -4.4704)
		(width 0.254)
		(layer "B.Cu")
		(net "P3V3_M2")
	)
	(segment
		(start 215.060784 -69.381624)
		(end 215.060784 -74.982832)
		(width 0.254)
		(layer "B.Cu")
		(net "P3V3_M2")
	)
	(segment
		(start 50.6984 -164.1602)
		(end 50.9524 -164.1602)
		(width 0.254)
		(layer "B.Cu")
		(net "P3V3_M2")
	)
	(segment
		(start 205.181962 -91.929204)
		(end 207.393032 -94.140274)
		(width 0.254)
		(layer "B.Cu")
		(net "P3V3_M2")
	)
	(segment
		(start 102.6033 -131.9149)
		(end 102.6033 -85.3313)
		(width 0.254)
		(layer "B.Cu")
		(net "P3V3_M2")
	)
	(segment
		(start 207.393032 -94.140274)
		(end 207.417924 -94.140274)
		(width 0.254)
		(layer "B.Cu")
		(net "P3V3_M2")
	)
	(segment
		(start 163.59886 -36.970462)
		(end 163.59886 -100.522786)
		(width 0.254)
		(layer "In2.Cu")
		(net "P3V3_M2")
	)
	(segment
		(start 144.1958 -7.17296)
		(end 144.19834 -7.1755)
		(width 0.254)
		(layer "In2.Cu")
		(net "P3V3_M2")
	)
	(segment
		(start 49.657 -166.5732)
		(end 49.657 -177.0126)
		(width 0.254)
		(layer "In2.Cu")
		(net "P3V3_M2")
	)
	(segment
		(start 144.19834 -7.1755)
		(end 144.19834 -17.569942)
		(width 0.254)
		(layer "In2.Cu")
		(net "P3V3_M2")
	)
	(segment
		(start 103.4542 -39.217854)
		(end 103.4542 -40.669972)
		(width 0.254)
		(layer "In2.Cu")
		(net "P3V3_M2")
	)
	(segment
		(start 103.327962 -36.778692)
		(end 102.563676 -37.542978)
		(width 0.254)
		(layer "In2.Cu")
		(net "P3V3_M2")
	)
	(segment
		(start 103.327962 -31.021528)
		(end 103.327962 -36.778692)
		(width 0.254)
		(layer "In2.Cu")
		(net "P3V3_M2")
	)
	(segment
		(start 112.0394 -28.1813)
		(end 111.987584 -28.233116)
		(width 0.254)
		(layer "In2.Cu")
		(net "P3V3_M2")
	)
	(segment
		(start 111.987584 -28.233116)
		(end 106.116374 -28.233116)
		(width 0.254)
		(layer "In2.Cu")
		(net "P3V3_M2")
	)
	(segment
		(start 102.563676 -38.32733)
		(end 103.4542 -39.217854)
		(width 0.254)
		(layer "In2.Cu")
		(net "P3V3_M2")
	)
	(segment
		(start 163.59886 -100.522786)
		(end 170.116246 -107.040172)
		(width 0.254)
		(layer "In2.Cu")
		(net "P3V3_M2")
	)
	(segment
		(start 102.563676 -37.542978)
		(end 102.563676 -38.32733)
		(width 0.254)
		(layer "In2.Cu")
		(net "P3V3_M2")
	)
	(segment
		(start 98.4885 -45.635672)
		(end 98.4885 -80.4545)
		(width 0.254)
		(layer "In2.Cu")
		(net "P3V3_M2")
	)
	(segment
		(start 50.6984 -165.5318)
		(end 49.657 -166.5732)
		(width 0.254)
		(layer "In2.Cu")
		(net "P3V3_M2")
	)
	(segment
		(start 144.19834 -17.569942)
		(end 163.59886 -36.970462)
		(width 0.254)
		(layer "In2.Cu")
		(net "P3V3_M2")
	)
	(segment
		(start 106.116374 -28.233116)
		(end 103.327962 -31.021528)
		(width 0.254)
		(layer "In2.Cu")
		(net "P3V3_M2")
	)
	(segment
		(start 98.4885 -80.4545)
		(end 98.1075 -80.8355)
		(width 0.254)
		(layer "In2.Cu")
		(net "P3V3_M2")
	)
	(segment
		(start 103.4542 -40.669972)
		(end 98.4885 -45.635672)
		(width 0.254)
		(layer "In2.Cu")
		(net "P3V3_M2")
	)
	(segment
		(start 170.116246 -107.040172)
		(end 170.116246 -116.337588)
		(width 0.254)
		(layer "In2.Cu")
		(net "P3V3_M2")
	)
	(segment
		(start 50.6984 -164.1602)
		(end 50.6984 -165.5318)
		(width 0.254)
		(layer "In2.Cu")
		(net "P3V3_M2")
	)
	(segment
		(start 81.596738 -177.750216)
		(end 76.940156 -177.750216)
		(width 0.254)
		(layer "In5.Cu")
		(net "P3V3_M2")
	)
	(segment
		(start 67.555872 -176.093374)
		(end 66.687446 -176.9618)
		(width 0.254)
		(layer "In5.Cu")
		(net "P3V3_M2")
	)
	(segment
		(start 109.506004 -8.071612)
		(end 109.506004 -5.365242)
		(width 0.254)
		(layer "In5.Cu")
		(net "P3V3_M2")
	)
	(segment
		(start 112.776 -21.6154)
		(end 111.419132 -20.258532)
		(width 0.254)
		(layer "In5.Cu")
		(net "P3V3_M2")
	)
	(segment
		(start 66.687446 -176.9618)
		(end 64.42837 -176.9618)
		(width 0.254)
		(layer "In5.Cu")
		(net "P3V3_M2")
	)
	(segment
		(start 83.103466 -179.256944)
		(end 81.596738 -177.750216)
		(width 0.254)
		(layer "In5.Cu")
		(net "P3V3_M2")
	)
	(segment
		(start 71.5772 -177.2158)
		(end 70.454774 -176.093374)
		(width 0.254)
		(layer "In5.Cu")
		(net "P3V3_M2")
	)
	(segment
		(start 116.5606 -24.257)
		(end 113.919 -21.6154)
		(width 0.254)
		(layer "In5.Cu")
		(net "P3V3_M2")
	)
	(segment
		(start 100.661724 -177.477928)
		(end 99.748086 -177.477928)
		(width 0.254)
		(layer "In5.Cu")
		(net "P3V3_M2")
	)
	(segment
		(start 97.96907 -179.256944)
		(end 83.103466 -179.256944)
		(width 0.254)
		(layer "In5.Cu")
		(net "P3V3_M2")
	)
	(segment
		(start 116.713 -24.257)
		(end 116.5606 -24.257)
		(width 0.254)
		(layer "In5.Cu")
		(net "P3V3_M2")
	)
	(segment
		(start 76.940156 -177.750216)
		(end 76.40574 -177.2158)
		(width 0.254)
		(layer "In5.Cu")
		(net "P3V3_M2")
	)
	(segment
		(start 64.42837 -176.9618)
		(end 63.10757 -178.2826)
		(width 0.254)
		(layer "In5.Cu")
		(net "P3V3_M2")
	)
	(segment
		(start 109.506004 -5.365242)
		(end 109.796326 -5.07492)
		(width 0.254)
		(layer "In5.Cu")
		(net "P3V3_M2")
	)
	(segment
		(start 75.154028 -177.242216)
		(end 74.606404 -177.242216)
		(width 0.254)
		(layer "In5.Cu")
		(net "P3V3_M2")
	)
	(segment
		(start 50.927 -178.2826)
		(end 49.657 -177.0126)
		(width 0.254)
		(layer "In5.Cu")
		(net "P3V3_M2")
	)
	(segment
		(start 74.579988 -177.2158)
		(end 71.5772 -177.2158)
		(width 0.254)
		(layer "In5.Cu")
		(net "P3V3_M2")
	)
	(segment
		(start 99.748086 -177.477928)
		(end 97.96907 -179.256944)
		(width 0.254)
		(layer "In5.Cu")
		(net "P3V3_M2")
	)
	(segment
		(start 63.10757 -178.2826)
		(end 50.927 -178.2826)
		(width 0.254)
		(layer "In5.Cu")
		(net "P3V3_M2")
	)
	(segment
		(start 111.419132 -20.258532)
		(end 111.419132 -9.98474)
		(width 0.254)
		(layer "In5.Cu")
		(net "P3V3_M2")
	)
	(segment
		(start 74.606404 -177.242216)
		(end 74.579988 -177.2158)
		(width 0.254)
		(layer "In5.Cu")
		(net "P3V3_M2")
	)
	(segment
		(start 113.919 -21.6154)
		(end 112.776 -21.6154)
		(width 0.254)
		(layer "In5.Cu")
		(net "P3V3_M2")
	)
	(segment
		(start 75.180444 -177.2158)
		(end 75.154028 -177.242216)
		(width 0.254)
		(layer "In5.Cu")
		(net "P3V3_M2")
	)
	(segment
		(start 76.40574 -177.2158)
		(end 75.180444 -177.2158)
		(width 0.254)
		(layer "In5.Cu")
		(net "P3V3_M2")
	)
	(segment
		(start 70.454774 -176.093374)
		(end 67.555872 -176.093374)
		(width 0.254)
		(layer "In5.Cu")
		(net "P3V3_M2")
	)
	(segment
		(start 111.419132 -9.98474)
		(end 109.506004 -8.071612)
		(width 0.254)
		(layer "In5.Cu")
		(net "P3V3_M2")
	)
	(segment
		(start 91.5162 -52.634896)
		(end 92.44965 -51.701446)
		(width 0.127)
		(layer "F.Cu")
		(net "P3V3_EN")
	)
	(segment
		(start 93.950028 -57.384442)
		(end 92.962222 -57.384442)
		(width 0.127)
		(layer "F.Cu")
		(net "P3V3_EN")
	)
	(segment
		(start 91.5162 -54.595014)
		(end 91.5162 -52.634896)
		(width 0.127)
		(layer "F.Cu")
		(net "P3V3_EN")
	)
	(segment
		(start 91.801696 -54.870096)
		(end 91.791282 -54.870096)
		(width 0.127)
		(layer "F.Cu")
		(net "P3V3_EN")
	)
	(segment
		(start 92.74175 -59.32551)
		(end 93.70949 -59.32551)
		(width 0.127)
		(layer "F.Cu")
		(net "P3V3_EN")
	)
	(segment
		(start 92.962222 -57.384442)
		(end 92.946474 -57.368694)
		(width 0.127)
		(layer "F.Cu")
		(net "P3V3_EN")
	)
	(segment
		(start 91.791282 -54.870096)
		(end 91.5162 -54.595014)
		(width 0.127)
		(layer "F.Cu")
		(net "P3V3_EN")
	)
	(segment
		(start 93.950028 -59.084972)
		(end 93.950028 -57.384442)
		(width 0.127)
		(layer "F.Cu")
		(net "P3V3_EN")
	)
	(segment
		(start 92.946474 -57.368694)
		(end 92.946474 -56.014874)
		(width 0.127)
		(layer "F.Cu")
		(net "P3V3_EN")
	)
	(segment
		(start 93.70949 -59.32551)
		(end 93.950028 -59.084972)
		(width 0.127)
		(layer "F.Cu")
		(net "P3V3_EN")
	)
	(segment
		(start 92.946474 -56.014874)
		(end 91.801696 -54.870096)
		(width 0.127)
		(layer "F.Cu")
		(net "P3V3_EN")
	)
	(via
		(at 93.950028 -57.384442)
		(size 0.6604)
		(drill 0.3302)
		(layers "F.Cu" "B.Cu")
		(net "P3V3_EN")
	)
	(segment
		(start 51.8414 -164.211)
		(end 51.8414 -162.9283)
		(width 0.508)
		(layer "F.Cu")
		(net "P3V3")
	)
	(segment
		(start 90.654632 -46.8376)
		(end 90.851228 -47.034196)
		(width 0.508)
		(layer "F.Cu")
		(net "P3V3")
	)
	(segment
		(start 88.2904 -47.4726)
		(end 88.9254 -46.8376)
		(width 0.508)
		(layer "F.Cu")
		(net "P3V3")
	)
	(segment
		(start 88.9254 -46.8376)
		(end 90.654632 -46.8376)
		(width 0.508)
		(layer "F.Cu")
		(net "P3V3")
	)
	(via
		(at 7.281418 -161.060638)
		(size 0.508)
		(drill 0.254)
		(layers "F.Cu" "B.Cu")
		(net "P3V3")
	)
	(via
		(at 85.060028 -50.921412)
		(size 0.7112)
		(drill 0.4064)
		(layers "F.Cu" "B.Cu")
		(net "P3V3")
	)
	(via
		(at 84.155534 -50.43678)
		(size 0.6096)
		(drill 0.3048)
		(layers "F.Cu" "B.Cu")
		(net "P3V3")
	)
	(via
		(at 100.7872 -18.9992)
		(size 0.508)
		(drill 0.254)
		(layers "F.Cu" "B.Cu")
		(net "P3V3")
	)
	(via
		(at 7.143242 -115.229132)
		(size 0.508)
		(drill 0.254)
		(layers "F.Cu" "B.Cu")
		(net "P3V3")
	)
	(via
		(at 212.170264 -86.592156)
		(size 0.508)
		(drill 0.254)
		(layers "F.Cu" "B.Cu")
		(net "P3V3")
	)
	(via
		(at 87.196168 -47.69231)
		(size 0.6604)
		(drill 0.3302)
		(layers "F.Cu" "B.Cu")
		(net "P3V3")
	)
	(via
		(at 85.060028 -48.381412)
		(size 0.7112)
		(drill 0.4064)
		(layers "F.Cu" "B.Cu")
		(net "P3V3")
	)
	(via
		(at 85.060028 -49.651412)
		(size 0.7112)
		(drill 0.4064)
		(layers "F.Cu" "B.Cu")
		(net "P3V3")
	)
	(via
		(at 77.668628 -55.187596)
		(size 0.508)
		(drill 0.254)
		(layers "F.Cu" "B.Cu")
		(net "P3V3")
	)
	(via
		(at 71.2724 -114.0206)
		(size 0.508)
		(drill 0.254)
		(layers "F.Cu" "B.Cu")
		(net "P3V3")
	)
	(via
		(at 51.8414 -164.211)
		(size 0.508)
		(drill 0.254)
		(layers "F.Cu" "B.Cu")
		(net "P3V3")
	)
	(via
		(at 172.72 -6.0706)
		(size 0.508)
		(drill 0.254)
		(layers "F.Cu" "B.Cu")
		(net "P3V3")
	)
	(via
		(at 83.426554 -52.760626)
		(size 0.6096)
		(drill 0.3048)
		(layers "F.Cu" "B.Cu")
		(net "P3V3")
	)
	(via
		(at 77.643228 -56.914796)
		(size 0.508)
		(drill 0.254)
		(layers "F.Cu" "B.Cu")
		(net "P3V3")
	)
	(via
		(at 80.229964 -54.497224)
		(size 0.6096)
		(drill 0.3048)
		(layers "F.Cu" "B.Cu")
		(net "P3V3")
	)
	(via
		(at 84.8868 -52.1716)
		(size 0.6096)
		(drill 0.3048)
		(layers "F.Cu" "B.Cu")
		(net "P3V3")
	)
	(via
		(at 50.8 -168.7068)
		(size 0.508)
		(drill 0.254)
		(layers "F.Cu" "B.Cu")
		(net "P3V3")
	)
	(via
		(at 77.668628 -56.051196)
		(size 0.508)
		(drill 0.254)
		(layers "F.Cu" "B.Cu")
		(net "P3V3")
	)
	(segment
		(start 110.235746 -3.3782)
		(end 169.479722 -3.3782)
		(width 0.508)
		(layer "B.Cu")
		(net "P3V3")
	)
	(segment
		(start 211.198206 -86.56828)
		(end 211.222082 -86.592156)
		(width 0.508)
		(layer "B.Cu")
		(net "P3V3")
	)
	(segment
		(start 100.7872 -18.9992)
		(end 102.362 -17.4244)
		(width 0.508)
		(layer "B.Cu")
		(net "P3V3")
	)
	(segment
		(start 103.69296 -17.4244)
		(end 108.2294 -12.88796)
		(width 0.508)
		(layer "B.Cu")
		(net "P3V3")
	)
	(segment
		(start 108.2294 -5.384546)
		(end 110.235746 -3.3782)
		(width 0.508)
		(layer "B.Cu")
		(net "P3V3")
	)
	(segment
		(start 108.2294 -12.88796)
		(end 108.2294 -5.384546)
		(width 0.508)
		(layer "B.Cu")
		(net "P3V3")
	)
	(segment
		(start 212.170264 -86.592156)
		(end 212.805264 -87.227156)
		(width 0.508)
		(layer "B.Cu")
		(net "P3V3")
	)
	(segment
		(start 211.222082 -86.592156)
		(end 212.170264 -86.592156)
		(width 0.508)
		(layer "B.Cu")
		(net "P3V3")
	)
	(segment
		(start 102.362 -17.4244)
		(end 103.69296 -17.4244)
		(width 0.508)
		(layer "B.Cu")
		(net "P3V3")
	)
	(segment
		(start 169.479722 -3.3782)
		(end 172.172122 -6.0706)
		(width 0.508)
		(layer "B.Cu")
		(net "P3V3")
	)
	(segment
		(start 172.172122 -6.0706)
		(end 172.72 -6.0706)
		(width 0.508)
		(layer "B.Cu")
		(net "P3V3")
	)
	(segment
		(start 212.805264 -87.227156)
		(end 212.805264 -87.468456)
		(width 0.508)
		(layer "B.Cu")
		(net "P3V3")
	)
	(segment
		(start 80.0608 -67.077082)
		(end 82.418428 -69.43471)
		(width 0.508)
		(layer "In2.Cu")
		(net "P3V3")
	)
	(segment
		(start 80.233012 -98.125788)
		(end 80.233012 -99.745292)
		(width 0.508)
		(layer "In2.Cu")
		(net "P3V3")
	)
	(segment
		(start 80.0608 -59.332368)
		(end 80.0608 -67.077082)
		(width 0.508)
		(layer "In2.Cu")
		(net "P3V3")
	)
	(segment
		(start 78.279498 -108.7247)
		(end 77.961998 -109.0422)
		(width 0.508)
		(layer "In2.Cu")
		(net "P3V3")
	)
	(segment
		(start 83.8454 -106.740452)
		(end 81.861152 -108.7247)
		(width 0.508)
		(layer "In2.Cu")
		(net "P3V3")
	)
	(segment
		(start 80.233012 -99.745292)
		(end 83.8454 -103.35768)
		(width 0.508)
		(layer "In2.Cu")
		(net "P3V3")
	)
	(segment
		(start 5.25145 -117.120924)
		(end 7.143242 -115.229132)
		(width 0.508)
		(layer "In2.Cu")
		(net "P3V3")
	)
	(segment
		(start 77.961744 -109.0422)
		(end 72.983344 -114.0206)
		(width 0.508)
		(layer "In2.Cu")
		(net "P3V3")
	)
	(segment
		(start 82.21472 -90.535252)
		(end 82.21472 -96.14408)
		(width 0.508)
		(layer "In2.Cu")
		(net "P3V3")
	)
	(segment
		(start 7.281418 -161.060638)
		(end 5.25145 -159.03067)
		(width 0.508)
		(layer "In2.Cu")
		(net "P3V3")
	)
	(segment
		(start 81.861152 -108.7247)
		(end 78.279498 -108.7247)
		(width 0.508)
		(layer "In2.Cu")
		(net "P3V3")
	)
	(segment
		(start 72.983344 -114.0206)
		(end 71.2724 -114.0206)
		(width 0.508)
		(layer "In2.Cu")
		(net "P3V3")
	)
	(segment
		(start 5.25145 -159.03067)
		(end 5.25145 -117.120924)
		(width 0.508)
		(layer "In2.Cu")
		(net "P3V3")
	)
	(segment
		(start 82.21472 -96.14408)
		(end 80.233012 -98.125788)
		(width 0.508)
		(layer "In2.Cu")
		(net "P3V3")
	)
	(segment
		(start 51.5874 -167.9194)
		(end 51.5874 -164.465)
		(width 0.508)
		(layer "In2.Cu")
		(net "P3V3")
	)
	(segment
		(start 83.8454 -103.35768)
		(end 83.8454 -106.740452)
		(width 0.508)
		(layer "In2.Cu")
		(net "P3V3")
	)
	(segment
		(start 77.961998 -109.0422)
		(end 77.961744 -109.0422)
		(width 0.508)
		(layer "In2.Cu")
		(net "P3V3")
	)
	(segment
		(start 50.8 -168.7068)
		(end 51.5874 -167.9194)
		(width 0.508)
		(layer "In2.Cu")
		(net "P3V3")
	)
	(segment
		(start 82.418428 -69.43471)
		(end 82.418428 -90.331544)
		(width 0.508)
		(layer "In2.Cu")
		(net "P3V3")
	)
	(segment
		(start 51.5874 -164.465)
		(end 51.8414 -164.211)
		(width 0.508)
		(layer "In2.Cu")
		(net "P3V3")
	)
	(segment
		(start 82.418428 -90.331544)
		(end 82.21472 -90.535252)
		(width 0.508)
		(layer "In2.Cu")
		(net "P3V3")
	)
	(segment
		(start 77.643228 -56.914796)
		(end 80.0608 -59.332368)
		(width 0.508)
		(layer "In2.Cu")
		(net "P3V3")
	)
	(segment
		(start 88.830658 -31.412942)
		(end 88.830658 -40.619172)
		(width 0.508)
		(layer "In5.Cu")
		(net "P3V3")
	)
	(segment
		(start 25.809448 -163.629848)
		(end 23.7998 -161.6202)
		(width 0.508)
		(layer "In5.Cu")
		(net "P3V3")
	)
	(segment
		(start 60.63361 -113.79581)
		(end 58.864246 -112.026446)
		(width 0.508)
		(layer "In5.Cu")
		(net "P3V3")
	)
	(segment
		(start 70.174612 -114.0206)
		(end 69.717412 -113.5634)
		(width 0.508)
		(layer "In5.Cu")
		(net "P3V3")
	)
	(segment
		(start 88.830658 -40.619172)
		(end 85.852 -43.59783)
		(width 0.508)
		(layer "In5.Cu")
		(net "P3V3")
	)
	(segment
		(start 50.8 -168.7068)
		(end 45.493686 -174.013114)
		(width 0.508)
		(layer "In5.Cu")
		(net "P3V3")
	)
	(segment
		(start 58.864246 -112.026446)
		(end 53.225954 -112.026446)
		(width 0.508)
		(layer "In5.Cu")
		(net "P3V3")
	)
	(segment
		(start 37.1856 -167.061642)
		(end 33.753806 -163.629848)
		(width 0.508)
		(layer "In5.Cu")
		(net "P3V3")
	)
	(segment
		(start 71.2724 -114.0206)
		(end 70.174612 -114.0206)
		(width 0.508)
		(layer "In5.Cu")
		(net "P3V3")
	)
	(segment
		(start 206.901542 -10.287508)
		(end 211.006182 -14.392148)
		(width 0.508)
		(layer "In5.Cu")
		(net "P3V3")
	)
	(segment
		(start 27.5463 -112.0775)
		(end 26.848816 -111.380016)
		(width 0.508)
		(layer "In5.Cu")
		(net "P3V3")
	)
	(segment
		(start 91.821 -28.4226)
		(end 88.830658 -31.412942)
		(width 0.508)
		(layer "In5.Cu")
		(net "P3V3")
	)
	(segment
		(start 40.3606 -112.8522)
		(end 39.5859 -112.0775)
		(width 0.508)
		(layer "In5.Cu")
		(net "P3V3")
	)
	(segment
		(start 23.7998 -161.6202)
		(end 7.84098 -161.6202)
		(width 0.508)
		(layer "In5.Cu")
		(net "P3V3")
	)
	(segment
		(start 68.4022 -113.5634)
		(end 67.945 -114.0206)
		(width 0.508)
		(layer "In5.Cu")
		(net "P3V3")
	)
	(segment
		(start 37.1856 -171.464986)
		(end 37.1856 -167.061642)
		(width 0.508)
		(layer "In5.Cu")
		(net "P3V3")
	)
	(segment
		(start 175.52797 -6.0706)
		(end 179.744878 -10.287508)
		(width 0.508)
		(layer "In5.Cu")
		(net "P3V3")
	)
	(segment
		(start 69.717412 -113.5634)
		(end 68.4022 -113.5634)
		(width 0.508)
		(layer "In5.Cu")
		(net "P3V3")
	)
	(segment
		(start 211.006182 -14.392148)
		(end 211.006182 -85.428074)
		(width 0.508)
		(layer "In5.Cu")
		(net "P3V3")
	)
	(segment
		(start 93.1672 -28.4226)
		(end 91.821 -28.4226)
		(width 0.508)
		(layer "In5.Cu")
		(net "P3V3")
	)
	(segment
		(start 85.852 -47.58944)
		(end 85.060028 -48.381412)
		(width 0.508)
		(layer "In5.Cu")
		(net "P3V3")
	)
	(segment
		(start 39.733728 -174.013114)
		(end 37.1856 -171.464986)
		(width 0.508)
		(layer "In5.Cu")
		(net "P3V3")
	)
	(segment
		(start 33.753806 -163.629848)
		(end 25.809448 -163.629848)
		(width 0.508)
		(layer "In5.Cu")
		(net "P3V3")
	)
	(segment
		(start 85.852 -43.59783)
		(end 85.852 -47.58944)
		(width 0.508)
		(layer "In5.Cu")
		(net "P3V3")
	)
	(segment
		(start 39.5859 -112.0775)
		(end 27.5463 -112.0775)
		(width 0.508)
		(layer "In5.Cu")
		(net "P3V3")
	)
	(segment
		(start 52.4002 -112.8522)
		(end 40.3606 -112.8522)
		(width 0.508)
		(layer "In5.Cu")
		(net "P3V3")
	)
	(segment
		(start 100.7872 -18.9992)
		(end 100.7872 -20.8026)
		(width 0.508)
		(layer "In5.Cu")
		(net "P3V3")
	)
	(segment
		(start 26.848816 -111.380016)
		(end 10.992358 -111.380016)
		(width 0.508)
		(layer "In5.Cu")
		(net "P3V3")
	)
	(segment
		(start 7.84098 -161.6202)
		(end 7.281418 -161.060638)
		(width 0.508)
		(layer "In5.Cu")
		(net "P3V3")
	)
	(segment
		(start 179.744878 -10.287508)
		(end 206.901542 -10.287508)
		(width 0.508)
		(layer "In5.Cu")
		(net "P3V3")
	)
	(segment
		(start 53.225954 -112.026446)
		(end 52.4002 -112.8522)
		(width 0.508)
		(layer "In5.Cu")
		(net "P3V3")
	)
	(segment
		(start 100.7872 -20.8026)
		(end 93.1672 -28.4226)
		(width 0.508)
		(layer "In5.Cu")
		(net "P3V3")
	)
	(segment
		(start 172.72 -6.0706)
		(end 175.52797 -6.0706)
		(width 0.508)
		(layer "In5.Cu")
		(net "P3V3")
	)
	(segment
		(start 45.493686 -174.013114)
		(end 39.733728 -174.013114)
		(width 0.508)
		(layer "In5.Cu")
		(net "P3V3")
	)
	(segment
		(start 60.640976 -113.79581)
		(end 60.63361 -113.79581)
		(width 0.508)
		(layer "In5.Cu")
		(net "P3V3")
	)
	(segment
		(start 10.992358 -111.380016)
		(end 7.143242 -115.229132)
		(width 0.508)
		(layer "In5.Cu")
		(net "P3V3")
	)
	(segment
		(start 60.865766 -114.0206)
		(end 60.640976 -113.79581)
		(width 0.508)
		(layer "In5.Cu")
		(net "P3V3")
	)
	(segment
		(start 67.945 -114.0206)
		(end 60.865766 -114.0206)
		(width 0.508)
		(layer "In5.Cu")
		(net "P3V3")
	)
	(segment
		(start 211.006182 -85.428074)
		(end 212.170264 -86.592156)
		(width 0.508)
		(layer "In5.Cu")
		(net "P3V3")
	)
	(segment
		(start 53.371242 -167.397684)
		(end 53.371242 -168.1734)
		(width 0.508)
		(layer "F.Cu")
		(net "P2V5_STBY")
	)
	(segment
		(start 24.478234 -136.117838)
		(end 24.478234 -135.667496)
		(width 0.3048)
		(layer "F.Cu")
		(net "P2V5_STBY")
	)
	(segment
		(start 15.699232 -147.761452)
		(end 16.834612 -147.761452)
		(width 0.3556)
		(layer "F.Cu")
		(net "P2V5_STBY")
	)
	(segment
		(start 14.967204 -147.931378)
		(end 14.97457 -147.924012)
		(width 0.3556)
		(layer "F.Cu")
		(net "P2V5_STBY")
	)
	(segment
		(start 14.97457 -147.924012)
		(end 15.536672 -147.924012)
		(width 0.3556)
		(layer "F.Cu")
		(net "P2V5_STBY")
	)
	(segment
		(start 15.536672 -147.924012)
		(end 15.699232 -147.761452)
		(width 0.3556)
		(layer "F.Cu")
		(net "P2V5_STBY")
	)
	(segment
		(start 23.234396 -137.361676)
		(end 24.478234 -136.117838)
		(width 0.3048)
		(layer "F.Cu")
		(net "P2V5_STBY")
	)
	(via
		(at 75.8698 -171.3484)
		(size 0.7112)
		(drill 0.4064)
		(layers "F.Cu" "B.Cu")
		(net "P2V5_STBY")
	)
	(via
		(at 67.966336 -166.758874)
		(size 0.6096)
		(drill 0.3048)
		(layers "F.Cu" "B.Cu")
		(net "P2V5_STBY")
	)
	(via
		(at 28.550362 -166.783258)
		(size 0.6604)
		(drill 0.3302)
		(layers "F.Cu" "B.Cu")
		(net "P2V5_STBY")
	)
	(via
		(at 77.1398 -171.3484)
		(size 0.7112)
		(drill 0.4064)
		(layers "F.Cu" "B.Cu")
		(net "P2V5_STBY")
	)
	(via
		(at 24.478234 -135.667496)
		(size 0.508)
		(drill 0.254)
		(layers "F.Cu" "B.Cu")
		(net "P2V5_STBY")
	)
	(via
		(at 28.6639 -162.937952)
		(size 0.6604)
		(drill 0.3302)
		(layers "F.Cu" "B.Cu")
		(net "P2V5_STBY")
	)
	(via
		(at 31.07309 -166.568628)
		(size 0.7112)
		(drill 0.4064)
		(layers "F.Cu" "B.Cu")
		(net "P2V5_STBY")
	)
	(via
		(at 31.07309 -167.787828)
		(size 0.7112)
		(drill 0.4064)
		(layers "F.Cu" "B.Cu")
		(net "P2V5_STBY")
	)
	(via
		(at 55.60695 -169.21988)
		(size 0.6096)
		(drill 0.3048)
		(layers "F.Cu" "B.Cu")
		(net "P2V5_STBY")
	)
	(via
		(at 53.371242 -168.1734)
		(size 0.508)
		(drill 0.254)
		(layers "F.Cu" "B.Cu")
		(net "P2V5_STBY")
	)
	(via
		(at 14.967204 -147.931378)
		(size 0.508)
		(drill 0.254)
		(layers "F.Cu" "B.Cu")
		(net "P2V5_STBY")
	)
	(via
		(at 13.538708 -144.098518)
		(size 0.508)
		(drill 0.254)
		(layers "F.Cu" "B.Cu")
		(net "P2V5_STBY")
	)
	(via
		(at 14.438376 -149.517354)
		(size 0.6604)
		(drill 0.3302)
		(layers "F.Cu" "B.Cu")
		(net "P2V5_STBY")
	)
	(via
		(at 33.782 -166.7256)
		(size 0.6096)
		(drill 0.3048)
		(layers "F.Cu" "B.Cu")
		(net "P2V5_STBY")
	)
	(via
		(at 22.419564 -157.77591)
		(size 0.6604)
		(drill 0.3302)
		(layers "F.Cu" "B.Cu")
		(net "P2V5_STBY")
	)
	(via
		(at 73.901554 -171.104814)
		(size 0.6096)
		(drill 0.3048)
		(layers "F.Cu" "B.Cu")
		(net "P2V5_STBY")
	)
	(segment
		(start 13.538454 -144.098264)
		(end 12.107672 -144.098264)
		(width 0.762)
		(layer "B.Cu")
		(net "P2V5_STBY")
	)
	(segment
		(start 13.538708 -144.098518)
		(end 13.538454 -144.098264)
		(width 0.762)
		(layer "B.Cu")
		(net "P2V5_STBY")
	)
	(segment
		(start 24.910034 -136.099296)
		(end 24.478234 -135.667496)
		(width 0.508)
		(layer "B.Cu")
		(net "P2V5_STBY")
	)
	(segment
		(start 25.317196 -136.099296)
		(end 24.910034 -136.099296)
		(width 0.508)
		(layer "B.Cu")
		(net "P2V5_STBY")
	)
	(segment
		(start 26.073608 -133.491478)
		(end 24.478234 -135.086852)
		(width 1.016)
		(layer "In2.Cu")
		(net "P2V5_STBY")
	)
	(segment
		(start 26.073608 -132.186426)
		(end 26.073608 -133.491478)
		(width 1.016)
		(layer "In2.Cu")
		(net "P2V5_STBY")
	)
	(segment
		(start 14.652498 -142.984728)
		(end 14.652498 -132.859018)
		(width 1.016)
		(layer "In2.Cu")
		(net "P2V5_STBY")
	)
	(segment
		(start 25.3365 -131.449318)
		(end 26.073608 -132.186426)
		(width 1.016)
		(layer "In2.Cu")
		(net "P2V5_STBY")
	)
	(segment
		(start 13.538708 -146.502882)
		(end 13.538708 -144.098518)
		(width 1.016)
		(layer "In2.Cu")
		(net "P2V5_STBY")
	)
	(segment
		(start 14.652498 -132.859018)
		(end 16.062198 -131.449318)
		(width 1.016)
		(layer "In2.Cu")
		(net "P2V5_STBY")
	)
	(segment
		(start 16.062198 -131.449318)
		(end 25.3365 -131.449318)
		(width 1.016)
		(layer "In2.Cu")
		(net "P2V5_STBY")
	)
	(segment
		(start 14.967204 -147.931378)
		(end 13.538708 -146.502882)
		(width 1.016)
		(layer "In2.Cu")
		(net "P2V5_STBY")
	)
	(segment
		(start 24.478234 -135.086852)
		(end 24.478234 -135.667496)
		(width 1.016)
		(layer "In2.Cu")
		(net "P2V5_STBY")
	)
	(segment
		(start 13.538708 -144.098518)
		(end 14.652498 -142.984728)
		(width 1.016)
		(layer "In2.Cu")
		(net "P2V5_STBY")
	)
	(segment
		(start 22.011386 -131.451858)
		(end 22.011386 -132.51053)
		(width 0.508)
		(layer "F.Cu")
		(net "P1V2_STBY")
	)
	(segment
		(start 16.834612 -148.561552)
		(end 16.434562 -148.961602)
		(width 0.3048)
		(layer "F.Cu")
		(net "P1V2_STBY")
	)
	(segment
		(start 16.834104 -142.161514)
		(end 16.434054 -142.561564)
		(width 0.3048)
		(layer "F.Cu")
		(net "P1V2_STBY")
	)
	(segment
		(start 23.234396 -148.561552)
		(end 23.240492 -148.561552)
		(width 0.3048)
		(layer "F.Cu")
		(net "P1V2_STBY")
	)
	(segment
		(start 23.234396 -142.161514)
		(end 23.234142 -142.161514)
		(width 0.3048)
		(layer "F.Cu")
		(net "P1V2_STBY")
	)
	(segment
		(start 20.582128 -131.451858)
		(end 20.582128 -132.51053)
		(width 0.508)
		(layer "F.Cu")
		(net "P1V2_STBY")
	)
	(segment
		(start 13.361924 -136.715246)
		(end 11.241024 -136.715246)
		(width 0.508)
		(layer "F.Cu")
		(net "P1V2_STBY")
	)
	(segment
		(start 22.834346 -144.16151)
		(end 23.234396 -143.76146)
		(width 0.3048)
		(layer "F.Cu")
		(net "P1V2_STBY")
	)
	(segment
		(start 22.434296 -142.161514)
		(end 22.0345 -142.56131)
		(width 0.3048)
		(layer "F.Cu")
		(net "P1V2_STBY")
	)
	(segment
		(start 18.434558 -147.761452)
		(end 18.834354 -148.161248)
		(width 0.3048)
		(layer "F.Cu")
		(net "P1V2_STBY")
	)
	(segment
		(start 44.72813 -147.438364)
		(end 44.72813 -146.828002)
		(width 0.3556)
		(layer "F.Cu")
		(net "P1V2_STBY")
	)
	(segment
		(start 13.354558 -139.573)
		(end 11.1887 -139.573)
		(width 0.508)
		(layer "F.Cu")
		(net "P1V2_STBY")
	)
	(segment
		(start 24.05888 -141.386052)
		(end 24.05888 -141.518132)
		(width 0.3048)
		(layer "F.Cu")
		(net "P1V2_STBY")
	)
	(segment
		(start 44.099988 -144.599914)
		(end 44.099734 -144.599914)
		(width 0.3556)
		(layer "F.Cu")
		(net "P1V2_STBY")
	)
	(segment
		(start 16.53667 -140.561568)
		(end 16.117824 -140.980414)
		(width 0.3048)
		(layer "F.Cu")
		(net "P1V2_STBY")
	)
	(segment
		(start 43.699938 -143.400272)
		(end 44.100242 -142.999968)
		(width 0.3048)
		(layer "F.Cu")
		(net "P1V2_STBY")
	)
	(segment
		(start 17.634458 -142.161768)
		(end 17.234662 -142.561564)
		(width 0.3048)
		(layer "F.Cu")
		(net "P1V2_STBY")
	)
	(segment
		(start 44.72813 -146.828002)
		(end 44.525692 -146.625564)
		(width 0.3556)
		(layer "F.Cu")
		(net "P1V2_STBY")
	)
	(segment
		(start 23.368 -132.437886)
		(end 23.440644 -132.51053)
		(width 0.508)
		(layer "F.Cu")
		(net "P1V2_STBY")
	)
	(segment
		(start 16.434054 -137.760964)
		(end 16.833342 -137.361676)
		(width 0.3048)
		(layer "F.Cu")
		(net "P1V2_STBY")
	)
	(segment
		(start 16.834612 -146.961606)
		(end 16.834866 -146.961606)
		(width 0.3048)
		(layer "F.Cu")
		(net "P1V2_STBY")
	)
	(segment
		(start 16.834612 -146.161506)
		(end 16.834612 -146.16176)
		(width 0.3048)
		(layer "F.Cu")
		(net "P1V2_STBY")
	)
	(segment
		(start 44.525692 -146.625564)
		(end 44.099988 -146.19986)
		(width 0.3048)
		(layer "F.Cu")
		(net "P1V2_STBY")
	)
	(segment
		(start 22.43455 -144.561306)
		(end 22.834346 -144.16151)
		(width 0.3048)
		(layer "F.Cu")
		(net "P1V2_STBY")
	)
	(segment
		(start 16.834612 -142.161514)
		(end 16.834104 -142.161514)
		(width 0.3048)
		(layer "F.Cu")
		(net "P1V2_STBY")
	)
	(segment
		(start 18.834354 -148.161248)
		(end 18.834608 -148.161248)
		(width 0.3048)
		(layer "F.Cu")
		(net "P1V2_STBY")
	)
	(segment
		(start 16.834358 -143.76146)
		(end 16.434054 -144.161764)
		(width 0.3048)
		(layer "F.Cu")
		(net "P1V2_STBY")
	)
	(segment
		(start 44.099734 -144.599914)
		(end 43.699938 -144.200118)
		(width 0.3556)
		(layer "F.Cu")
		(net "P1V2_STBY")
	)
	(segment
		(start 21.63445 -143.76146)
		(end 21.2344 -144.16151)
		(width 0.3048)
		(layer "F.Cu")
		(net "P1V2_STBY")
	)
	(segment
		(start 44.366434 -147.80006)
		(end 44.72813 -147.438364)
		(width 0.3556)
		(layer "F.Cu")
		(net "P1V2_STBY")
	)
	(segment
		(start 25.682702 -132.798058)
		(end 25.15743 -132.798058)
		(width 0.508)
		(layer "F.Cu")
		(net "P1V2_STBY")
	)
	(segment
		(start 44.099734 -143.800068)
		(end 43.699938 -143.400272)
		(width 0.3556)
		(layer "F.Cu")
		(net "P1V2_STBY")
	)
	(segment
		(start 11.241024 -138.144504)
		(end 13.311632 -138.144504)
		(width 0.508)
		(layer "F.Cu")
		(net "P1V2_STBY")
	)
	(segment
		(start 19.15287 -131.451858)
		(end 19.15287 -132.51053)
		(width 0.508)
		(layer "F.Cu")
		(net "P1V2_STBY")
	)
	(segment
		(start 16.834612 -143.76146)
		(end 16.834358 -143.76146)
		(width 0.3048)
		(layer "F.Cu")
		(net "P1V2_STBY")
	)
	(segment
		(start 23.234396 -146.161506)
		(end 23.634446 -145.761456)
		(width 0.3048)
		(layer "F.Cu")
		(net "P1V2_STBY")
	)
	(segment
		(start 17.634458 -144.561814)
		(end 17.234662 -144.96161)
		(width 0.3048)
		(layer "F.Cu")
		(net "P1V2_STBY")
	)
	(segment
		(start 23.234142 -142.161514)
		(end 22.834346 -142.56131)
		(width 0.3048)
		(layer "F.Cu")
		(net "P1V2_STBY")
	)
	(segment
		(start 23.368 -131.4323)
		(end 23.368 -132.437886)
		(width 0.508)
		(layer "F.Cu")
		(net "P1V2_STBY")
	)
	(segment
		(start 13.361162 -139.579604)
		(end 13.354558 -139.573)
		(width 0.508)
		(layer "F.Cu")
		(net "P1V2_STBY")
	)
	(segment
		(start 23.234396 -147.761452)
		(end 23.634192 -147.361656)
		(width 0.3048)
		(layer "F.Cu")
		(net "P1V2_STBY")
	)
	(segment
		(start 23.634954 -148.956014)
		(end 23.634954 -149.216364)
		(width 0.3048)
		(layer "F.Cu")
		(net "P1V2_STBY")
	)
	(segment
		(start 17.634458 -142.161514)
		(end 17.634458 -142.161768)
		(width 0.3048)
		(layer "F.Cu")
		(net "P1V2_STBY")
	)
	(segment
		(start 16.833342 -137.361676)
		(end 16.834612 -137.361676)
		(width 0.3048)
		(layer "F.Cu")
		(net "P1V2_STBY")
	)
	(segment
		(start 23.240492 -148.561552)
		(end 23.634954 -148.956014)
		(width 0.3048)
		(layer "F.Cu")
		(net "P1V2_STBY")
	)
	(segment
		(start 17.723612 -131.451858)
		(end 17.723612 -132.51053)
		(width 0.508)
		(layer "F.Cu")
		(net "P1V2_STBY")
	)
	(segment
		(start 13.33119 -141.008862)
		(end 11.236198 -141.008862)
		(width 0.508)
		(layer "F.Cu")
		(net "P1V2_STBY")
	)
	(segment
		(start 25.15743 -132.798058)
		(end 24.869902 -132.51053)
		(width 0.508)
		(layer "F.Cu")
		(net "P1V2_STBY")
	)
	(segment
		(start 23.234396 -136.334246)
		(end 23.5204 -136.048242)
		(width 0.3048)
		(layer "F.Cu")
		(net "P1V2_STBY")
	)
	(segment
		(start 16.834866 -146.961606)
		(end 17.234662 -146.56181)
		(width 0.3048)
		(layer "F.Cu")
		(net "P1V2_STBY")
	)
	(segment
		(start 23.234396 -140.561568)
		(end 24.05888 -141.386052)
		(width 0.3048)
		(layer "F.Cu")
		(net "P1V2_STBY")
	)
	(segment
		(start 11.215624 -135.285988)
		(end 13.595096 -135.285988)
		(width 0.508)
		(layer "F.Cu")
		(net "P1V2_STBY")
	)
	(segment
		(start 17.634458 -144.56156)
		(end 17.634458 -144.561814)
		(width 0.3048)
		(layer "F.Cu")
		(net "P1V2_STBY")
	)
	(segment
		(start 16.834612 -140.561568)
		(end 16.53667 -140.561568)
		(width 0.3048)
		(layer "F.Cu")
		(net "P1V2_STBY")
	)
	(segment
		(start 44.099988 -143.800068)
		(end 44.099734 -143.800068)
		(width 0.3556)
		(layer "F.Cu")
		(net "P1V2_STBY")
	)
	(segment
		(start 13.363702 -136.713468)
		(end 13.361924 -136.715246)
		(width 0.508)
		(layer "F.Cu")
		(net "P1V2_STBY")
	)
	(segment
		(start 44.100242 -142.999968)
		(end 44.099988 -142.999968)
		(width 0.3048)
		(layer "F.Cu")
		(net "P1V2_STBY")
	)
	(segment
		(start 23.234396 -136.561576)
		(end 23.234396 -136.334246)
		(width 0.3048)
		(layer "F.Cu")
		(net "P1V2_STBY")
	)
	(segment
		(start 16.834612 -146.16176)
		(end 17.234662 -146.56181)
		(width 0.3048)
		(layer "F.Cu")
		(net "P1V2_STBY")
	)
	(segment
		(start 22.43455 -142.161514)
		(end 22.434296 -142.161514)
		(width 0.3048)
		(layer "F.Cu")
		(net "P1V2_STBY")
	)
	(segment
		(start 44.099988 -147.80006)
		(end 44.366434 -147.80006)
		(width 0.3556)
		(layer "F.Cu")
		(net "P1V2_STBY")
	)
	(segment
		(start 22.43455 -144.56156)
		(end 22.43455 -144.561306)
		(width 0.3048)
		(layer "F.Cu")
		(net "P1V2_STBY")
	)
	(via
		(at 19.333972 -158.81985)
		(size 0.7112)
		(drill 0.4064)
		(layers "F.Cu" "B.Cu")
		(net "P1V2_STBY")
	)
	(via
		(at 43.699938 -144.200118)
		(size 0.4572)
		(drill 0.2032)
		(layers "F.Cu" "B.Cu")
		(net "P1V2_STBY")
	)
	(via
		(at 13.595096 -132.402326)
		(size 0.508)
		(drill 0.254)
		(layers "F.Cu" "B.Cu")
		(net "P1V2_STBY")
	)
	(via
		(at 16.434562 -148.961602)
		(size 0.508)
		(drill 0.254)
		(layers "F.Cu" "B.Cu")
		(net "P1V2_STBY")
	)
	(via
		(at 13.311632 -138.144504)
		(size 0.508)
		(drill 0.254)
		(layers "F.Cu" "B.Cu")
		(net "P1V2_STBY")
	)
	(via
		(at 18.834608 -148.161248)
		(size 0.508)
		(drill 0.254)
		(layers "F.Cu" "B.Cu")
		(net "P1V2_STBY")
	)
	(via
		(at 13.595096 -135.285988)
		(size 0.508)
		(drill 0.254)
		(layers "F.Cu" "B.Cu")
		(net "P1V2_STBY")
	)
	(via
		(at 20.582128 -132.51053)
		(size 0.508)
		(drill 0.254)
		(layers "F.Cu" "B.Cu")
		(net "P1V2_STBY")
	)
	(via
		(at 13.595096 -133.85673)
		(size 0.508)
		(drill 0.254)
		(layers "F.Cu" "B.Cu")
		(net "P1V2_STBY")
	)
	(via
		(at 22.0345 -142.56131)
		(size 0.508)
		(drill 0.254)
		(layers "F.Cu" "B.Cu")
		(net "P1V2_STBY")
	)
	(via
		(at 23.634192 -147.361656)
		(size 0.508)
		(drill 0.254)
		(layers "F.Cu" "B.Cu")
		(net "P1V2_STBY")
	)
	(via
		(at 19.15287 -132.51053)
		(size 0.508)
		(drill 0.254)
		(layers "F.Cu" "B.Cu")
		(net "P1V2_STBY")
	)
	(via
		(at 23.634954 -149.216364)
		(size 0.508)
		(drill 0.254)
		(layers "F.Cu" "B.Cu")
		(net "P1V2_STBY")
	)
	(via
		(at 44.525692 -146.625564)
		(size 0.4572)
		(drill 0.2032)
		(layers "F.Cu" "B.Cu")
		(net "P1V2_STBY")
	)
	(via
		(at 24.869902 -132.51053)
		(size 0.508)
		(drill 0.254)
		(layers "F.Cu" "B.Cu")
		(net "P1V2_STBY")
	)
	(via
		(at 25.808432 -151.516842)
		(size 0.508)
		(drill 0.254)
		(layers "F.Cu" "B.Cu")
		(net "P1V2_STBY")
	)
	(via
		(at 22.834346 -144.16151)
		(size 0.508)
		(drill 0.254)
		(layers "F.Cu" "B.Cu")
		(net "P1V2_STBY")
	)
	(via
		(at 29.748734 -147.319746)
		(size 0.6096)
		(drill 0.3048)
		(layers "F.Cu" "B.Cu")
		(net "P1V2_STBY")
	)
	(via
		(at 24.05888 -141.518132)
		(size 0.508)
		(drill 0.254)
		(layers "F.Cu" "B.Cu")
		(net "P1V2_STBY")
	)
	(via
		(at 23.634446 -145.761456)
		(size 0.508)
		(drill 0.254)
		(layers "F.Cu" "B.Cu")
		(net "P1V2_STBY")
	)
	(via
		(at 13.5382 -142.463266)
		(size 0.508)
		(drill 0.254)
		(layers "F.Cu" "B.Cu")
		(net "P1V2_STBY")
	)
	(via
		(at 13.361162 -139.579604)
		(size 0.508)
		(drill 0.254)
		(layers "F.Cu" "B.Cu")
		(net "P1V2_STBY")
	)
	(via
		(at 17.234662 -142.561564)
		(size 0.508)
		(drill 0.254)
		(layers "F.Cu" "B.Cu")
		(net "P1V2_STBY")
	)
	(via
		(at 22.834346 -142.56131)
		(size 0.508)
		(drill 0.254)
		(layers "F.Cu" "B.Cu")
		(net "P1V2_STBY")
	)
	(via
		(at 32.20212 -142.944342)
		(size 0.6096)
		(drill 0.3048)
		(layers "F.Cu" "B.Cu")
		(net "P1V2_STBY")
	)
	(via
		(at 23.878794 -151.654764)
		(size 0.508)
		(drill 0.254)
		(layers "F.Cu" "B.Cu")
		(net "P1V2_STBY")
	)
	(via
		(at 20.603972 -158.81985)
		(size 0.7112)
		(drill 0.4064)
		(layers "F.Cu" "B.Cu")
		(net "P1V2_STBY")
	)
	(via
		(at 23.440644 -132.51053)
		(size 0.508)
		(drill 0.254)
		(layers "F.Cu" "B.Cu")
		(net "P1V2_STBY")
	)
	(via
		(at 17.234662 -144.96161)
		(size 0.508)
		(drill 0.254)
		(layers "F.Cu" "B.Cu")
		(net "P1V2_STBY")
	)
	(via
		(at 16.434054 -142.561564)
		(size 0.508)
		(drill 0.254)
		(layers "F.Cu" "B.Cu")
		(net "P1V2_STBY")
	)
	(via
		(at 21.2344 -144.16151)
		(size 0.508)
		(drill 0.254)
		(layers "F.Cu" "B.Cu")
		(net "P1V2_STBY")
	)
	(via
		(at 22.011386 -132.51053)
		(size 0.508)
		(drill 0.254)
		(layers "F.Cu" "B.Cu")
		(net "P1V2_STBY")
	)
	(via
		(at 17.723612 -132.51053)
		(size 0.508)
		(drill 0.254)
		(layers "F.Cu" "B.Cu")
		(net "P1V2_STBY")
	)
	(via
		(at 13.363702 -136.713468)
		(size 0.508)
		(drill 0.254)
		(layers "F.Cu" "B.Cu")
		(net "P1V2_STBY")
	)
	(via
		(at 43.699938 -143.400272)
		(size 0.4572)
		(drill 0.2032)
		(layers "F.Cu" "B.Cu")
		(net "P1V2_STBY")
	)
	(via
		(at 16.434054 -144.161764)
		(size 0.508)
		(drill 0.254)
		(layers "F.Cu" "B.Cu")
		(net "P1V2_STBY")
	)
	(via
		(at 16.117824 -140.980414)
		(size 0.508)
		(drill 0.254)
		(layers "F.Cu" "B.Cu")
		(net "P1V2_STBY")
	)
	(via
		(at 13.33119 -141.008862)
		(size 0.508)
		(drill 0.254)
		(layers "F.Cu" "B.Cu")
		(net "P1V2_STBY")
	)
	(via
		(at 16.434054 -137.760964)
		(size 0.508)
		(drill 0.254)
		(layers "F.Cu" "B.Cu")
		(net "P1V2_STBY")
	)
	(via
		(at 16.294354 -132.51053)
		(size 0.508)
		(drill 0.254)
		(layers "F.Cu" "B.Cu")
		(net "P1V2_STBY")
	)
	(via
		(at 23.5204 -136.048242)
		(size 0.508)
		(drill 0.254)
		(layers "F.Cu" "B.Cu")
		(net "P1V2_STBY")
	)
	(via
		(at 17.234662 -146.56181)
		(size 0.508)
		(drill 0.254)
		(layers "F.Cu" "B.Cu")
		(net "P1V2_STBY")
	)
	(segment
		(start 33.12414 -156.9085)
		(end 33.9344 -156.9085)
		(width 0.508)
		(layer "B.Cu")
		(net "P1V2_STBY")
	)
	(segment
		(start 32.4866 -157.0482)
		(end 32.98444 -157.0482)
		(width 0.508)
		(layer "B.Cu")
		(net "P1V2_STBY")
	)
	(segment
		(start 32.98444 -157.0482)
		(end 33.12414 -156.9085)
		(width 0.508)
		(layer "B.Cu")
		(net "P1V2_STBY")
	)
	(segment
		(start 20.603972 -158.81985)
		(end 21.93925 -158.81985)
		(width 0.508)
		(layer "B.Cu")
		(net "P1V2_STBY")
	)
	(segment
		(start 23.440644 -131.451858)
		(end 23.440644 -132.51053)
		(width 0.508)
		(layer "B.Cu")
		(net "P1V2_STBY")
	)
	(segment
		(start 24.869902 -131.451858)
		(end 24.869902 -132.51053)
		(width 0.508)
		(layer "B.Cu")
		(net "P1V2_STBY")
	)
	(segment
		(start 31.1404 -158.3944)
		(end 32.4866 -157.0482)
		(width 0.508)
		(layer "B.Cu")
		(net "P1V2_STBY")
	)
	(segment
		(start 43.835574 -144.335754)
		(end 43.699938 -144.200118)
		(width 0.508)
		(layer "B.Cu")
		(net "P1V2_STBY")
	)
	(segment
		(start 12.536424 -135.285988)
		(end 13.595096 -135.285988)
		(width 0.508)
		(layer "B.Cu")
		(net "P1V2_STBY")
	)
	(segment
		(start 12.536424 -138.144504)
		(end 13.311632 -138.144504)
		(width 0.508)
		(layer "B.Cu")
		(net "P1V2_STBY")
	)
	(segment
		(start 12.536424 -136.715246)
		(end 13.361924 -136.715246)
		(width 0.508)
		(layer "B.Cu")
		(net "P1V2_STBY")
	)
	(segment
		(start 12.55649 -139.579604)
		(end 13.361162 -139.579604)
		(width 0.508)
		(layer "B.Cu")
		(net "P1V2_STBY")
	)
	(segment
		(start 24.05888 -141.518132)
		(end 24.546052 -141.03096)
		(width 0.508)
		(layer "B.Cu")
		(net "P1V2_STBY")
	)
	(segment
		(start 12.55649 -142.463266)
		(end 13.5382 -142.463266)
		(width 0.508)
		(layer "B.Cu")
		(net "P1V2_STBY")
	)
	(segment
		(start 27.3177 -159.9565)
		(end 28.7274 -158.5468)
		(width 0.508)
		(layer "B.Cu")
		(net "P1V2_STBY")
	)
	(segment
		(start 17.723612 -131.451858)
		(end 17.723612 -132.51053)
		(width 0.508)
		(layer "B.Cu")
		(net "P1V2_STBY")
	)
	(segment
		(start 19.15287 -131.451858)
		(end 19.15287 -132.51053)
		(width 0.508)
		(layer "B.Cu")
		(net "P1V2_STBY")
	)
	(segment
		(start 22.011386 -131.451858)
		(end 22.011386 -132.51053)
		(width 0.508)
		(layer "B.Cu")
		(net "P1V2_STBY")
	)
	(segment
		(start 12.536424 -133.85673)
		(end 13.595096 -133.85673)
		(width 0.508)
		(layer "B.Cu")
		(net "P1V2_STBY")
	)
	(segment
		(start 24.546052 -141.03096)
		(end 24.890476 -141.03096)
		(width 0.508)
		(layer "B.Cu")
		(net "P1V2_STBY")
	)
	(segment
		(start 28.7274 -158.5468)
		(end 29.25064 -158.5468)
		(width 0.508)
		(layer "B.Cu")
		(net "P1V2_STBY")
	)
	(segment
		(start 12.55649 -141.008862)
		(end 13.33119 -141.008862)
		(width 0.508)
		(layer "B.Cu")
		(net "P1V2_STBY")
	)
	(segment
		(start 44.666408 -146.484848)
		(end 44.525692 -146.625564)
		(width 0.4572)
		(layer "B.Cu")
		(net "P1V2_STBY")
	)
	(segment
		(start 20.582128 -131.451858)
		(end 20.582128 -132.51053)
		(width 0.508)
		(layer "B.Cu")
		(net "P1V2_STBY")
	)
	(segment
		(start 44.666408 -145.810732)
		(end 44.666408 -146.484848)
		(width 0.4572)
		(layer "B.Cu")
		(net "P1V2_STBY")
	)
	(segment
		(start 16.294354 -131.451858)
		(end 16.294354 -132.51053)
		(width 0.508)
		(layer "B.Cu")
		(net "P1V2_STBY")
	)
	(segment
		(start 29.25064 -158.5468)
		(end 29.40304 -158.3944)
		(width 0.508)
		(layer "B.Cu")
		(net "P1V2_STBY")
	)
	(segment
		(start 44.538392 -144.335754)
		(end 43.835574 -144.335754)
		(width 0.508)
		(layer "B.Cu")
		(net "P1V2_STBY")
	)
	(segment
		(start 12.536424 -132.402326)
		(end 13.595096 -132.402326)
		(width 0.508)
		(layer "B.Cu")
		(net "P1V2_STBY")
	)
	(segment
		(start 29.40304 -158.3944)
		(end 31.1404 -158.3944)
		(width 0.508)
		(layer "B.Cu")
		(net "P1V2_STBY")
	)
	(segment
		(start 21.93925 -158.81985)
		(end 23.0759 -159.9565)
		(width 0.508)
		(layer "B.Cu")
		(net "P1V2_STBY")
	)
	(segment
		(start 23.0759 -159.9565)
		(end 27.3177 -159.9565)
		(width 0.508)
		(layer "B.Cu")
		(net "P1V2_STBY")
	)
	(segment
		(start 13.361924 -136.715246)
		(end 13.363702 -136.713468)
		(width 0.508)
		(layer "B.Cu")
		(net "P1V2_STBY")
	)
	(segment
		(start 51.689254 -145.03527)
		(end 51.664362 -145.03527)
		(width 0.254)
		(layer "F.Cu")
		(net "P1V15_STBY")
	)
	(segment
		(start 45.699934 -141.400022)
		(end 45.700696 -141.400022)
		(width 0.254)
		(layer "F.Cu")
		(net "P1V15_STBY")
	)
	(segment
		(start 45.700696 -141.400022)
		(end 46.100238 -141.00048)
		(width 0.254)
		(layer "F.Cu")
		(net "P1V15_STBY")
	)
	(segment
		(start 71.715376 -160.7312)
		(end 70.0913 -160.7312)
		(width 0.508)
		(layer "F.Cu")
		(net "P1V15_STBY")
	)
	(segment
		(start 51.299872 -147.000214)
		(end 51.299872 -146.99996)
		(width 0.254)
		(layer "F.Cu")
		(net "P1V15_STBY")
	)
	(segment
		(start 74.9046 -157.541976)
		(end 71.715376 -160.7312)
		(width 0.508)
		(layer "F.Cu")
		(net "P1V15_STBY")
	)
	(segment
		(start 51.299872 -147.80006)
		(end 51.299872 -147.799806)
		(width 0.254)
		(layer "F.Cu")
		(net "P1V15_STBY")
	)
	(segment
		(start 45.699934 -145.400776)
		(end 45.699934 -145.400014)
		(width 0.254)
		(layer "F.Cu")
		(net "P1V15_STBY")
	)
	(segment
		(start 51.699668 -148.999956)
		(end 51.299872 -148.60016)
		(width 0.254)
		(layer "F.Cu")
		(net "P1V15_STBY")
	)
	(segment
		(start 45.300138 -143.400526)
		(end 45.699934 -143.00073)
		(width 0.254)
		(layer "F.Cu")
		(net "P1V15_STBY")
	)
	(segment
		(start 47.72279 -140.222732)
		(end 48.09998 -140.599922)
		(width 0.254)
		(layer "F.Cu")
		(net "P1V15_STBY")
	)
	(segment
		(start 45.699426 -146.19986)
		(end 45.300138 -145.800572)
		(width 0.254)
		(layer "F.Cu")
		(net "P1V15_STBY")
	)
	(segment
		(start 51.699668 -142.600172)
		(end 51.299872 -142.999968)
		(width 0.254)
		(layer "F.Cu")
		(net "P1V15_STBY")
	)
	(segment
		(start 51.299872 -146.200114)
		(end 51.699668 -146.59991)
		(width 0.254)
		(layer "F.Cu")
		(net "P1V15_STBY")
	)
	(segment
		(start 45.69968 -143.800068)
		(end 45.300138 -143.400526)
		(width 0.254)
		(layer "F.Cu")
		(net "P1V15_STBY")
	)
	(segment
		(start 45.699934 -146.99996)
		(end 45.699172 -146.99996)
		(width 0.254)
		(layer "F.Cu")
		(net "P1V15_STBY")
	)
	(segment
		(start 48.09998 -148.599906)
		(end 48.499776 -148.999702)
		(width 0.254)
		(layer "F.Cu")
		(net "P1V15_STBY")
	)
	(segment
		(start 45.299884 -149.00021)
		(end 44.899834 -148.60016)
		(width 0.254)
		(layer "F.Cu")
		(net "P1V15_STBY")
	)
	(segment
		(start 42.500042 -140.599922)
		(end 42.099992 -140.199872)
		(width 0.3048)
		(layer "F.Cu")
		(net "P1V15_STBY")
	)
	(segment
		(start 45.699172 -146.99996)
		(end 45.299376 -146.600164)
		(width 0.254)
		(layer "F.Cu")
		(net "P1V15_STBY")
	)
	(segment
		(start 45.699934 -148.60016)
		(end 45.299884 -149.00021)
		(width 0.254)
		(layer "F.Cu")
		(net "P1V15_STBY")
	)
	(segment
		(start 51.299872 -147.799806)
		(end 51.699668 -147.40001)
		(width 0.254)
		(layer "F.Cu")
		(net "P1V15_STBY")
	)
	(segment
		(start 51.299872 -145.39976)
		(end 51.299872 -145.400014)
		(width 0.254)
		(layer "F.Cu")
		(net "P1V15_STBY")
	)
	(segment
		(start 48.499776 -148.999702)
		(end 48.499776 -148.999956)
		(width 0.254)
		(layer "F.Cu")
		(net "P1V15_STBY")
	)
	(segment
		(start 51.689254 -145.03527)
		(end 51.689254 -144.98955)
		(width 0.254)
		(layer "F.Cu")
		(net "P1V15_STBY")
	)
	(segment
		(start 51.299872 -144.600168)
		(end 51.299872 -144.599914)
		(width 0.254)
		(layer "F.Cu")
		(net "P1V15_STBY")
	)
	(segment
		(start 51.299872 -146.19986)
		(end 51.299872 -146.200114)
		(width 0.254)
		(layer "F.Cu")
		(net "P1V15_STBY")
	)
	(segment
		(start 45.300138 -145.800572)
		(end 45.699934 -145.400776)
		(width 0.254)
		(layer "F.Cu")
		(net "P1V15_STBY")
	)
	(segment
		(start 51.689254 -144.98955)
		(end 51.299872 -144.600168)
		(width 0.254)
		(layer "F.Cu")
		(net "P1V15_STBY")
	)
	(segment
		(start 45.699934 -148.599906)
		(end 45.699934 -148.60016)
		(width 0.254)
		(layer "F.Cu")
		(net "P1V15_STBY")
	)
	(segment
		(start 76.210922 -153.319226)
		(end 74.9046 -154.625548)
		(width 0.508)
		(layer "F.Cu")
		(net "P1V15_STBY")
	)
	(segment
		(start 46.500034 -148.599906)
		(end 46.500034 -148.60016)
		(width 0.254)
		(layer "F.Cu")
		(net "P1V15_STBY")
	)
	(segment
		(start 40.099996 -140.599922)
		(end 40.10025 -140.599922)
		(width 0.3048)
		(layer "F.Cu")
		(net "P1V15_STBY")
	)
	(segment
		(start 51.699922 -143.400272)
		(end 51.699668 -143.400272)
		(width 0.254)
		(layer "F.Cu")
		(net "P1V15_STBY")
	)
	(segment
		(start 74.9046 -154.625548)
		(end 74.9046 -157.541976)
		(width 0.508)
		(layer "F.Cu")
		(net "P1V15_STBY")
	)
	(segment
		(start 51.299872 -142.199868)
		(end 51.299872 -142.200122)
		(width 0.254)
		(layer "F.Cu")
		(net "P1V15_STBY")
	)
	(segment
		(start 46.49978 -141.400022)
		(end 46.500034 -141.400022)
		(width 0.254)
		(layer "F.Cu")
		(net "P1V15_STBY")
	)
	(segment
		(start 44.900088 -141.400022)
		(end 45.299884 -141.000226)
		(width 0.254)
		(layer "F.Cu")
		(net "P1V15_STBY")
	)
	(segment
		(start 45.300138 -144.975326)
		(end 45.699934 -144.57553)
		(width 0.254)
		(layer "F.Cu")
		(net "P1V15_STBY")
	)
	(segment
		(start 46.100238 -141.00048)
		(end 46.49978 -141.400022)
		(width 0.254)
		(layer "F.Cu")
		(net "P1V15_STBY")
	)
	(segment
		(start 44.899834 -148.60016)
		(end 44.899834 -148.599906)
		(width 0.254)
		(layer "F.Cu")
		(net "P1V15_STBY")
	)
	(segment
		(start 49.70018 -141.400022)
		(end 50.10023 -140.999972)
		(width 0.254)
		(layer "F.Cu")
		(net "P1V15_STBY")
	)
	(segment
		(start 49.699926 -141.400022)
		(end 49.70018 -141.400022)
		(width 0.254)
		(layer "F.Cu")
		(net "P1V15_STBY")
	)
	(segment
		(start 45.699934 -144.57553)
		(end 45.699934 -144.599914)
		(width 0.254)
		(layer "F.Cu")
		(net "P1V15_STBY")
	)
	(segment
		(start 45.699934 -143.800068)
		(end 45.69968 -143.800068)
		(width 0.254)
		(layer "F.Cu")
		(net "P1V15_STBY")
	)
	(segment
		(start 46.500034 -148.60016)
		(end 46.100238 -148.999956)
		(width 0.254)
		(layer "F.Cu")
		(net "P1V15_STBY")
	)
	(segment
		(start 51.699922 -142.600172)
		(end 51.699668 -142.600172)
		(width 0.254)
		(layer "F.Cu")
		(net "P1V15_STBY")
	)
	(segment
		(start 51.699668 -143.400272)
		(end 51.299872 -143.800068)
		(width 0.254)
		(layer "F.Cu")
		(net "P1V15_STBY")
	)
	(segment
		(start 50.10023 -140.999972)
		(end 50.500026 -141.399768)
		(width 0.254)
		(layer "F.Cu")
		(net "P1V15_STBY")
	)
	(segment
		(start 50.500026 -141.399768)
		(end 50.500026 -141.400022)
		(width 0.254)
		(layer "F.Cu")
		(net "P1V15_STBY")
	)
	(segment
		(start 45.699934 -146.19986)
		(end 45.699426 -146.19986)
		(width 0.254)
		(layer "F.Cu")
		(net "P1V15_STBY")
	)
	(segment
		(start 51.299872 -148.60016)
		(end 51.299872 -148.599906)
		(width 0.254)
		(layer "F.Cu")
		(net "P1V15_STBY")
	)
	(segment
		(start 40.10025 -140.599922)
		(end 40.490648 -140.209524)
		(width 0.3048)
		(layer "F.Cu")
		(net "P1V15_STBY")
	)
	(segment
		(start 51.664362 -145.03527)
		(end 51.299872 -145.39976)
		(width 0.254)
		(layer "F.Cu")
		(net "P1V15_STBY")
	)
	(segment
		(start 52.099972 -149.400006)
		(end 52.099718 -149.400006)
		(width 0.254)
		(layer "F.Cu")
		(net "P1V15_STBY")
	)
	(segment
		(start 51.699668 -147.40001)
		(end 51.299872 -147.000214)
		(width 0.254)
		(layer "F.Cu")
		(net "P1V15_STBY")
	)
	(segment
		(start 70.0913 -160.7312)
		(end 68.3895 -162.433)
		(width 0.508)
		(layer "F.Cu")
		(net "P1V15_STBY")
	)
	(segment
		(start 52.099718 -149.400006)
		(end 51.699668 -148.999956)
		(width 0.254)
		(layer "F.Cu")
		(net "P1V15_STBY")
	)
	(segment
		(start 45.699934 -143.00073)
		(end 45.699934 -142.999968)
		(width 0.254)
		(layer "F.Cu")
		(net "P1V15_STBY")
	)
	(segment
		(start 51.299872 -142.200122)
		(end 51.699922 -142.600172)
		(width 0.254)
		(layer "F.Cu")
		(net "P1V15_STBY")
	)
	(segment
		(start 44.899834 -141.400022)
		(end 44.900088 -141.400022)
		(width 0.254)
		(layer "F.Cu")
		(net "P1V15_STBY")
	)
	(via
		(at 77.004164 -152.294082)
		(size 0.6604)
		(drill 0.3302)
		(layers "F.Cu" "B.Cu")
		(net "P1V15_STBY")
	)
	(via
		(at 48.5648 -132.715)
		(size 0.508)
		(drill 0.254)
		(layers "F.Cu" "B.Cu")
		(net "P1V15_STBY")
	)
	(via
		(at 51.689254 -145.03527)
		(size 0.4572)
		(drill 0.2032)
		(layers "F.Cu" "B.Cu")
		(net "P1V15_STBY")
	)
	(via
		(at 51.699668 -147.40001)
		(size 0.4572)
		(drill 0.2032)
		(layers "F.Cu" "B.Cu")
		(net "P1V15_STBY")
	)
	(via
		(at 45.299884 -141.000226)
		(size 0.4572)
		(drill 0.2032)
		(layers "F.Cu" "B.Cu")
		(net "P1V15_STBY")
	)
	(via
		(at 45.300138 -143.400526)
		(size 0.4572)
		(drill 0.2032)
		(layers "F.Cu" "B.Cu")
		(net "P1V15_STBY")
	)
	(via
		(at 51.699668 -148.999956)
		(size 0.4572)
		(drill 0.2032)
		(layers "F.Cu" "B.Cu")
		(net "P1V15_STBY")
	)
	(via
		(at 33.3502 -165.1254)
		(size 0.508)
		(drill 0.254)
		(layers "F.Cu" "B.Cu")
		(net "P1V15_STBY")
	)
	(via
		(at 45.300138 -144.975326)
		(size 0.4572)
		(drill 0.2032)
		(layers "F.Cu" "B.Cu")
		(net "P1V15_STBY")
	)
	(via
		(at 42.099992 -140.199872)
		(size 0.4572)
		(drill 0.2032)
		(layers "F.Cu" "B.Cu")
		(net "P1V15_STBY")
	)
	(via
		(at 48.5902 -133.5786)
		(size 0.508)
		(drill 0.254)
		(layers "F.Cu" "B.Cu")
		(net "P1V15_STBY")
	)
	(via
		(at 76.210922 -153.319226)
		(size 0.508)
		(drill 0.254)
		(layers "F.Cu" "B.Cu")
		(net "P1V15_STBY")
	)
	(via
		(at 45.299376 -146.600164)
		(size 0.4572)
		(drill 0.2032)
		(layers "F.Cu" "B.Cu")
		(net "P1V15_STBY")
	)
	(via
		(at 48.499776 -148.999956)
		(size 0.4572)
		(drill 0.2032)
		(layers "F.Cu" "B.Cu")
		(net "P1V15_STBY")
	)
	(via
		(at 50.10023 -140.999972)
		(size 0.4572)
		(drill 0.2032)
		(layers "F.Cu" "B.Cu")
		(net "P1V15_STBY")
	)
	(via
		(at 45.300138 -145.800572)
		(size 0.4572)
		(drill 0.2032)
		(layers "F.Cu" "B.Cu")
		(net "P1V15_STBY")
	)
	(via
		(at 51.699922 -142.600172)
		(size 0.4572)
		(drill 0.2032)
		(layers "F.Cu" "B.Cu")
		(net "P1V15_STBY")
	)
	(via
		(at 51.699922 -143.400272)
		(size 0.4572)
		(drill 0.2032)
		(layers "F.Cu" "B.Cu")
		(net "P1V15_STBY")
	)
	(via
		(at 40.490648 -140.209524)
		(size 0.4572)
		(drill 0.2032)
		(layers "F.Cu" "B.Cu")
		(net "P1V15_STBY")
	)
	(via
		(at 46.100238 -148.999956)
		(size 0.4572)
		(drill 0.2032)
		(layers "F.Cu" "B.Cu")
		(net "P1V15_STBY")
	)
	(via
		(at 47.72279 -140.222732)
		(size 0.4572)
		(drill 0.2032)
		(layers "F.Cu" "B.Cu")
		(net "P1V15_STBY")
	)
	(via
		(at 45.299884 -149.00021)
		(size 0.4572)
		(drill 0.2032)
		(layers "F.Cu" "B.Cu")
		(net "P1V15_STBY")
	)
	(via
		(at 77.080872 -153.326338)
		(size 0.508)
		(drill 0.254)
		(layers "F.Cu" "B.Cu")
		(net "P1V15_STBY")
	)
	(via
		(at 51.699668 -146.59991)
		(size 0.4572)
		(drill 0.2032)
		(layers "F.Cu" "B.Cu")
		(net "P1V15_STBY")
	)
	(via
		(at 46.100238 -141.00048)
		(size 0.4572)
		(drill 0.2032)
		(layers "F.Cu" "B.Cu")
		(net "P1V15_STBY")
	)
	(via
		(at 34.29 -165.1)
		(size 0.508)
		(drill 0.254)
		(layers "F.Cu" "B.Cu")
		(net "P1V15_STBY")
	)
	(segment
		(start 42.099992 -140.20546)
		(end 42.099992 -140.199872)
		(width 0.3048)
		(layer "In2.Cu")
		(net "P1V15_STBY")
	)
	(segment
		(start 41.545764 -140.759688)
		(end 42.099992 -140.20546)
		(width 0.3048)
		(layer "In2.Cu")
		(net "P1V15_STBY")
	)
	(segment
		(start 40.490648 -140.209524)
		(end 41.040812 -140.759688)
		(width 0.3048)
		(layer "In2.Cu")
		(net "P1V15_STBY")
	)
	(segment
		(start 41.040812 -140.759688)
		(end 41.545764 -140.759688)
		(width 0.3048)
		(layer "In2.Cu")
		(net "P1V15_STBY")
	)
	(segment
		(start 33.3502 -165.2016)
		(end 33.3502 -165.1254)
		(width 0.508)
		(layer "In2.Cu")
		(net "P1V15_STBY")
	)
	(segment
		(start 117.499384 -14.556232)
		(end 117.942868 -14.556232)
		(width 0.508)
		(layer "F.Cu")
		(net "P12V_IOM")
	)
	(segment
		(start 117.425216 -14.6304)
		(end 117.499384 -14.556232)
		(width 0.508)
		(layer "F.Cu")
		(net "P12V_IOM")
	)
	(segment
		(start 116.9162 -14.6304)
		(end 117.425216 -14.6304)
		(width 0.508)
		(layer "F.Cu")
		(net "P12V_IOM")
	)
	(via
		(at 124.841 -18.1864)
		(size 0.7112)
		(drill 0.4064)
		(layers "F.Cu" "B.Cu")
		(net "P12V_IOM")
	)
	(via
		(at 128.651 -19.4564)
		(size 0.7112)
		(drill 0.4064)
		(layers "F.Cu" "B.Cu")
		(net "P12V_IOM")
	)
	(via
		(at 130.429 -15.748)
		(size 0.508)
		(drill 0.254)
		(layers "F.Cu" "B.Cu")
		(net "P12V_IOM")
	)
	(via
		(at 126.111 -18.1864)
		(size 0.7112)
		(drill 0.4064)
		(layers "F.Cu" "B.Cu")
		(net "P12V_IOM")
	)
	(via
		(at 124.841 -19.4564)
		(size 0.7112)
		(drill 0.4064)
		(layers "F.Cu" "B.Cu")
		(net "P12V_IOM")
	)
	(via
		(at 127.381 -19.4564)
		(size 0.7112)
		(drill 0.4064)
		(layers "F.Cu" "B.Cu")
		(net "P12V_IOM")
	)
	(via
		(at 138.43 -16.0782)
		(size 0.6604)
		(drill 0.3302)
		(layers "F.Cu" "B.Cu")
		(net "P12V_IOM")
	)
	(via
		(at 127.381 -18.1864)
		(size 0.7112)
		(drill 0.4064)
		(layers "F.Cu" "B.Cu")
		(net "P12V_IOM")
	)
	(via
		(at 126.111 -19.4564)
		(size 0.7112)
		(drill 0.4064)
		(layers "F.Cu" "B.Cu")
		(net "P12V_IOM")
	)
	(via
		(at 116.9162 -14.6304)
		(size 0.508)
		(drill 0.254)
		(layers "F.Cu" "B.Cu")
		(net "P12V_IOM")
	)
	(via
		(at 136.767824 -16.546576)
		(size 0.508)
		(drill 0.254)
		(layers "F.Cu" "B.Cu")
		(net "P12V_IOM")
	)
	(segment
		(start 124.841 -18.078958)
		(end 124.841 -18.1864)
		(width 0.508)
		(layer "B.Cu")
		(net "P12V_IOM")
	)
	(segment
		(start 117.658642 -14.396974)
		(end 121.159016 -14.396974)
		(width 0.508)
		(layer "B.Cu")
		(net "P12V_IOM")
	)
	(segment
		(start 121.159016 -14.396974)
		(end 124.841 -18.078958)
		(width 0.508)
		(layer "B.Cu")
		(net "P12V_IOM")
	)
	(segment
		(start 116.9162 -14.6304)
		(end 117.425216 -14.6304)
		(width 0.508)
		(layer "B.Cu")
		(net "P12V_IOM")
	)
	(segment
		(start 136.767824 -16.546576)
		(end 136.767824 -17.460468)
		(width 0.508)
		(layer "B.Cu")
		(net "P12V_IOM")
	)
	(segment
		(start 117.425216 -14.6304)
		(end 117.658642 -14.396974)
		(width 0.508)
		(layer "B.Cu")
		(net "P12V_IOM")
	)
	(segment
		(start 51.699414 -140.20038)
		(end 51.299872 -140.599922)
		(width 0.127)
		(layer "F.Cu")
		(net "P12V_A_PGOOD_R")
	)
	(segment
		(start 51.699668 -140.20038)
		(end 51.699414 -140.20038)
		(width 0.127)
		(layer "F.Cu")
		(net "P12V_A_PGOOD_R")
	)
	(via
		(at 50.673254 -129.35585)
		(size 0.508)
		(drill 0.254)
		(layers "F.Cu" "B.Cu")
		(net "P12V_A_PGOOD_R")
	)
	(via
		(at 51.699668 -140.20038)
		(size 0.4572)
		(drill 0.2032)
		(layers "F.Cu" "B.Cu")
		(net "P12V_A_PGOOD_R")
	)
	(via
		(at 50.494184 -128.436878)
		(size 0.6096)
		(drill 0.3048)
		(layers "F.Cu" "B.Cu")
		(net "P12V_A_PGOOD_R")
	)
	(segment
		(start 50.673254 -129.337054)
		(end 50.494184 -129.157984)
		(width 0.127)
		(layer "B.Cu")
		(net "P12V_A_PGOOD_R")
	)
	(segment
		(start 50.494184 -128.436878)
		(end 50.494184 -127.383286)
		(width 0.127)
		(layer "B.Cu")
		(net "P12V_A_PGOOD_R")
	)
	(segment
		(start 50.673254 -129.35585)
		(end 50.673254 -129.337054)
		(width 0.127)
		(layer "B.Cu")
		(net "P12V_A_PGOOD_R")
	)
	(segment
		(start 50.494184 -129.157984)
		(end 50.494184 -128.436878)
		(width 0.127)
		(layer "B.Cu")
		(net "P12V_A_PGOOD_R")
	)
	(segment
		(start 52.1589 -132.1943)
		(end 51.29784 -133.05536)
		(width 0.127)
		(layer "In2.Cu")
		(net "P12V_A_PGOOD_R")
	)
	(segment
		(start 50.78095 -129.4384)
		(end 51.363118 -129.4384)
		(width 0.127)
		(layer "In2.Cu")
		(net "P12V_A_PGOOD_R")
	)
	(segment
		(start 51.363118 -129.4384)
		(end 52.1589 -130.234182)
		(width 0.127)
		(layer "In2.Cu")
		(net "P12V_A_PGOOD_R")
	)
	(segment
		(start 51.29784 -133.05536)
		(end 51.29784 -139.798552)
		(width 0.127)
		(layer "In2.Cu")
		(net "P12V_A_PGOOD_R")
	)
	(segment
		(start 51.29784 -139.798552)
		(end 51.699668 -140.20038)
		(width 0.127)
		(layer "In2.Cu")
		(net "P12V_A_PGOOD_R")
	)
	(segment
		(start 50.673254 -129.35585)
		(end 50.6984 -129.35585)
		(width 0.127)
		(layer "In2.Cu")
		(net "P12V_A_PGOOD_R")
	)
	(segment
		(start 50.6984 -129.35585)
		(end 50.78095 -129.4384)
		(width 0.127)
		(layer "In2.Cu")
		(net "P12V_A_PGOOD_R")
	)
	(segment
		(start 52.1589 -130.234182)
		(end 52.1589 -132.1943)
		(width 0.127)
		(layer "In2.Cu")
		(net "P12V_A_PGOOD_R")
	)
	(segment
		(start 122.542554 -27.980132)
		(end 122.056652 -28.466034)
		(width 0.127)
		(layer "F.Cu")
		(net "P12V_A_PGOOD")
	)
	(segment
		(start 126.644908 -27.980132)
		(end 122.542554 -27.980132)
		(width 0.127)
		(layer "F.Cu")
		(net "P12V_A_PGOOD")
	)
	(segment
		(start 130.499866 -42.800016)
		(end 129.591308 -41.891458)
		(width 0.127)
		(layer "F.Cu")
		(net "P12V_A_PGOOD")
	)
	(segment
		(start 129.591308 -41.891458)
		(end 129.591308 -30.926532)
		(width 0.127)
		(layer "F.Cu")
		(net "P12V_A_PGOOD")
	)
	(segment
		(start 129.591308 -30.926532)
		(end 126.644908 -27.980132)
		(width 0.127)
		(layer "F.Cu")
		(net "P12V_A_PGOOD")
	)
	(via
		(at 94.2086 -119.8118)
		(size 0.508)
		(drill 0.254)
		(layers "F.Cu" "B.Cu")
		(net "P12V_A_PGOOD")
	)
	(via
		(at 122.056652 -28.466034)
		(size 0.508)
		(drill 0.254)
		(layers "F.Cu" "B.Cu")
		(net "P12V_A_PGOOD")
	)
	(via
		(at 50.9651 -126.456948)
		(size 0.508)
		(drill 0.254)
		(layers "F.Cu" "B.Cu")
		(net "P12V_A_PGOOD")
	)
	(via
		(at 114.93246 -16.31696)
		(size 0.6096)
		(drill 0.3048)
		(layers "F.Cu" "B.Cu")
		(net "P12V_A_PGOOD")
	)
	(segment
		(start 114.93246 -8.05434)
		(end 114.93246 -16.31696)
		(width 0.127)
		(layer "B.Cu")
		(net "P12V_A_PGOOD")
	)
	(segment
		(start 116.38534 -6.60146)
		(end 114.93246 -8.05434)
		(width 0.127)
		(layer "B.Cu")
		(net "P12V_A_PGOOD")
	)
	(segment
		(start 120.550432 -26.621232)
		(end 120.550432 -24.906732)
		(width 0.127)
		(layer "B.Cu")
		(net "P12V_A_PGOOD")
	)
	(segment
		(start 114.93246 -19.28876)
		(end 114.93246 -16.31696)
		(width 0.127)
		(layer "B.Cu")
		(net "P12V_A_PGOOD")
	)
	(segment
		(start 122.056652 -28.466034)
		(end 122.056652 -28.127452)
		(width 0.127)
		(layer "B.Cu")
		(net "P12V_A_PGOOD")
	)
	(segment
		(start 120.550432 -24.906732)
		(end 114.93246 -19.28876)
		(width 0.127)
		(layer "B.Cu")
		(net "P12V_A_PGOOD")
	)
	(segment
		(start 51.383184 -127.383286)
		(end 51.383184 -126.875032)
		(width 0.127)
		(layer "B.Cu")
		(net "P12V_A_PGOOD")
	)
	(segment
		(start 51.383184 -126.875032)
		(end 50.9651 -126.456948)
		(width 0.127)
		(layer "B.Cu")
		(net "P12V_A_PGOOD")
	)
	(segment
		(start 122.056652 -28.127452)
		(end 120.550432 -26.621232)
		(width 0.127)
		(layer "B.Cu")
		(net "P12V_A_PGOOD")
	)
	(segment
		(start 94.060772 -51.693572)
		(end 94.060772 -51.058572)
		(width 0.127)
		(layer "In2.Cu")
		(net "P12V_A_PGOOD")
	)
	(segment
		(start 103.879142 -22.835616)
		(end 114.567716 -22.835616)
		(width 0.127)
		(layer "In2.Cu")
		(net "P12V_A_PGOOD")
	)
	(segment
		(start 97.205546 -29.509212)
		(end 103.879142 -22.835616)
		(width 0.127)
		(layer "In2.Cu")
		(net "P12V_A_PGOOD")
	)
	(segment
		(start 94.869 -64.0588)
		(end 94.869 -52.5018)
		(width 0.127)
		(layer "In2.Cu")
		(net "P12V_A_PGOOD")
	)
	(segment
		(start 94.060772 -51.058572)
		(end 94.783148 -50.336196)
		(width 0.127)
		(layer "In2.Cu")
		(net "P12V_A_PGOOD")
	)
	(segment
		(start 95.3262 -94.109286)
		(end 94.7166 -93.499686)
		(width 0.127)
		(layer "In2.Cu")
		(net "P12V_A_PGOOD")
	)
	(segment
		(start 94.3356 -92.820236)
		(end 94.3356 -64.5922)
		(width 0.127)
		(layer "In2.Cu")
		(net "P12V_A_PGOOD")
	)
	(segment
		(start 114.567716 -22.835616)
		(end 120.198134 -28.466034)
		(width 0.127)
		(layer "In2.Cu")
		(net "P12V_A_PGOOD")
	)
	(segment
		(start 95.3262 -111.389668)
		(end 95.3262 -94.109286)
		(width 0.127)
		(layer "In2.Cu")
		(net "P12V_A_PGOOD")
	)
	(segment
		(start 93.5736 -115.2906)
		(end 93.5736 -113.142268)
		(width 0.127)
		(layer "In2.Cu")
		(net "P12V_A_PGOOD")
	)
	(segment
		(start 97.205546 -34.078418)
		(end 97.205546 -29.509212)
		(width 0.127)
		(layer "In2.Cu")
		(net "P12V_A_PGOOD")
	)
	(segment
		(start 94.7166 -93.499686)
		(end 94.7166 -93.201236)
		(width 0.127)
		(layer "In2.Cu")
		(net "P12V_A_PGOOD")
	)
	(segment
		(start 120.198134 -28.466034)
		(end 122.056652 -28.466034)
		(width 0.127)
		(layer "In2.Cu")
		(net "P12V_A_PGOOD")
	)
	(segment
		(start 94.869 -52.5018)
		(end 94.060772 -51.693572)
		(width 0.127)
		(layer "In2.Cu")
		(net "P12V_A_PGOOD")
	)
	(segment
		(start 94.3356 -64.5922)
		(end 94.869 -64.0588)
		(width 0.127)
		(layer "In2.Cu")
		(net "P12V_A_PGOOD")
	)
	(segment
		(start 93.5736 -113.142268)
		(end 95.3262 -111.389668)
		(width 0.127)
		(layer "In2.Cu")
		(net "P12V_A_PGOOD")
	)
	(segment
		(start 93.8784 -115.5954)
		(end 93.5736 -115.2906)
		(width 0.127)
		(layer "In2.Cu")
		(net "P12V_A_PGOOD")
	)
	(segment
		(start 93.8784 -119.4816)
		(end 93.8784 -115.5954)
		(width 0.127)
		(layer "In2.Cu")
		(net "P12V_A_PGOOD")
	)
	(segment
		(start 94.2086 -119.8118)
		(end 93.8784 -119.4816)
		(width 0.127)
		(layer "In2.Cu")
		(net "P12V_A_PGOOD")
	)
	(segment
		(start 94.783148 -36.500816)
		(end 97.205546 -34.078418)
		(width 0.127)
		(layer "In2.Cu")
		(net "P12V_A_PGOOD")
	)
	(segment
		(start 94.783148 -50.336196)
		(end 94.783148 -36.500816)
		(width 0.127)
		(layer "In2.Cu")
		(net "P12V_A_PGOOD")
	)
	(segment
		(start 94.7166 -93.201236)
		(end 94.3356 -92.820236)
		(width 0.127)
		(layer "In2.Cu")
		(net "P12V_A_PGOOD")
	)
	(segment
		(start 67.0179 -123.1773)
		(end 67.8434 -122.3518)
		(width 0.127)
		(layer "In5.Cu")
		(net "P12V_A_PGOOD")
	)
	(segment
		(start 50.9651 -126.456948)
		(end 51.148234 -126.273814)
		(width 0.127)
		(layer "In5.Cu")
		(net "P12V_A_PGOOD")
	)
	(segment
		(start 67.8434 -122.3518)
		(end 73.8632 -122.3518)
		(width 0.127)
		(layer "In5.Cu")
		(net "P12V_A_PGOOD")
	)
	(segment
		(start 53.451252 -123.66879)
		(end 58.287666 -123.66879)
		(width 0.127)
		(layer "In5.Cu")
		(net "P12V_A_PGOOD")
	)
	(segment
		(start 93.798898 -119.402098)
		(end 94.2086 -119.8118)
		(width 0.127)
		(layer "In5.Cu")
		(net "P12V_A_PGOOD")
	)
	(segment
		(start 58.779156 -123.1773)
		(end 67.0179 -123.1773)
		(width 0.127)
		(layer "In5.Cu")
		(net "P12V_A_PGOOD")
	)
	(segment
		(start 51.148234 -126.273814)
		(end 51.148234 -125.971808)
		(width 0.127)
		(layer "In5.Cu")
		(net "P12V_A_PGOOD")
	)
	(segment
		(start 82.4484 -126.0094)
		(end 89.055702 -119.402098)
		(width 0.127)
		(layer "In5.Cu")
		(net "P12V_A_PGOOD")
	)
	(segment
		(start 77.5208 -126.0094)
		(end 82.4484 -126.0094)
		(width 0.127)
		(layer "In5.Cu")
		(net "P12V_A_PGOOD")
	)
	(segment
		(start 73.8632 -122.3518)
		(end 77.5208 -126.0094)
		(width 0.127)
		(layer "In5.Cu")
		(net "P12V_A_PGOOD")
	)
	(segment
		(start 51.148234 -125.971808)
		(end 53.451252 -123.66879)
		(width 0.127)
		(layer "In5.Cu")
		(net "P12V_A_PGOOD")
	)
	(segment
		(start 89.055702 -119.402098)
		(end 93.798898 -119.402098)
		(width 0.127)
		(layer "In5.Cu")
		(net "P12V_A_PGOOD")
	)
	(segment
		(start 58.287666 -123.66879)
		(end 58.779156 -123.1773)
		(width 0.127)
		(layer "In5.Cu")
		(net "P12V_A_PGOOD")
	)
	(segment
		(start 34.613088 -132.026152)
		(end 34.293048 -132.346192)
		(width 0.127)
		(layer "F.Cu")
		(net "OSC_OUT")
	)
	(segment
		(start 36.046156 -132.026152)
		(end 34.613088 -132.026152)
		(width 0.127)
		(layer "F.Cu")
		(net "OSC_OUT")
	)
	(segment
		(start 31.950152 -130.696208)
		(end 32.576008 -130.696208)
		(width 0.127)
		(layer "F.Cu")
		(net "OSC_OE")
	)
	(segment
		(start 35.618166 -131.399534)
		(end 36.068 -130.9497)
		(width 0.127)
		(layer "F.Cu")
		(net "OSC_OE")
	)
	(segment
		(start 32.576008 -130.696208)
		(end 33.279334 -131.399534)
		(width 0.127)
		(layer "F.Cu")
		(net "OSC_OE")
	)
	(segment
		(start 33.279334 -131.399534)
		(end 35.618166 -131.399534)
		(width 0.127)
		(layer "F.Cu")
		(net "OSC_OE")
	)
	(segment
		(start 41.699942 -145.400014)
		(end 41.299892 -144.999964)
		(width 0.127)
		(layer "F.Cu")
		(net "MIOZ")
	)
	(via
		(at 41.299892 -144.999964)
		(size 0.4572)
		(drill 0.2032)
		(layers "F.Cu" "B.Cu")
		(net "MIOZ")
	)
	(segment
		(start 39.96944 -144.6022)
		(end 40.659558 -144.6022)
		(width 0.127)
		(layer "B.Cu")
		(net "MIOZ")
	)
	(segment
		(start 41.057322 -144.999964)
		(end 41.299892 -144.999964)
		(width 0.127)
		(layer "B.Cu")
		(net "MIOZ")
	)
	(segment
		(start 39.751254 -144.384014)
		(end 39.96944 -144.6022)
		(width 0.127)
		(layer "B.Cu")
		(net "MIOZ")
	)
	(segment
		(start 40.659558 -144.6022)
		(end 41.057322 -144.999964)
		(width 0.127)
		(layer "B.Cu")
		(net "MIOZ")
	)
	(segment
		(start 39.751254 -143.336518)
		(end 39.751254 -144.384014)
		(width 0.127)
		(layer "B.Cu")
		(net "MIOZ")
	)
	(segment
		(start 19.932396 -141.833092)
		(end 19.932396 -142.824708)
		(width 0.508)
		(layer "B.Cu")
		(net "MEMCK_TER")
	)
	(segment
		(start 19.932396 -142.824708)
		(end 19.874738 -142.882366)
		(width 0.508)
		(layer "B.Cu")
		(net "MEMCK_TER")
	)
	(segment
		(start 19.93265 -140.808202)
		(end 19.93265 -141.832838)
		(width 0.508)
		(layer "B.Cu")
		(net "MEMCK_TER")
	)
	(segment
		(start 19.93265 -141.832838)
		(end 19.932396 -141.833092)
		(width 0.508)
		(layer "B.Cu")
		(net "MEMCK_TER")
	)
	(segment
		(start 15.470886 -139.406122)
		(end 15.183358 -139.118594)
		(width 0.127)
		(layer "F.Cu")
		(net "MEMBG_0")
	)
	(segment
		(start 13.95476 -138.8618)
		(end 10.5283 -138.8618)
		(width 0.127)
		(layer "F.Cu")
		(net "MEMBG_0")
	)
	(segment
		(start 17.319752 -139.761468)
		(end 16.964406 -139.406122)
		(width 0.127)
		(layer "F.Cu")
		(net "MEMBG_0")
	)
	(segment
		(start 14.08176 -138.9888)
		(end 13.95476 -138.8618)
		(width 0.127)
		(layer "F.Cu")
		(net "MEMBG_0")
	)
	(segment
		(start 9.2837 -139.573)
		(end 10.2997 -139.573)
		(width 0.127)
		(layer "F.Cu")
		(net "MEMBG_0")
	)
	(segment
		(start 15.183358 -139.118594)
		(end 14.734286 -139.118594)
		(width 0.127)
		(layer "F.Cu")
		(net "MEMBG_0")
	)
	(segment
		(start 17.634712 -139.761468)
		(end 18.034508 -139.361672)
		(width 0.127)
		(layer "F.Cu")
		(net "MEMBG_0")
	)
	(segment
		(start 41.299384 -143.400018)
		(end 41.699434 -143.800068)
		(width 0.127)
		(layer "F.Cu")
		(net "MEMBG_0")
	)
	(segment
		(start 14.46276 -140.365734)
		(end 14.20876 -140.365734)
		(width 0.127)
		(layer "F.Cu")
		(net "MEMBG_0")
	)
	(segment
		(start 17.634458 -139.761468)
		(end 17.634712 -139.761468)
		(width 0.127)
		(layer "F.Cu")
		(net "MEMBG_0")
	)
	(segment
		(start 41.699434 -143.800068)
		(end 41.699942 -143.800068)
		(width 0.127)
		(layer "F.Cu")
		(net "MEMBG_0")
	)
	(segment
		(start 41.29913 -143.400018)
		(end 41.299384 -143.400018)
		(width 0.127)
		(layer "F.Cu")
		(net "MEMBG_0")
	)
	(segment
		(start 16.964406 -139.406122)
		(end 15.470886 -139.406122)
		(width 0.127)
		(layer "F.Cu")
		(net "MEMBG_0")
	)
	(segment
		(start 14.58976 -139.26312)
		(end 14.58976 -140.238734)
		(width 0.127)
		(layer "F.Cu")
		(net "MEMBG_0")
	)
	(segment
		(start 14.20876 -140.365734)
		(end 14.08176 -140.238734)
		(width 0.127)
		(layer "F.Cu")
		(net "MEMBG_0")
	)
	(segment
		(start 10.5283 -138.8618)
		(end 10.2997 -139.0904)
		(width 0.127)
		(layer "F.Cu")
		(net "MEMBG_0")
	)
	(segment
		(start 10.2997 -139.0904)
		(end 10.2997 -139.573)
		(width 0.127)
		(layer "F.Cu")
		(net "MEMBG_0")
	)
	(segment
		(start 17.634458 -139.761468)
		(end 17.319752 -139.761468)
		(width 0.127)
		(layer "F.Cu")
		(net "MEMBG_0")
	)
	(segment
		(start 14.734286 -139.118594)
		(end 14.58976 -139.26312)
		(width 0.127)
		(layer "F.Cu")
		(net "MEMBG_0")
	)
	(segment
		(start 14.08176 -140.238734)
		(end 14.08176 -138.9888)
		(width 0.127)
		(layer "F.Cu")
		(net "MEMBG_0")
	)
	(segment
		(start 14.58976 -140.238734)
		(end 14.46276 -140.365734)
		(width 0.127)
		(layer "F.Cu")
		(net "MEMBG_0")
	)
	(via
		(at 41.29913 -143.400018)
		(size 0.4572)
		(drill 0.2032)
		(layers "F.Cu" "B.Cu")
		(net "MEMBG_0")
	)
	(via
		(at 18.034508 -139.361672)
		(size 0.508)
		(drill 0.254)
		(layers "F.Cu" "B.Cu")
		(net "MEMBG_0")
	)
	(segment
		(start 21.368004 -139.462764)
		(end 21.148548 -139.68222)
		(width 0.127)
		(layer "In5.Cu")
		(net "MEMBG_0")
	)
	(segment
		(start 17.514316 -140.303758)
		(end 17.278604 -140.068046)
		(width 0.0889)
		(layer "In5.Cu")
		(net "MEMBG_0")
	)
	(segment
		(start 21.068538 -139.761468)
		(end 21.00453 -139.825476)
		(width 0.0889)
		(layer "In5.Cu")
		(net "MEMBG_0")
	)
	(segment
		(start 37.971476 -141.869414)
		(end 31.933388 -141.869414)
		(width 0.127)
		(layer "In5.Cu")
		(net "MEMBG_0")
	)
	(segment
		(start 19.838924 -140.310616)
		(end 19.661124 -140.310616)
		(width 0.0889)
		(layer "In5.Cu")
		(net "MEMBG_0")
	)
	(segment
		(start 20.016724 -139.825476)
		(end 19.927824 -139.914376)
		(width 0.0889)
		(layer "In5.Cu")
		(net "MEMBG_0")
	)
	(segment
		(start 21.148548 -139.68222)
		(end 21.0693 -139.761468)
		(width 0.0889)
		(layer "In5.Cu")
		(net "MEMBG_0")
	)
	(segment
		(start 24.426418 -139.462764)
		(end 21.368004 -139.462764)
		(width 0.127)
		(layer "In5.Cu")
		(net "MEMBG_0")
	)
	(segment
		(start 19.572224 -140.221716)
		(end 19.572224 -139.914376)
		(width 0.0889)
		(layer "In5.Cu")
		(net "MEMBG_0")
	)
	(segment
		(start 40.926766 -143.298164)
		(end 39.400226 -143.298164)
		(width 0.127)
		(layer "In5.Cu")
		(net "MEMBG_0")
	)
	(segment
		(start 19.927824 -140.221716)
		(end 19.838924 -140.310616)
		(width 0.0889)
		(layer "In5.Cu")
		(net "MEMBG_0")
	)
	(segment
		(start 19.927824 -139.914376)
		(end 19.927824 -140.221716)
		(width 0.0889)
		(layer "In5.Cu")
		(net "MEMBG_0")
	)
	(segment
		(start 20.194524 -139.825476)
		(end 20.016724 -139.825476)
		(width 0.0889)
		(layer "In5.Cu")
		(net "MEMBG_0")
	)
	(segment
		(start 20.727924 -139.825476)
		(end 20.639024 -139.914376)
		(width 0.0889)
		(layer "In5.Cu")
		(net "MEMBG_0")
	)
	(segment
		(start 17.278604 -140.068046)
		(end 17.278604 -139.546838)
		(width 0.0889)
		(layer "In5.Cu")
		(net "MEMBG_0")
	)
	(segment
		(start 20.639024 -140.221716)
		(end 20.550124 -140.310616)
		(width 0.0889)
		(layer "In5.Cu")
		(net "MEMBG_0")
	)
	(segment
		(start 27.4955 -139.58824)
		(end 24.551894 -139.58824)
		(width 0.127)
		(layer "In5.Cu")
		(net "MEMBG_0")
	)
	(segment
		(start 20.283424 -139.914376)
		(end 20.194524 -139.825476)
		(width 0.0889)
		(layer "In5.Cu")
		(net "MEMBG_0")
	)
	(segment
		(start 17.278604 -139.546838)
		(end 17.46377 -139.361672)
		(width 0.0889)
		(layer "In5.Cu")
		(net "MEMBG_0")
	)
	(segment
		(start 21.00453 -139.825476)
		(end 20.727924 -139.825476)
		(width 0.0889)
		(layer "In5.Cu")
		(net "MEMBG_0")
	)
	(segment
		(start 24.551894 -139.58824)
		(end 24.426418 -139.462764)
		(width 0.127)
		(layer "In5.Cu")
		(net "MEMBG_0")
	)
	(segment
		(start 18.877026 -139.58316)
		(end 18.156428 -140.303758)
		(width 0.0889)
		(layer "In5.Cu")
		(net "MEMBG_0")
	)
	(segment
		(start 39.400226 -143.298164)
		(end 37.971476 -141.869414)
		(width 0.127)
		(layer "In5.Cu")
		(net "MEMBG_0")
	)
	(segment
		(start 19.572224 -139.914376)
		(end 19.241008 -139.58316)
		(width 0.0889)
		(layer "In5.Cu")
		(net "MEMBG_0")
	)
	(segment
		(start 20.283424 -140.221716)
		(end 20.283424 -139.914376)
		(width 0.0889)
		(layer "In5.Cu")
		(net "MEMBG_0")
	)
	(segment
		(start 20.639024 -139.914376)
		(end 20.639024 -140.221716)
		(width 0.0889)
		(layer "In5.Cu")
		(net "MEMBG_0")
	)
	(segment
		(start 31.933388 -141.869414)
		(end 31.732982 -142.06982)
		(width 0.127)
		(layer "In5.Cu")
		(net "MEMBG_0")
	)
	(segment
		(start 17.46377 -139.361672)
		(end 18.034508 -139.361672)
		(width 0.0889)
		(layer "In5.Cu")
		(net "MEMBG_0")
	)
	(segment
		(start 18.156428 -140.303758)
		(end 17.514316 -140.303758)
		(width 0.0889)
		(layer "In5.Cu")
		(net "MEMBG_0")
	)
	(segment
		(start 31.732982 -142.06982)
		(end 29.97708 -142.06982)
		(width 0.127)
		(layer "In5.Cu")
		(net "MEMBG_0")
	)
	(segment
		(start 20.372324 -140.310616)
		(end 20.283424 -140.221716)
		(width 0.0889)
		(layer "In5.Cu")
		(net "MEMBG_0")
	)
	(segment
		(start 21.0693 -139.761468)
		(end 21.068538 -139.761468)
		(width 0.0889)
		(layer "In5.Cu")
		(net "MEMBG_0")
	)
	(segment
		(start 20.550124 -140.310616)
		(end 20.372324 -140.310616)
		(width 0.0889)
		(layer "In5.Cu")
		(net "MEMBG_0")
	)
	(segment
		(start 19.241008 -139.58316)
		(end 18.877026 -139.58316)
		(width 0.0889)
		(layer "In5.Cu")
		(net "MEMBG_0")
	)
	(segment
		(start 29.97708 -142.06982)
		(end 27.4955 -139.58824)
		(width 0.127)
		(layer "In5.Cu")
		(net "MEMBG_0")
	)
	(segment
		(start 19.661124 -140.310616)
		(end 19.572224 -140.221716)
		(width 0.0889)
		(layer "In5.Cu")
		(net "MEMBG_0")
	)
	(arc
		(start 41.29913 -143.400018)
		(mid 41.187972 -143.416344)
		(end 41.088056 -143.364966)
		(width 0.127)
		(layer "In5.Cu")
		(net "MEMBG_0")
	)
	(arc
		(start 41.088056 -143.364966)
		(mid 41.014056 -143.31552)
		(end 40.926766 -143.298164)
		(width 0.127)
		(layer "In5.Cu")
		(net "MEMBG_0")
	)
	(segment
		(start 12.96416 -134.42823)
		(end 12.456414 -133.920484)
		(width 0.127)
		(layer "F.Cu")
		(net "MEM_PAR")
	)
	(segment
		(start 18.434558 -136.561576)
		(end 16.301212 -134.42823)
		(width 0.127)
		(layer "F.Cu")
		(net "MEM_PAR")
	)
	(segment
		(start 10.326624 -135.285988)
		(end 9.75868 -135.285988)
		(width 0.127)
		(layer "F.Cu")
		(net "MEM_PAR")
	)
	(segment
		(start 10.326624 -134.326376)
		(end 10.326624 -135.285988)
		(width 0.127)
		(layer "F.Cu")
		(net "MEM_PAR")
	)
	(segment
		(start 16.301212 -134.42823)
		(end 12.96416 -134.42823)
		(width 0.127)
		(layer "F.Cu")
		(net "MEM_PAR")
	)
	(segment
		(start 9.75868 -135.285988)
		(end 9.754616 -135.290052)
		(width 0.127)
		(layer "F.Cu")
		(net "MEM_PAR")
	)
	(segment
		(start 12.456414 -133.920484)
		(end 10.732516 -133.920484)
		(width 0.127)
		(layer "F.Cu")
		(net "MEM_PAR")
	)
	(segment
		(start 10.732516 -133.920484)
		(end 10.326624 -134.326376)
		(width 0.127)
		(layer "F.Cu")
		(net "MEM_PAR")
	)
	(segment
		(start 9.754616 -135.290052)
		(end 9.32561 -135.290052)
		(width 0.127)
		(layer "F.Cu")
		(net "MEM_PAR")
	)
	(segment
		(start 53.699664 -150.999952)
		(end 53.299614 -150.599902)
		(width 0.127)
		(layer "F.Cu")
		(net "MAC2_TXD3")
	)
	(segment
		(start 53.699918 -150.999952)
		(end 53.699664 -150.999952)
		(width 0.127)
		(layer "F.Cu")
		(net "MAC2_TXD3")
	)
	(via
		(at 57.45353 -153.232866)
		(size 0.6096)
		(drill 0.3048)
		(layers "F.Cu" "B.Cu")
		(net "MAC2_TXD3")
	)
	(via
		(at 53.299614 -150.599902)
		(size 0.4572)
		(drill 0.2032)
		(layers "F.Cu" "B.Cu")
		(net "MAC2_TXD3")
	)
	(segment
		(start 57.45353 -153.232866)
		(end 57.412128 -153.232866)
		(width 0.127)
		(layer "B.Cu")
		(net "MAC2_TXD3")
	)
	(segment
		(start 57.412128 -153.232866)
		(end 55.969662 -151.7904)
		(width 0.127)
		(layer "B.Cu")
		(net "MAC2_TXD3")
	)
	(segment
		(start 57.914794 -156.047694)
		(end 57.813448 -156.14904)
		(width 0.127)
		(layer "B.Cu")
		(net "MAC2_TXD3")
	)
	(segment
		(start 57.661302 -157.462474)
		(end 57.661302 -157.462728)
		(width 0.127)
		(layer "B.Cu")
		(net "MAC2_TXD3")
	)
	(segment
		(start 55.969662 -151.7904)
		(end 54.671468 -151.7904)
		(width 0.127)
		(layer "B.Cu")
		(net "MAC2_TXD3")
	)
	(segment
		(start 53.3273 -150.627588)
		(end 53.299614 -150.599902)
		(width 0.127)
		(layer "B.Cu")
		(net "MAC2_TXD3")
	)
	(segment
		(start 57.661048 -156.820616)
		(end 57.661048 -157.46222)
		(width 0.127)
		(layer "B.Cu")
		(net "MAC2_TXD3")
	)
	(segment
		(start 54.671468 -151.7904)
		(end 53.508656 -150.627588)
		(width 0.127)
		(layer "B.Cu")
		(net "MAC2_TXD3")
	)
	(segment
		(start 57.93486 -158.1785)
		(end 57.948068 -158.191708)
		(width 0.127)
		(layer "B.Cu")
		(net "MAC2_TXD3")
	)
	(segment
		(start 57.45353 -153.232866)
		(end 57.914794 -153.69413)
		(width 0.127)
		(layer "B.Cu")
		(net "MAC2_TXD3")
	)
	(segment
		(start 57.661302 -156.765498)
		(end 57.661048 -156.820616)
		(width 0.127)
		(layer "B.Cu")
		(net "MAC2_TXD3")
	)
	(segment
		(start 56.896 -158.1785)
		(end 57.93486 -158.1785)
		(width 0.127)
		(layer "B.Cu")
		(net "MAC2_TXD3")
	)
	(segment
		(start 57.661048 -157.46222)
		(end 57.661302 -157.462474)
		(width 0.127)
		(layer "B.Cu")
		(net "MAC2_TXD3")
	)
	(segment
		(start 53.508656 -150.627588)
		(end 53.3273 -150.627588)
		(width 0.127)
		(layer "B.Cu")
		(net "MAC2_TXD3")
	)
	(segment
		(start 57.813448 -156.613352)
		(end 57.661302 -156.765498)
		(width 0.127)
		(layer "B.Cu")
		(net "MAC2_TXD3")
	)
	(segment
		(start 57.948068 -157.749494)
		(end 57.948068 -158.191708)
		(width 0.127)
		(layer "B.Cu")
		(net "MAC2_TXD3")
	)
	(segment
		(start 57.914794 -153.69413)
		(end 57.914794 -156.047694)
		(width 0.127)
		(layer "B.Cu")
		(net "MAC2_TXD3")
	)
	(segment
		(start 57.661302 -157.462728)
		(end 57.948068 -157.749494)
		(width 0.127)
		(layer "B.Cu")
		(net "MAC2_TXD3")
	)
	(segment
		(start 57.813448 -156.14904)
		(end 57.813448 -156.613352)
		(width 0.127)
		(layer "B.Cu")
		(net "MAC2_TXD3")
	)
	(segment
		(start 53.700172 -150.199852)
		(end 53.699918 -150.199852)
		(width 0.127)
		(layer "F.Cu")
		(net "MAC2_TXD2")
	)
	(segment
		(start 54.099968 -149.800056)
		(end 53.700172 -150.199852)
		(width 0.127)
		(layer "F.Cu")
		(net "MAC2_TXD2")
	)
	(via
		(at 54.099968 -149.800056)
		(size 0.4572)
		(drill 0.2032)
		(layers "F.Cu" "B.Cu")
		(net "MAC2_TXD2")
	)
	(via
		(at 55.447692 -150.304246)
		(size 0.6096)
		(drill 0.3048)
		(layers "F.Cu" "B.Cu")
		(net "MAC2_TXD2")
	)
	(segment
		(start 59.40171 -150.749)
		(end 58.88101 -150.2283)
		(width 0.127)
		(layer "B.Cu")
		(net "MAC2_TXD2")
	)
	(segment
		(start 55.867554 -150.304246)
		(end 55.447692 -150.304246)
		(width 0.127)
		(layer "B.Cu")
		(net "MAC2_TXD2")
	)
	(segment
		(start 58.88101 -150.2283)
		(end 55.9435 -150.2283)
		(width 0.127)
		(layer "B.Cu")
		(net "MAC2_TXD2")
	)
	(segment
		(start 59.8043 -150.749)
		(end 59.40171 -150.749)
		(width 0.127)
		(layer "B.Cu")
		(net "MAC2_TXD2")
	)
	(segment
		(start 54.3433 -149.800056)
		(end 54.099968 -149.800056)
		(width 0.127)
		(layer "B.Cu")
		(net "MAC2_TXD2")
	)
	(segment
		(start 55.447692 -150.304246)
		(end 54.84749 -150.304246)
		(width 0.127)
		(layer "B.Cu")
		(net "MAC2_TXD2")
	)
	(segment
		(start 60.6933 -151.638)
		(end 59.8043 -150.749)
		(width 0.127)
		(layer "B.Cu")
		(net "MAC2_TXD2")
	)
	(segment
		(start 55.9435 -150.2283)
		(end 55.867554 -150.304246)
		(width 0.127)
		(layer "B.Cu")
		(net "MAC2_TXD2")
	)
	(segment
		(start 54.84749 -150.304246)
		(end 54.3433 -149.800056)
		(width 0.127)
		(layer "B.Cu")
		(net "MAC2_TXD2")
	)
	(segment
		(start 60.6933 -151.765)
		(end 60.6933 -151.638)
		(width 0.127)
		(layer "B.Cu")
		(net "MAC2_TXD2")
	)
	(segment
		(start 60.9219 -158.3944)
		(end 60.452 -157.9245)
		(width 0.127)
		(layer "F.Cu")
		(net "MAC2_TXD1")
	)
	(segment
		(start 57.267856 -155.308554)
		(end 57.267856 -153.246836)
		(width 0.127)
		(layer "F.Cu")
		(net "MAC2_TXD1")
	)
	(segment
		(start 60.4012 -159.9692)
		(end 60.9219 -159.4485)
		(width 0.127)
		(layer "F.Cu")
		(net "MAC2_TXD1")
	)
	(segment
		(start 60.452 -157.9245)
		(end 59.9948 -157.4673)
		(width 0.127)
		(layer "F.Cu")
		(net "MAC2_TXD1")
	)
	(segment
		(start 56.252618 -152.231598)
		(end 55.73141 -152.231598)
		(width 0.127)
		(layer "F.Cu")
		(net "MAC2_TXD1")
	)
	(segment
		(start 57.267856 -153.246836)
		(end 56.252618 -152.231598)
		(width 0.127)
		(layer "F.Cu")
		(net "MAC2_TXD1")
	)
	(segment
		(start 59.9821 -161.1122)
		(end 59.9821 -160.3883)
		(width 0.127)
		(layer "F.Cu")
		(net "MAC2_TXD1")
	)
	(segment
		(start 58.905902 -156.9466)
		(end 57.267856 -155.308554)
		(width 0.127)
		(layer "F.Cu")
		(net "MAC2_TXD1")
	)
	(segment
		(start 59.9948 -157.4673)
		(end 59.279028 -157.4673)
		(width 0.127)
		(layer "F.Cu")
		(net "MAC2_TXD1")
	)
	(segment
		(start 59.279028 -157.4673)
		(end 58.905902 -157.094174)
		(width 0.127)
		(layer "F.Cu")
		(net "MAC2_TXD1")
	)
	(segment
		(start 55.73141 -152.231598)
		(end 55.299864 -151.800052)
		(width 0.127)
		(layer "F.Cu")
		(net "MAC2_TXD1")
	)
	(segment
		(start 60.9219 -159.4485)
		(end 60.9219 -158.3944)
		(width 0.127)
		(layer "F.Cu")
		(net "MAC2_TXD1")
	)
	(segment
		(start 58.905902 -157.094174)
		(end 58.905902 -156.9466)
		(width 0.127)
		(layer "F.Cu")
		(net "MAC2_TXD1")
	)
	(segment
		(start 59.9821 -160.3883)
		(end 60.4012 -159.9692)
		(width 0.127)
		(layer "F.Cu")
		(net "MAC2_TXD1")
	)
	(via
		(at 60.4012 -159.9692)
		(size 0.6604)
		(drill 0.3302)
		(layers "F.Cu" "B.Cu")
		(net "MAC2_TXD1")
	)
	(segment
		(start 59.436 -157.933136)
		(end 59.436 -157.9245)
		(width 0.127)
		(layer "F.Cu")
		(net "MAC2_TXD0")
	)
	(segment
		(start 58.801 -158.707328)
		(end 58.801 -158.568136)
		(width 0.127)
		(layer "F.Cu")
		(net "MAC2_TXD0")
	)
	(segment
		(start 58.283856 -157.978856)
		(end 58.283856 -158.976568)
		(width 0.127)
		(layer "F.Cu")
		(net "MAC2_TXD0")
	)
	(segment
		(start 58.407808 -159.10052)
		(end 58.801 -158.707328)
		(width 0.127)
		(layer "F.Cu")
		(net "MAC2_TXD0")
	)
	(segment
		(start 57.4802 -157.1752)
		(end 58.283856 -157.978856)
		(width 0.127)
		(layer "F.Cu")
		(net "MAC2_TXD0")
	)
	(segment
		(start 57.4802 -157.1752)
		(end 56.9468 -156.6418)
		(width 0.127)
		(layer "F.Cu")
		(net "MAC2_TXD0")
	)
	(segment
		(start 58.801 -158.568136)
		(end 59.436 -157.933136)
		(width 0.127)
		(layer "F.Cu")
		(net "MAC2_TXD0")
	)
	(segment
		(start 56.9468 -156.6418)
		(end 56.9468 -153.446734)
		(width 0.127)
		(layer "F.Cu")
		(net "MAC2_TXD0")
	)
	(segment
		(start 56.9468 -153.446734)
		(end 56.099964 -152.599898)
		(width 0.127)
		(layer "F.Cu")
		(net "MAC2_TXD0")
	)
	(segment
		(start 58.283856 -158.976568)
		(end 58.407808 -159.10052)
		(width 0.127)
		(layer "F.Cu")
		(net "MAC2_TXD0")
	)
	(via
		(at 57.4802 -157.1752)
		(size 0.6604)
		(drill 0.3302)
		(layers "F.Cu" "B.Cu")
		(net "MAC2_TXD0")
	)
	(segment
		(start 57.3786 -158.4071)
		(end 56.3626 -158.4071)
		(width 0.127)
		(layer "F.Cu")
		(net "MAC2_TXCTL")
	)
	(segment
		(start 55.2704 -157.6578)
		(end 55.2704 -155.697936)
		(width 0.127)
		(layer "F.Cu")
		(net "MAC2_TXCTL")
	)
	(segment
		(start 55.2704 -155.697936)
		(end 54.9148 -155.342336)
		(width 0.127)
		(layer "F.Cu")
		(net "MAC2_TXCTL")
	)
	(segment
		(start 56.0197 -158.4071)
		(end 55.2704 -157.6578)
		(width 0.127)
		(layer "F.Cu")
		(net "MAC2_TXCTL")
	)
	(segment
		(start 54.9148 -155.342336)
		(end 54.9148 -153.785062)
		(width 0.127)
		(layer "F.Cu")
		(net "MAC2_TXCTL")
	)
	(segment
		(start 54.9148 -153.785062)
		(end 55.299864 -153.399998)
		(width 0.127)
		(layer "F.Cu")
		(net "MAC2_TXCTL")
	)
	(segment
		(start 56.3626 -158.4071)
		(end 56.0197 -158.4071)
		(width 0.127)
		(layer "F.Cu")
		(net "MAC2_TXCTL")
	)
	(via
		(at 55.2704 -157.6578)
		(size 0.6604)
		(drill 0.3302)
		(layers "F.Cu" "B.Cu")
		(net "MAC2_TXCTL")
	)
	(segment
		(start 53.299868 -148.999702)
		(end 53.300122 -148.999702)
		(width 0.127)
		(layer "F.Cu")
		(net "MAC1_TXD3")
	)
	(segment
		(start 53.300122 -148.999702)
		(end 53.699918 -148.599906)
		(width 0.127)
		(layer "F.Cu")
		(net "MAC1_TXD3")
	)
	(via
		(at 59.064144 -149.371812)
		(size 0.6096)
		(drill 0.3048)
		(layers "F.Cu" "B.Cu")
		(net "MAC1_TXD3")
	)
	(via
		(at 53.299868 -148.999702)
		(size 0.4572)
		(drill 0.2032)
		(layers "F.Cu" "B.Cu")
		(net "MAC1_TXD3")
	)
	(segment
		(start 59.477656 -148.9583)
		(end 59.064144 -149.371812)
		(width 0.127)
		(layer "B.Cu")
		(net "MAC1_TXD3")
	)
	(segment
		(start 53.706014 -149.405848)
		(end 53.299868 -148.999702)
		(width 0.127)
		(layer "B.Cu")
		(net "MAC1_TXD3")
	)
	(segment
		(start 58.626756 -149.8092)
		(end 55.466488 -149.8092)
		(width 0.127)
		(layer "B.Cu")
		(net "MAC1_TXD3")
	)
	(segment
		(start 60.4774 -148.9583)
		(end 59.477656 -148.9583)
		(width 0.127)
		(layer "B.Cu")
		(net "MAC1_TXD3")
	)
	(segment
		(start 55.466488 -149.8092)
		(end 55.063136 -149.405848)
		(width 0.127)
		(layer "B.Cu")
		(net "MAC1_TXD3")
	)
	(segment
		(start 59.064144 -149.371812)
		(end 58.626756 -149.8092)
		(width 0.127)
		(layer "B.Cu")
		(net "MAC1_TXD3")
	)
	(segment
		(start 55.063136 -149.405848)
		(end 53.706014 -149.405848)
		(width 0.127)
		(layer "B.Cu")
		(net "MAC1_TXD3")
	)
	(segment
		(start 61.4934 -148.9583)
		(end 60.4774 -148.9583)
		(width 0.127)
		(layer "B.Cu")
		(net "MAC1_TXD3")
	)
	(segment
		(start 52.899818 -148.599906)
		(end 52.499768 -148.999956)
		(width 0.127)
		(layer "F.Cu")
		(net "MAC1_TXD2")
	)
	(via
		(at 52.499768 -148.999956)
		(size 0.4572)
		(drill 0.2032)
		(layers "F.Cu" "B.Cu")
		(net "MAC1_TXD2")
	)
	(via
		(at 54.8386 -151.257)
		(size 0.6096)
		(drill 0.3048)
		(layers "F.Cu" "B.Cu")
		(net "MAC1_TXD2")
	)
	(segment
		(start 55.660544 -151.257)
		(end 56.244744 -150.6728)
		(width 0.127)
		(layer "B.Cu")
		(net "MAC1_TXD2")
	)
	(segment
		(start 54.548278 -150.966678)
		(end 54.548278 -150.490682)
		(width 0.127)
		(layer "B.Cu")
		(net "MAC1_TXD2")
	)
	(segment
		(start 52.499768 -149.165056)
		(end 52.499768 -148.999956)
		(width 0.127)
		(layer "B.Cu")
		(net "MAC1_TXD2")
	)
	(segment
		(start 52.899818 -149.956774)
		(end 52.899818 -149.565106)
		(width 0.127)
		(layer "B.Cu")
		(net "MAC1_TXD2")
	)
	(segment
		(start 53.148992 -150.205948)
		(end 52.899818 -149.956774)
		(width 0.127)
		(layer "B.Cu")
		(net "MAC1_TXD2")
	)
	(segment
		(start 54.8386 -151.257)
		(end 54.548278 -150.966678)
		(width 0.127)
		(layer "B.Cu")
		(net "MAC1_TXD2")
	)
	(segment
		(start 56.244744 -150.6728)
		(end 56.6293 -150.6728)
		(width 0.127)
		(layer "B.Cu")
		(net "MAC1_TXD2")
	)
	(segment
		(start 54.263544 -150.205948)
		(end 53.148992 -150.205948)
		(width 0.127)
		(layer "B.Cu")
		(net "MAC1_TXD2")
	)
	(segment
		(start 54.8386 -151.257)
		(end 55.660544 -151.257)
		(width 0.127)
		(layer "B.Cu")
		(net "MAC1_TXD2")
	)
	(segment
		(start 56.6293 -151.6888)
		(end 56.6293 -150.6728)
		(width 0.127)
		(layer "B.Cu")
		(net "MAC1_TXD2")
	)
	(segment
		(start 52.899818 -149.565106)
		(end 52.499768 -149.165056)
		(width 0.127)
		(layer "B.Cu")
		(net "MAC1_TXD2")
	)
	(segment
		(start 54.548278 -150.490682)
		(end 54.263544 -150.205948)
		(width 0.127)
		(layer "B.Cu")
		(net "MAC1_TXD2")
	)
	(segment
		(start 54.500018 -138.199876)
		(end 54.500018 -138.199622)
		(width 0.127)
		(layer "F.Cu")
		(net "M2_2_PRESENT_N")
	)
	(segment
		(start 166.834058 -132.507482)
		(end 166.838884 -132.512308)
		(width 0.127)
		(layer "F.Cu")
		(net "M2_2_PRESENT_N")
	)
	(segment
		(start 166.064184 -132.507482)
		(end 166.834058 -132.507482)
		(width 0.127)
		(layer "F.Cu")
		(net "M2_2_PRESENT_N")
	)
	(segment
		(start 166.073582 -133.555994)
		(end 166.073582 -132.51688)
		(width 0.127)
		(layer "F.Cu")
		(net "M2_2_PRESENT_N")
	)
	(segment
		(start 54.500018 -138.199622)
		(end 54.899814 -137.799826)
		(width 0.127)
		(layer "F.Cu")
		(net "M2_2_PRESENT_N")
	)
	(segment
		(start 166.073582 -132.51688)
		(end 166.064184 -132.507482)
		(width 0.127)
		(layer "F.Cu")
		(net "M2_2_PRESENT_N")
	)
	(via
		(at 60.0456 -111.9632)
		(size 0.508)
		(drill 0.254)
		(layers "F.Cu" "B.Cu")
		(net "M2_2_PRESENT_N")
	)
	(via
		(at 54.899814 -137.799826)
		(size 0.4572)
		(drill 0.2032)
		(layers "F.Cu" "B.Cu")
		(net "M2_2_PRESENT_N")
	)
	(via
		(at 177.457354 -108.75391)
		(size 0.508)
		(drill 0.254)
		(layers "F.Cu" "B.Cu")
		(net "M2_2_PRESENT_N")
	)
	(via
		(at 166.838884 -132.512308)
		(size 0.508)
		(drill 0.254)
		(layers "F.Cu" "B.Cu")
		(net "M2_2_PRESENT_N")
	)
	(segment
		(start 166.838884 -131.557014)
		(end 166.838884 -132.512308)
		(width 0.127)
		(layer "B.Cu")
		(net "M2_2_PRESENT_N")
	)
	(segment
		(start 172.16374 -111.75746)
		(end 172.16374 -116.353844)
		(width 0.127)
		(layer "B.Cu")
		(net "M2_2_PRESENT_N")
	)
	(segment
		(start 167.756078 -120.761506)
		(end 167.756078 -130.63982)
		(width 0.127)
		(layer "B.Cu")
		(net "M2_2_PRESENT_N")
	)
	(segment
		(start 175.16729 -108.75391)
		(end 172.16374 -111.75746)
		(width 0.127)
		(layer "B.Cu")
		(net "M2_2_PRESENT_N")
	)
	(segment
		(start 177.457354 -108.75391)
		(end 175.16729 -108.75391)
		(width 0.127)
		(layer "B.Cu")
		(net "M2_2_PRESENT_N")
	)
	(segment
		(start 167.756078 -130.63982)
		(end 166.838884 -131.557014)
		(width 0.127)
		(layer "B.Cu")
		(net "M2_2_PRESENT_N")
	)
	(segment
		(start 172.16374 -116.353844)
		(end 167.756078 -120.761506)
		(width 0.127)
		(layer "B.Cu")
		(net "M2_2_PRESENT_N")
	)
	(segment
		(start 56.84774 -130.549142)
		(end 54.899814 -132.497068)
		(width 0.127)
		(layer "In2.Cu")
		(net "M2_2_PRESENT_N")
	)
	(segment
		(start 60.0456 -111.9632)
		(end 60.0456 -113.902998)
		(width 0.127)
		(layer "In2.Cu")
		(net "M2_2_PRESENT_N")
	)
	(segment
		(start 57.9247 -116.323618)
		(end 56.67375 -117.574568)
		(width 0.127)
		(layer "In2.Cu")
		(net "M2_2_PRESENT_N")
	)
	(segment
		(start 56.67375 -117.574568)
		(end 56.67375 -125.284738)
		(width 0.127)
		(layer "In2.Cu")
		(net "M2_2_PRESENT_N")
	)
	(segment
		(start 57.9247 -116.023898)
		(end 57.9247 -116.323618)
		(width 0.127)
		(layer "In2.Cu")
		(net "M2_2_PRESENT_N")
	)
	(segment
		(start 56.67375 -125.284738)
		(end 56.84774 -125.458728)
		(width 0.127)
		(layer "In2.Cu")
		(net "M2_2_PRESENT_N")
	)
	(segment
		(start 56.84774 -125.458728)
		(end 56.84774 -130.549142)
		(width 0.127)
		(layer "In2.Cu")
		(net "M2_2_PRESENT_N")
	)
	(segment
		(start 60.0456 -113.902998)
		(end 57.9247 -116.023898)
		(width 0.127)
		(layer "In2.Cu")
		(net "M2_2_PRESENT_N")
	)
	(segment
		(start 54.899814 -132.497068)
		(end 54.899814 -137.799826)
		(width 0.127)
		(layer "In2.Cu")
		(net "M2_2_PRESENT_N")
	)
	(segment
		(start 75.8317 -99.170744)
		(end 75.8317 -48.692308)
		(width 0.127)
		(layer "In5.Cu")
		(net "M2_2_PRESENT_N")
	)
	(segment
		(start 174.42053 -3.9751)
		(end 180.034438 -9.589008)
		(width 0.127)
		(layer "In5.Cu")
		(net "M2_2_PRESENT_N")
	)
	(segment
		(start 211.71662 -88.44915)
		(end 211.71662 -100.304346)
		(width 0.127)
		(layer "In5.Cu")
		(net "M2_2_PRESENT_N")
	)
	(segment
		(start 180.034438 -9.589008)
		(end 207.191102 -9.589008)
		(width 0.127)
		(layer "In5.Cu")
		(net "M2_2_PRESENT_N")
	)
	(segment
		(start 211.71662 -100.304346)
		(end 207.982058 -104.038908)
		(width 0.127)
		(layer "In5.Cu")
		(net "M2_2_PRESENT_N")
	)
	(segment
		(start 75.8317 -48.692308)
		(end 76.873608 -47.6504)
		(width 0.127)
		(layer "In5.Cu")
		(net "M2_2_PRESENT_N")
	)
	(segment
		(start 66.3702 -112.7506)
		(end 73.93813 -112.7506)
		(width 0.127)
		(layer "In5.Cu")
		(net "M2_2_PRESENT_N")
	)
	(segment
		(start 81.13649 -101.9048)
		(end 78.565756 -101.9048)
		(width 0.127)
		(layer "In5.Cu")
		(net "M2_2_PRESENT_N")
	)
	(segment
		(start 211.704682 -84.886292)
		(end 212.640164 -85.821774)
		(width 0.127)
		(layer "In5.Cu")
		(net "M2_2_PRESENT_N")
	)
	(segment
		(start 81.818988 -10.992612)
		(end 84.417408 -8.394192)
		(width 0.127)
		(layer "In5.Cu")
		(net "M2_2_PRESENT_N")
	)
	(segment
		(start 73.93813 -112.7506)
		(end 77.64653 -109.0422)
		(width 0.127)
		(layer "In5.Cu")
		(net "M2_2_PRESENT_N")
	)
	(segment
		(start 180.970174 -104.038908)
		(end 177.457354 -107.551728)
		(width 0.127)
		(layer "In5.Cu")
		(net "M2_2_PRESENT_N")
	)
	(segment
		(start 97.3328 -3.9751)
		(end 174.42053 -3.9751)
		(width 0.127)
		(layer "In5.Cu")
		(net "M2_2_PRESENT_N")
	)
	(segment
		(start 212.640164 -85.821774)
		(end 212.640164 -87.525606)
		(width 0.127)
		(layer "In5.Cu")
		(net "M2_2_PRESENT_N")
	)
	(segment
		(start 207.982058 -104.038908)
		(end 180.970174 -104.038908)
		(width 0.127)
		(layer "In5.Cu")
		(net "M2_2_PRESENT_N")
	)
	(segment
		(start 66.1924 -112.9284)
		(end 66.3702 -112.7506)
		(width 0.127)
		(layer "In5.Cu")
		(net "M2_2_PRESENT_N")
	)
	(segment
		(start 61.0108 -112.9284)
		(end 66.1924 -112.9284)
		(width 0.127)
		(layer "In5.Cu")
		(net "M2_2_PRESENT_N")
	)
	(segment
		(start 78.6892 -43.599354)
		(end 81.819242 -40.469312)
		(width 0.127)
		(layer "In5.Cu")
		(net "M2_2_PRESENT_N")
	)
	(segment
		(start 81.819242 -40.469312)
		(end 81.819242 -11.308334)
		(width 0.127)
		(layer "In5.Cu")
		(net "M2_2_PRESENT_N")
	)
	(segment
		(start 78.565756 -101.9048)
		(end 75.8317 -99.170744)
		(width 0.127)
		(layer "In5.Cu")
		(net "M2_2_PRESENT_N")
	)
	(segment
		(start 60.0456 -111.9632)
		(end 61.0108 -112.9284)
		(width 0.127)
		(layer "In5.Cu")
		(net "M2_2_PRESENT_N")
	)
	(segment
		(start 92.913708 -8.394192)
		(end 97.3328 -3.9751)
		(width 0.127)
		(layer "In5.Cu")
		(net "M2_2_PRESENT_N")
	)
	(segment
		(start 78.1558 -47.6504)
		(end 78.6892 -47.117)
		(width 0.127)
		(layer "In5.Cu")
		(net "M2_2_PRESENT_N")
	)
	(segment
		(start 84.417408 -8.394192)
		(end 92.913708 -8.394192)
		(width 0.127)
		(layer "In5.Cu")
		(net "M2_2_PRESENT_N")
	)
	(segment
		(start 211.704682 -14.102588)
		(end 211.704682 -84.886292)
		(width 0.127)
		(layer "In5.Cu")
		(net "M2_2_PRESENT_N")
	)
	(segment
		(start 76.873608 -47.6504)
		(end 78.1558 -47.6504)
		(width 0.127)
		(layer "In5.Cu")
		(net "M2_2_PRESENT_N")
	)
	(segment
		(start 177.457354 -107.551728)
		(end 177.457354 -108.75391)
		(width 0.127)
		(layer "In5.Cu")
		(net "M2_2_PRESENT_N")
	)
	(segment
		(start 81.819242 -11.308334)
		(end 81.818988 -11.30808)
		(width 0.127)
		(layer "In5.Cu")
		(net "M2_2_PRESENT_N")
	)
	(segment
		(start 81.818988 -11.30808)
		(end 81.818988 -10.992612)
		(width 0.127)
		(layer "In5.Cu")
		(net "M2_2_PRESENT_N")
	)
	(segment
		(start 78.6892 -47.117)
		(end 78.6892 -43.599354)
		(width 0.127)
		(layer "In5.Cu")
		(net "M2_2_PRESENT_N")
	)
	(segment
		(start 212.640164 -87.525606)
		(end 211.71662 -88.44915)
		(width 0.127)
		(layer "In5.Cu")
		(net "M2_2_PRESENT_N")
	)
	(segment
		(start 77.64653 -109.0422)
		(end 79.959454 -109.0422)
		(width 0.127)
		(layer "In5.Cu")
		(net "M2_2_PRESENT_N")
	)
	(segment
		(start 83.284314 -105.71734)
		(end 83.284314 -104.052624)
		(width 0.127)
		(layer "In5.Cu")
		(net "M2_2_PRESENT_N")
	)
	(segment
		(start 207.191102 -9.589008)
		(end 211.704682 -14.102588)
		(width 0.127)
		(layer "In5.Cu")
		(net "M2_2_PRESENT_N")
	)
	(segment
		(start 79.959454 -109.0422)
		(end 83.284314 -105.71734)
		(width 0.127)
		(layer "In5.Cu")
		(net "M2_2_PRESENT_N")
	)
	(segment
		(start 83.284314 -104.052624)
		(end 81.13649 -101.9048)
		(width 0.127)
		(layer "In5.Cu")
		(net "M2_2_PRESENT_N")
	)
	(segment
		(start 182.884318 -121.580656)
		(end 182.884318 -122.722132)
		(width 0.127)
		(layer "F.Cu")
		(net "M2_2_CLKREQ#")
	)
	(segment
		(start 182.884318 -122.722132)
		(end 182.883556 -122.722894)
		(width 0.127)
		(layer "F.Cu")
		(net "M2_2_CLKREQ#")
	)
	(segment
		(start 182.883556 -122.722894)
		(end 182.883556 -127.308356)
		(width 0.127)
		(layer "F.Cu")
		(net "M2_2_CLKREQ#")
	)
	(segment
		(start 182.883556 -127.308356)
		(end 182.900066 -127.324866)
		(width 0.127)
		(layer "F.Cu")
		(net "M2_2_CLKREQ#")
	)
	(via
		(at 182.884318 -122.722132)
		(size 0.6604)
		(drill 0.3302)
		(layers "F.Cu" "B.Cu")
		(net "M2_2_CLKREQ#")
	)
	(segment
		(start 120.2944 -27.5082)
		(end 119.758714 -27.5082)
		(width 0.127)
		(layer "F.Cu")
		(net "M2_2_ALERT#")
	)
	(segment
		(start 119.758714 -27.5082)
		(end 117.345714 -29.9212)
		(width 0.127)
		(layer "F.Cu")
		(net "M2_2_ALERT#")
	)
	(segment
		(start 117.345714 -29.9212)
		(end 116.078 -29.9212)
		(width 0.127)
		(layer "F.Cu")
		(net "M2_2_ALERT#")
	)
	(segment
		(start 180.90007 -125.805184)
		(end 180.90007 -127.324866)
		(width 0.127)
		(layer "F.Cu")
		(net "M2_2_ALERT#")
	)
	(segment
		(start 181.064154 -121.496328)
		(end 181.064154 -122.704606)
		(width 0.127)
		(layer "F.Cu")
		(net "M2_2_ALERT#")
	)
	(segment
		(start 181.064154 -122.704606)
		(end 181.064154 -125.6411)
		(width 0.127)
		(layer "F.Cu")
		(net "M2_2_ALERT#")
	)
	(segment
		(start 181.064154 -121.496328)
		(end 180.7718 -121.496328)
		(width 0.127)
		(layer "F.Cu")
		(net "M2_2_ALERT#")
	)
	(segment
		(start 181.064154 -125.6411)
		(end 180.90007 -125.805184)
		(width 0.127)
		(layer "F.Cu")
		(net "M2_2_ALERT#")
	)
	(segment
		(start 180.7718 -121.496328)
		(end 180.2638 -122.004328)
		(width 0.127)
		(layer "F.Cu")
		(net "M2_2_ALERT#")
	)
	(via
		(at 94.877636 -117.55882)
		(size 0.508)
		(drill 0.254)
		(layers "F.Cu" "B.Cu")
		(net "M2_2_ALERT#")
	)
	(via
		(at 50.3428 -123.571)
		(size 0.508)
		(drill 0.254)
		(layers "F.Cu" "B.Cu")
		(net "M2_2_ALERT#")
	)
	(via
		(at 116.078 -29.9212)
		(size 0.508)
		(drill 0.254)
		(layers "F.Cu" "B.Cu")
		(net "M2_2_ALERT#")
	)
	(via
		(at 180.2638 -122.004328)
		(size 0.508)
		(drill 0.254)
		(layers "F.Cu" "B.Cu")
		(net "M2_2_ALERT#")
	)
	(via
		(at 181.064154 -122.704606)
		(size 0.6604)
		(drill 0.3302)
		(layers "F.Cu" "B.Cu")
		(net "M2_2_ALERT#")
	)
	(via
		(at 120.2944 -27.5082)
		(size 0.508)
		(drill 0.254)
		(layers "F.Cu" "B.Cu")
		(net "M2_2_ALERT#")
	)
	(via
		(at 101.1047 -41.148)
		(size 0.508)
		(drill 0.254)
		(layers "F.Cu" "B.Cu")
		(net "M2_2_ALERT#")
	)
	(segment
		(start 96.7486 -96.120966)
		(end 96.7486 -114.6302)
		(width 0.127)
		(layer "B.Cu")
		(net "M2_2_ALERT#")
	)
	(segment
		(start 92.49156 -82.227674)
		(end 92.49156 -91.863926)
		(width 0.127)
		(layer "B.Cu")
		(net "M2_2_ALERT#")
	)
	(segment
		(start 100.218748 -43.697652)
		(end 100.218748 -74.500486)
		(width 0.127)
		(layer "B.Cu")
		(net "M2_2_ALERT#")
	)
	(segment
		(start 100.5332 -41.7195)
		(end 100.5332 -43.3832)
		(width 0.127)
		(layer "B.Cu")
		(net "M2_2_ALERT#")
	)
	(segment
		(start 50.8635 -124.333)
		(end 50.8635 -124.0917)
		(width 0.127)
		(layer "B.Cu")
		(net "M2_2_ALERT#")
	)
	(segment
		(start 100.218748 -74.500486)
		(end 92.49156 -82.227674)
		(width 0.127)
		(layer "B.Cu")
		(net "M2_2_ALERT#")
	)
	(segment
		(start 92.49156 -91.863926)
		(end 96.7486 -96.120966)
		(width 0.127)
		(layer "B.Cu")
		(net "M2_2_ALERT#")
	)
	(segment
		(start 94.87662 -117.557804)
		(end 94.877636 -117.55882)
		(width 0.127)
		(layer "B.Cu")
		(net "M2_2_ALERT#")
	)
	(segment
		(start 101.1047 -41.148)
		(end 100.5332 -41.7195)
		(width 0.127)
		(layer "B.Cu")
		(net "M2_2_ALERT#")
	)
	(segment
		(start 50.8635 -124.0917)
		(end 50.3428 -123.571)
		(width 0.127)
		(layer "B.Cu")
		(net "M2_2_ALERT#")
	)
	(segment
		(start 100.5332 -43.3832)
		(end 100.218748 -43.697652)
		(width 0.127)
		(layer "B.Cu")
		(net "M2_2_ALERT#")
	)
	(segment
		(start 96.7486 -114.6302)
		(end 94.87662 -116.50218)
		(width 0.127)
		(layer "B.Cu")
		(net "M2_2_ALERT#")
	)
	(segment
		(start 94.87662 -116.50218)
		(end 94.87662 -117.557804)
		(width 0.127)
		(layer "B.Cu")
		(net "M2_2_ALERT#")
	)
	(segment
		(start 112.853724 -26.899616)
		(end 115.875308 -29.9212)
		(width 0.127)
		(layer "In2.Cu")
		(net "M2_2_ALERT#")
	)
	(segment
		(start 100.584 -36.7284)
		(end 101.549962 -35.762438)
		(width 0.127)
		(layer "In2.Cu")
		(net "M2_2_ALERT#")
	)
	(segment
		(start 105.56367 -26.899616)
		(end 112.853724 -26.899616)
		(width 0.127)
		(layer "In2.Cu")
		(net "M2_2_ALERT#")
	)
	(segment
		(start 115.875308 -29.9212)
		(end 116.078 -29.9212)
		(width 0.127)
		(layer "In2.Cu")
		(net "M2_2_ALERT#")
	)
	(segment
		(start 101.549962 -35.762438)
		(end 101.549962 -30.913324)
		(width 0.127)
		(layer "In2.Cu")
		(net "M2_2_ALERT#")
	)
	(segment
		(start 100.584 -40.6273)
		(end 100.584 -36.7284)
		(width 0.127)
		(layer "In2.Cu")
		(net "M2_2_ALERT#")
	)
	(segment
		(start 101.1047 -41.148)
		(end 100.584 -40.6273)
		(width 0.127)
		(layer "In2.Cu")
		(net "M2_2_ALERT#")
	)
	(segment
		(start 101.549962 -30.913324)
		(end 105.56367 -26.899616)
		(width 0.127)
		(layer "In2.Cu")
		(net "M2_2_ALERT#")
	)
	(segment
		(start 55.8546 -119.9642)
		(end 62.694566 -119.9642)
		(width 0.127)
		(layer "In5.Cu")
		(net "M2_2_ALERT#")
	)
	(segment
		(start 129.7178 -20.428966)
		(end 132.260086 -17.88668)
		(width 0.127)
		(layer "In5.Cu")
		(net "M2_2_ALERT#")
	)
	(segment
		(start 67.152774 -119.507)
		(end 72.391524 -119.507)
		(width 0.127)
		(layer "In5.Cu")
		(net "M2_2_ALERT#")
	)
	(segment
		(start 63.53302 -120.802654)
		(end 65.85712 -120.802654)
		(width 0.127)
		(layer "In5.Cu")
		(net "M2_2_ALERT#")
	)
	(segment
		(start 84.6328 -114.3)
		(end 85.8266 -115.4938)
		(width 0.127)
		(layer "In5.Cu")
		(net "M2_2_ALERT#")
	)
	(segment
		(start 127.947166 -23.2156)
		(end 129.7178 -21.444966)
		(width 0.127)
		(layer "In5.Cu")
		(net "M2_2_ALERT#")
	)
	(segment
		(start 77.598524 -114.3)
		(end 84.6328 -114.3)
		(width 0.127)
		(layer "In5.Cu")
		(net "M2_2_ALERT#")
	)
	(segment
		(start 129.7178 -21.444966)
		(end 129.7178 -20.428966)
		(width 0.127)
		(layer "In5.Cu")
		(net "M2_2_ALERT#")
	)
	(segment
		(start 173.576488 -39.470584)
		(end 173.576488 -95.215964)
		(width 0.127)
		(layer "In5.Cu")
		(net "M2_2_ALERT#")
	)
	(segment
		(start 172.466 -117.4496)
		(end 172.466 -120.269)
		(width 0.127)
		(layer "In5.Cu")
		(net "M2_2_ALERT#")
	)
	(segment
		(start 72.391524 -119.507)
		(end 77.598524 -114.3)
		(width 0.127)
		(layer "In5.Cu")
		(net "M2_2_ALERT#")
	)
	(segment
		(start 87.8586 -117.5258)
		(end 94.844616 -117.5258)
		(width 0.127)
		(layer "In5.Cu")
		(net "M2_2_ALERT#")
	)
	(segment
		(start 132.260086 -17.88668)
		(end 143.4465 -17.88668)
		(width 0.127)
		(layer "In5.Cu")
		(net "M2_2_ALERT#")
	)
	(segment
		(start 50.3428 -123.571)
		(end 50.3428 -123.5202)
		(width 0.127)
		(layer "In5.Cu")
		(net "M2_2_ALERT#")
	)
	(segment
		(start 86.124034 -115.824)
		(end 86.1568 -115.824)
		(width 0.127)
		(layer "In5.Cu")
		(net "M2_2_ALERT#")
	)
	(segment
		(start 52.832254 -121.031)
		(end 54.7878 -121.031)
		(width 0.127)
		(layer "In5.Cu")
		(net "M2_2_ALERT#")
	)
	(segment
		(start 65.85712 -120.802654)
		(end 67.152774 -119.507)
		(width 0.127)
		(layer "In5.Cu")
		(net "M2_2_ALERT#")
	)
	(segment
		(start 62.694566 -119.9642)
		(end 63.53302 -120.802654)
		(width 0.127)
		(layer "In5.Cu")
		(net "M2_2_ALERT#")
	)
	(segment
		(start 86.1568 -115.824)
		(end 87.8586 -117.5258)
		(width 0.127)
		(layer "In5.Cu")
		(net "M2_2_ALERT#")
	)
	(segment
		(start 52.7558 -121.1072)
		(end 52.756054 -121.1072)
		(width 0.127)
		(layer "In5.Cu")
		(net "M2_2_ALERT#")
	)
	(segment
		(start 94.844616 -117.5258)
		(end 94.877636 -117.55882)
		(width 0.127)
		(layer "In5.Cu")
		(net "M2_2_ALERT#")
	)
	(segment
		(start 177.426366 -124.206)
		(end 179.628038 -122.004328)
		(width 0.127)
		(layer "In5.Cu")
		(net "M2_2_ALERT#")
	)
	(segment
		(start 179.628038 -122.004328)
		(end 180.2638 -122.004328)
		(width 0.127)
		(layer "In5.Cu")
		(net "M2_2_ALERT#")
	)
	(segment
		(start 120.2944 -27.5082)
		(end 124.587 -23.2156)
		(width 0.127)
		(layer "In5.Cu")
		(net "M2_2_ALERT#")
	)
	(segment
		(start 173.99 -95.629476)
		(end 173.99 -115.9256)
		(width 0.127)
		(layer "In5.Cu")
		(net "M2_2_ALERT#")
	)
	(segment
		(start 153.99766 -17.98066)
		(end 153.99766 -19.891756)
		(width 0.127)
		(layer "In5.Cu")
		(net "M2_2_ALERT#")
	)
	(segment
		(start 143.4465 -17.88668)
		(end 145.258536 -16.074644)
		(width 0.127)
		(layer "In5.Cu")
		(net "M2_2_ALERT#")
	)
	(segment
		(start 145.258536 -16.074644)
		(end 152.091644 -16.074644)
		(width 0.127)
		(layer "In5.Cu")
		(net "M2_2_ALERT#")
	)
	(segment
		(start 152.091644 -16.074644)
		(end 153.99766 -17.98066)
		(width 0.127)
		(layer "In5.Cu")
		(net "M2_2_ALERT#")
	)
	(segment
		(start 85.8266 -115.526566)
		(end 86.124034 -115.824)
		(width 0.127)
		(layer "In5.Cu")
		(net "M2_2_ALERT#")
	)
	(segment
		(start 50.3428 -123.5202)
		(end 52.7558 -121.1072)
		(width 0.127)
		(layer "In5.Cu")
		(net "M2_2_ALERT#")
	)
	(segment
		(start 85.8266 -115.4938)
		(end 85.8266 -115.526566)
		(width 0.127)
		(layer "In5.Cu")
		(net "M2_2_ALERT#")
	)
	(segment
		(start 173.576488 -95.215964)
		(end 173.99 -95.629476)
		(width 0.127)
		(layer "In5.Cu")
		(net "M2_2_ALERT#")
	)
	(segment
		(start 52.756054 -121.1072)
		(end 52.832254 -121.031)
		(width 0.127)
		(layer "In5.Cu")
		(net "M2_2_ALERT#")
	)
	(segment
		(start 172.466 -120.269)
		(end 176.403 -124.206)
		(width 0.127)
		(layer "In5.Cu")
		(net "M2_2_ALERT#")
	)
	(segment
		(start 153.99766 -19.891756)
		(end 173.576488 -39.470584)
		(width 0.127)
		(layer "In5.Cu")
		(net "M2_2_ALERT#")
	)
	(segment
		(start 173.99 -115.9256)
		(end 172.466 -117.4496)
		(width 0.127)
		(layer "In5.Cu")
		(net "M2_2_ALERT#")
	)
	(segment
		(start 124.587 -23.2156)
		(end 127.947166 -23.2156)
		(width 0.127)
		(layer "In5.Cu")
		(net "M2_2_ALERT#")
	)
	(segment
		(start 176.403 -124.206)
		(end 177.426366 -124.206)
		(width 0.127)
		(layer "In5.Cu")
		(net "M2_2_ALERT#")
	)
	(segment
		(start 54.7878 -121.031)
		(end 55.8546 -119.9642)
		(width 0.127)
		(layer "In5.Cu")
		(net "M2_2_ALERT#")
	)
	(segment
		(start 55.699914 -137.799826)
		(end 55.299864 -138.199876)
		(width 0.127)
		(layer "F.Cu")
		(net "M2_1_PRESENT_N")
	)
	(via
		(at 172.7962 -4.445)
		(size 0.508)
		(drill 0.254)
		(layers "F.Cu" "B.Cu")
		(net "M2_1_PRESENT_N")
	)
	(via
		(at 61.1886 -111.9886)
		(size 0.508)
		(drill 0.254)
		(layers "F.Cu" "B.Cu")
		(net "M2_1_PRESENT_N")
	)
	(via
		(at 192.872868 -138.075162)
		(size 0.508)
		(drill 0.254)
		(layers "F.Cu" "B.Cu")
		(net "M2_1_PRESENT_N")
	)
	(via
		(at 55.699914 -137.799826)
		(size 0.4572)
		(drill 0.2032)
		(layers "F.Cu" "B.Cu")
		(net "M2_1_PRESENT_N")
	)
	(segment
		(start 82.3849 -32.03956)
		(end 84.336128 -33.990788)
		(width 0.127)
		(layer "B.Cu")
		(net "M2_1_PRESENT_N")
	)
	(segment
		(start 83.496658 -102.495858)
		(end 83.496658 -107.787694)
		(width 0.127)
		(layer "B.Cu")
		(net "M2_1_PRESENT_N")
	)
	(segment
		(start 191.777366 -137.434574)
		(end 191.777366 -136.834372)
		(width 0.127)
		(layer "B.Cu")
		(net "M2_1_PRESENT_N")
	)
	(segment
		(start 90.36304 -1.7907)
		(end 82.3849 -9.76884)
		(width 0.127)
		(layer "B.Cu")
		(net "M2_1_PRESENT_N")
	)
	(segment
		(start 192.872868 -138.075162)
		(end 192.417954 -138.075162)
		(width 0.127)
		(layer "B.Cu")
		(net "M2_1_PRESENT_N")
	)
	(segment
		(start 76.920344 -100.212144)
		(end 80.51165 -100.212144)
		(width 0.127)
		(layer "B.Cu")
		(net "M2_1_PRESENT_N")
	)
	(segment
		(start 80.219804 -110.119414)
		(end 74.871834 -110.119414)
		(width 0.127)
		(layer "B.Cu")
		(net "M2_1_PRESENT_N")
	)
	(segment
		(start 74.871834 -110.119414)
		(end 74.094848 -110.8964)
		(width 0.127)
		(layer "B.Cu")
		(net "M2_1_PRESENT_N")
	)
	(segment
		(start 83.496658 -107.787694)
		(end 82.315812 -108.96854)
		(width 0.127)
		(layer "B.Cu")
		(net "M2_1_PRESENT_N")
	)
	(segment
		(start 81.859882 -108.96854)
		(end 81.532222 -109.2962)
		(width 0.127)
		(layer "B.Cu")
		(net "M2_1_PRESENT_N")
	)
	(segment
		(start 81.043018 -109.2962)
		(end 80.219804 -110.119414)
		(width 0.127)
		(layer "B.Cu")
		(net "M2_1_PRESENT_N")
	)
	(segment
		(start 192.85077 -136.854438)
		(end 191.797432 -136.854438)
		(width 0.127)
		(layer "B.Cu")
		(net "M2_1_PRESENT_N")
	)
	(segment
		(start 80.51165 -100.212144)
		(end 81.112106 -100.8126)
		(width 0.127)
		(layer "B.Cu")
		(net "M2_1_PRESENT_N")
	)
	(segment
		(start 84.336128 -41.495472)
		(end 80.9371 -44.8945)
		(width 0.127)
		(layer "B.Cu")
		(net "M2_1_PRESENT_N")
	)
	(segment
		(start 82.3849 -9.76884)
		(end 82.3849 -32.03956)
		(width 0.127)
		(layer "B.Cu")
		(net "M2_1_PRESENT_N")
	)
	(segment
		(start 80.9371 -44.8945)
		(end 74.664062 -44.8945)
		(width 0.127)
		(layer "B.Cu")
		(net "M2_1_PRESENT_N")
	)
	(segment
		(start 84.336128 -33.990788)
		(end 84.336128 -41.495472)
		(width 0.127)
		(layer "B.Cu")
		(net "M2_1_PRESENT_N")
	)
	(segment
		(start 82.315812 -108.96854)
		(end 81.859882 -108.96854)
		(width 0.127)
		(layer "B.Cu")
		(net "M2_1_PRESENT_N")
	)
	(segment
		(start 73.85558 -97.14738)
		(end 76.920344 -100.212144)
		(width 0.127)
		(layer "B.Cu")
		(net "M2_1_PRESENT_N")
	)
	(segment
		(start 191.797432 -136.854438)
		(end 191.777366 -136.834372)
		(width 0.127)
		(layer "B.Cu")
		(net "M2_1_PRESENT_N")
	)
	(segment
		(start 74.094848 -110.8964)
		(end 62.2808 -110.8964)
		(width 0.127)
		(layer "B.Cu")
		(net "M2_1_PRESENT_N")
	)
	(segment
		(start 192.417954 -138.075162)
		(end 191.777366 -137.434574)
		(width 0.127)
		(layer "B.Cu")
		(net "M2_1_PRESENT_N")
	)
	(segment
		(start 74.664062 -44.8945)
		(end 73.85558 -45.702982)
		(width 0.127)
		(layer "B.Cu")
		(net "M2_1_PRESENT_N")
	)
	(segment
		(start 172.7962 -4.445)
		(end 172.791882 -4.445)
		(width 0.127)
		(layer "B.Cu")
		(net "M2_1_PRESENT_N")
	)
	(segment
		(start 81.8134 -100.8126)
		(end 83.496658 -102.495858)
		(width 0.127)
		(layer "B.Cu")
		(net "M2_1_PRESENT_N")
	)
	(segment
		(start 170.137582 -1.7907)
		(end 90.36304 -1.7907)
		(width 0.127)
		(layer "B.Cu")
		(net "M2_1_PRESENT_N")
	)
	(segment
		(start 172.791882 -4.445)
		(end 170.137582 -1.7907)
		(width 0.127)
		(layer "B.Cu")
		(net "M2_1_PRESENT_N")
	)
	(segment
		(start 62.2808 -110.8964)
		(end 61.1886 -111.9886)
		(width 0.127)
		(layer "B.Cu")
		(net "M2_1_PRESENT_N")
	)
	(segment
		(start 73.85558 -45.702982)
		(end 73.85558 -97.14738)
		(width 0.127)
		(layer "B.Cu")
		(net "M2_1_PRESENT_N")
	)
	(segment
		(start 81.112106 -100.8126)
		(end 81.8134 -100.8126)
		(width 0.127)
		(layer "B.Cu")
		(net "M2_1_PRESENT_N")
	)
	(segment
		(start 81.532222 -109.2962)
		(end 81.043018 -109.2962)
		(width 0.127)
		(layer "B.Cu")
		(net "M2_1_PRESENT_N")
	)
	(segment
		(start 170.953176 -106.201972)
		(end 164.29736 -99.546156)
		(width 0.127)
		(layer "In2.Cu")
		(net "M2_1_PRESENT_N")
	)
	(segment
		(start 61.1632 -112.014)
		(end 61.1632 -113.324386)
		(width 0.127)
		(layer "In2.Cu")
		(net "M2_1_PRESENT_N")
	)
	(segment
		(start 164.29736 -130.635502)
		(end 164.29736 -123.083066)
		(width 0.127)
		(layer "In2.Cu")
		(net "M2_1_PRESENT_N")
	)
	(segment
		(start 172.2501 -11.634978)
		(end 172.2501 -4.9911)
		(width 0.127)
		(layer "In2.Cu")
		(net "M2_1_PRESENT_N")
	)
	(segment
		(start 179.82438 -137.07618)
		(end 178.77536 -136.02716)
		(width 0.127)
		(layer "In2.Cu")
		(net "M2_1_PRESENT_N")
	)
	(segment
		(start 61.1886 -111.9886)
		(end 61.1632 -112.014)
		(width 0.127)
		(layer "In2.Cu")
		(net "M2_1_PRESENT_N")
	)
	(segment
		(start 58.4708 -125.3744)
		(end 58.4708 -127.783336)
		(width 0.127)
		(layer "In2.Cu")
		(net "M2_1_PRESENT_N")
	)
	(segment
		(start 55.699914 -132.973826)
		(end 55.699914 -137.799826)
		(width 0.127)
		(layer "In2.Cu")
		(net "M2_1_PRESENT_N")
	)
	(segment
		(start 164.29736 -19.587718)
		(end 172.2501 -11.634978)
		(width 0.127)
		(layer "In2.Cu")
		(net "M2_1_PRESENT_N")
	)
	(segment
		(start 192.433702 -138.075162)
		(end 191.43472 -137.07618)
		(width 0.127)
		(layer "In2.Cu")
		(net "M2_1_PRESENT_N")
	)
	(segment
		(start 164.29736 -99.546156)
		(end 164.29736 -19.587718)
		(width 0.127)
		(layer "In2.Cu")
		(net "M2_1_PRESENT_N")
	)
	(segment
		(start 178.77536 -136.02716)
		(end 169.689018 -136.02716)
		(width 0.127)
		(layer "In2.Cu")
		(net "M2_1_PRESENT_N")
	)
	(segment
		(start 59.6773 -129.684018)
		(end 59.402218 -129.9591)
		(width 0.127)
		(layer "In2.Cu")
		(net "M2_1_PRESENT_N")
	)
	(segment
		(start 59.6773 -128.989836)
		(end 59.6773 -129.684018)
		(width 0.127)
		(layer "In2.Cu")
		(net "M2_1_PRESENT_N")
	)
	(segment
		(start 59.402218 -129.9591)
		(end 58.71464 -129.9591)
		(width 0.127)
		(layer "In2.Cu")
		(net "M2_1_PRESENT_N")
	)
	(segment
		(start 170.953176 -116.42725)
		(end 170.953176 -106.201972)
		(width 0.127)
		(layer "In2.Cu")
		(net "M2_1_PRESENT_N")
	)
	(segment
		(start 191.43472 -137.07618)
		(end 179.82438 -137.07618)
		(width 0.127)
		(layer "In2.Cu")
		(net "M2_1_PRESENT_N")
	)
	(segment
		(start 58.3057 -116.181886)
		(end 58.3057 -125.2093)
		(width 0.127)
		(layer "In2.Cu")
		(net "M2_1_PRESENT_N")
	)
	(segment
		(start 172.2501 -4.9911)
		(end 172.7962 -4.445)
		(width 0.127)
		(layer "In2.Cu")
		(net "M2_1_PRESENT_N")
	)
	(segment
		(start 192.872868 -138.075162)
		(end 192.433702 -138.075162)
		(width 0.127)
		(layer "In2.Cu")
		(net "M2_1_PRESENT_N")
	)
	(segment
		(start 61.1632 -113.324386)
		(end 58.3057 -116.181886)
		(width 0.127)
		(layer "In2.Cu")
		(net "M2_1_PRESENT_N")
	)
	(segment
		(start 58.4708 -127.783336)
		(end 59.6773 -128.989836)
		(width 0.127)
		(layer "In2.Cu")
		(net "M2_1_PRESENT_N")
	)
	(segment
		(start 169.689018 -136.02716)
		(end 164.29736 -130.635502)
		(width 0.127)
		(layer "In2.Cu")
		(net "M2_1_PRESENT_N")
	)
	(segment
		(start 58.3057 -125.2093)
		(end 58.4708 -125.3744)
		(width 0.127)
		(layer "In2.Cu")
		(net "M2_1_PRESENT_N")
	)
	(segment
		(start 164.29736 -123.083066)
		(end 170.953176 -116.42725)
		(width 0.127)
		(layer "In2.Cu")
		(net "M2_1_PRESENT_N")
	)
	(segment
		(start 58.71464 -129.9591)
		(end 55.699914 -132.973826)
		(width 0.127)
		(layer "In2.Cu")
		(net "M2_1_PRESENT_N")
	)
	(segment
		(start 209.226912 -122.304048)
		(end 209.226912 -124.122688)
		(width 0.127)
		(layer "F.Cu")
		(net "M2_1_CLKREQ#")
	)
	(segment
		(start 209.226912 -124.122688)
		(end 207.900016 -125.449584)
		(width 0.127)
		(layer "F.Cu")
		(net "M2_1_CLKREQ#")
	)
	(segment
		(start 209.226912 -121.1707)
		(end 209.226912 -122.304048)
		(width 0.127)
		(layer "F.Cu")
		(net "M2_1_CLKREQ#")
	)
	(segment
		(start 207.900016 -125.449584)
		(end 207.900016 -127.324866)
		(width 0.127)
		(layer "F.Cu")
		(net "M2_1_CLKREQ#")
	)
	(via
		(at 209.226912 -122.304048)
		(size 0.6604)
		(drill 0.3302)
		(layers "F.Cu" "B.Cu")
		(net "M2_1_CLKREQ#")
	)
	(segment
		(start 119.705374 -26.842974)
		(end 119.486426 -26.842974)
		(width 0.127)
		(layer "F.Cu")
		(net "M2_1_ALERT#")
	)
	(segment
		(start 205.90002 -125.645418)
		(end 205.90002 -127.324866)
		(width 0.127)
		(layer "F.Cu")
		(net "M2_1_ALERT#")
	)
	(segment
		(start 206.019146 -121.216166)
		(end 206.019146 -122.368818)
		(width 0.127)
		(layer "F.Cu")
		(net "M2_1_ALERT#")
	)
	(segment
		(start 206.019146 -125.526292)
		(end 205.90002 -125.645418)
		(width 0.127)
		(layer "F.Cu")
		(net "M2_1_ALERT#")
	)
	(segment
		(start 119.486426 -26.842974)
		(end 117.23751 -29.09189)
		(width 0.127)
		(layer "F.Cu")
		(net "M2_1_ALERT#")
	)
	(segment
		(start 206.019146 -121.216166)
		(end 205.0796 -121.216166)
		(width 0.127)
		(layer "F.Cu")
		(net "M2_1_ALERT#")
	)
	(segment
		(start 117.23751 -29.09189)
		(end 115.764564 -29.09189)
		(width 0.127)
		(layer "F.Cu")
		(net "M2_1_ALERT#")
	)
	(segment
		(start 206.019146 -122.368818)
		(end 206.019146 -125.526292)
		(width 0.127)
		(layer "F.Cu")
		(net "M2_1_ALERT#")
	)
	(via
		(at 119.705374 -26.842974)
		(size 0.508)
		(drill 0.254)
		(layers "F.Cu" "B.Cu")
		(net "M2_1_ALERT#")
	)
	(via
		(at 51.2064 -123.571)
		(size 0.508)
		(drill 0.254)
		(layers "F.Cu" "B.Cu")
		(net "M2_1_ALERT#")
	)
	(via
		(at 101.092 -42.0116)
		(size 0.508)
		(drill 0.254)
		(layers "F.Cu" "B.Cu")
		(net "M2_1_ALERT#")
	)
	(via
		(at 94.888304 -118.4402)
		(size 0.508)
		(drill 0.254)
		(layers "F.Cu" "B.Cu")
		(net "M2_1_ALERT#")
	)
	(via
		(at 205.0796 -121.216166)
		(size 0.508)
		(drill 0.254)
		(layers "F.Cu" "B.Cu")
		(net "M2_1_ALERT#")
	)
	(via
		(at 206.019146 -122.368818)
		(size 0.6604)
		(drill 0.3302)
		(layers "F.Cu" "B.Cu")
		(net "M2_1_ALERT#")
	)
	(via
		(at 115.764564 -29.09189)
		(size 0.508)
		(drill 0.254)
		(layers "F.Cu" "B.Cu")
		(net "M2_1_ALERT#")
	)
	(segment
		(start 101.092 -42.0116)
		(end 101.092 -43.5864)
		(width 0.127)
		(layer "B.Cu")
		(net "M2_1_ALERT#")
	)
	(segment
		(start 51.3461 -123.7107)
		(end 51.2064 -123.571)
		(width 0.127)
		(layer "B.Cu")
		(net "M2_1_ALERT#")
	)
	(segment
		(start 100.726748 -43.951652)
		(end 100.726748 -74.711052)
		(width 0.127)
		(layer "B.Cu")
		(net "M2_1_ALERT#")
	)
	(segment
		(start 101.092 -43.5864)
		(end 100.726748 -43.951652)
		(width 0.127)
		(layer "B.Cu")
		(net "M2_1_ALERT#")
	)
	(segment
		(start 92.99956 -91.65336)
		(end 97.2566 -95.9104)
		(width 0.127)
		(layer "B.Cu")
		(net "M2_1_ALERT#")
	)
	(segment
		(start 95.4786 -117.849904)
		(end 94.888304 -118.4402)
		(width 0.127)
		(layer "B.Cu")
		(net "M2_1_ALERT#")
	)
	(segment
		(start 92.99956 -82.43824)
		(end 92.99956 -91.65336)
		(width 0.127)
		(layer "B.Cu")
		(net "M2_1_ALERT#")
	)
	(segment
		(start 95.4786 -116.6876)
		(end 95.4786 -117.849904)
		(width 0.127)
		(layer "B.Cu")
		(net "M2_1_ALERT#")
	)
	(segment
		(start 97.2566 -95.9104)
		(end 97.2566 -114.9096)
		(width 0.127)
		(layer "B.Cu")
		(net "M2_1_ALERT#")
	)
	(segment
		(start 100.726748 -74.711052)
		(end 92.99956 -82.43824)
		(width 0.127)
		(layer "B.Cu")
		(net "M2_1_ALERT#")
	)
	(segment
		(start 97.2566 -114.9096)
		(end 95.4786 -116.6876)
		(width 0.127)
		(layer "B.Cu")
		(net "M2_1_ALERT#")
	)
	(segment
		(start 52.0192 -123.7107)
		(end 51.3461 -123.7107)
		(width 0.127)
		(layer "B.Cu")
		(net "M2_1_ALERT#")
	)
	(segment
		(start 101.041962 -30.702758)
		(end 105.353104 -26.391616)
		(width 0.127)
		(layer "In2.Cu")
		(net "M2_1_ALERT#")
	)
	(segment
		(start 105.353104 -26.391616)
		(end 113.06429 -26.391616)
		(width 0.127)
		(layer "In2.Cu")
		(net "M2_1_ALERT#")
	)
	(segment
		(start 101.092 -42.0116)
		(end 100.076 -40.9956)
		(width 0.127)
		(layer "In2.Cu")
		(net "M2_1_ALERT#")
	)
	(segment
		(start 100.076 -40.9956)
		(end 100.076 -36.517834)
		(width 0.127)
		(layer "In2.Cu")
		(net "M2_1_ALERT#")
	)
	(segment
		(start 100.076 -36.517834)
		(end 101.041962 -35.551872)
		(width 0.127)
		(layer "In2.Cu")
		(net "M2_1_ALERT#")
	)
	(segment
		(start 101.041962 -35.551872)
		(end 101.041962 -30.702758)
		(width 0.127)
		(layer "In2.Cu")
		(net "M2_1_ALERT#")
	)
	(segment
		(start 113.06429 -26.391616)
		(end 115.764564 -29.09189)
		(width 0.127)
		(layer "In2.Cu")
		(net "M2_1_ALERT#")
	)
	(segment
		(start 154.50566 -19.68119)
		(end 174.084488 -39.260018)
		(width 0.127)
		(layer "In5.Cu")
		(net "M2_1_ALERT#")
	)
	(segment
		(start 174.498 -95.41891)
		(end 174.498 -116.136166)
		(width 0.127)
		(layer "In5.Cu")
		(net "M2_1_ALERT#")
	)
	(segment
		(start 176.613566 -123.698)
		(end 177.2158 -123.698)
		(width 0.127)
		(layer "In5.Cu")
		(net "M2_1_ALERT#")
	)
	(segment
		(start 119.705374 -26.842974)
		(end 123.840748 -22.7076)
		(width 0.127)
		(layer "In5.Cu")
		(net "M2_1_ALERT#")
	)
	(segment
		(start 152.30221 -15.566644)
		(end 154.50566 -17.770094)
		(width 0.127)
		(layer "In5.Cu")
		(net "M2_1_ALERT#")
	)
	(segment
		(start 145.04797 -15.566644)
		(end 152.30221 -15.566644)
		(width 0.127)
		(layer "In5.Cu")
		(net "M2_1_ALERT#")
	)
	(segment
		(start 72.11949 -120.4976)
		(end 66.88074 -120.4976)
		(width 0.127)
		(layer "In5.Cu")
		(net "M2_1_ALERT#")
	)
	(segment
		(start 177.2158 -123.698)
		(end 179.4256 -121.4882)
		(width 0.127)
		(layer "In5.Cu")
		(net "M2_1_ALERT#")
	)
	(segment
		(start 94.888304 -118.4402)
		(end 94.481904 -118.0338)
		(width 0.127)
		(layer "In5.Cu")
		(net "M2_1_ALERT#")
	)
	(segment
		(start 85.913468 -116.332)
		(end 85.3186 -115.737132)
		(width 0.127)
		(layer "In5.Cu")
		(net "M2_1_ALERT#")
	)
	(segment
		(start 77.80909 -114.808)
		(end 72.11949 -120.4976)
		(width 0.127)
		(layer "In5.Cu")
		(net "M2_1_ALERT#")
	)
	(segment
		(start 52.324508 -122.257058)
		(end 51.2064 -123.375166)
		(width 0.127)
		(layer "In5.Cu")
		(net "M2_1_ALERT#")
	)
	(segment
		(start 154.50566 -17.770094)
		(end 154.50566 -19.68119)
		(width 0.127)
		(layer "In5.Cu")
		(net "M2_1_ALERT#")
	)
	(segment
		(start 172.974 -117.660166)
		(end 172.974 -120.058434)
		(width 0.127)
		(layer "In5.Cu")
		(net "M2_1_ALERT#")
	)
	(segment
		(start 174.084488 -95.005398)
		(end 174.498 -95.41891)
		(width 0.127)
		(layer "In5.Cu")
		(net "M2_1_ALERT#")
	)
	(segment
		(start 66.88074 -120.4976)
		(end 66.01714 -121.3612)
		(width 0.127)
		(layer "In5.Cu")
		(net "M2_1_ALERT#")
	)
	(segment
		(start 56.086248 -120.523)
		(end 55.070248 -121.539)
		(width 0.127)
		(layer "In5.Cu")
		(net "M2_1_ALERT#")
	)
	(segment
		(start 127.7366 -22.7076)
		(end 129.2098 -21.2344)
		(width 0.127)
		(layer "In5.Cu")
		(net "M2_1_ALERT#")
	)
	(segment
		(start 88.068912 -118.034054)
		(end 87.648288 -118.034054)
		(width 0.127)
		(layer "In5.Cu")
		(net "M2_1_ALERT#")
	)
	(segment
		(start 204.0128 -121.4882)
		(end 204.284834 -121.216166)
		(width 0.127)
		(layer "In5.Cu")
		(net "M2_1_ALERT#")
	)
	(segment
		(start 132.04952 -17.37868)
		(end 143.235934 -17.37868)
		(width 0.127)
		(layer "In5.Cu")
		(net "M2_1_ALERT#")
	)
	(segment
		(start 94.481904 -118.0338)
		(end 88.069166 -118.0338)
		(width 0.127)
		(layer "In5.Cu")
		(net "M2_1_ALERT#")
	)
	(segment
		(start 143.235934 -17.37868)
		(end 145.04797 -15.566644)
		(width 0.127)
		(layer "In5.Cu")
		(net "M2_1_ALERT#")
	)
	(segment
		(start 123.840748 -22.7076)
		(end 127.7366 -22.7076)
		(width 0.127)
		(layer "In5.Cu")
		(net "M2_1_ALERT#")
	)
	(segment
		(start 61.2902 -120.904)
		(end 60.9092 -120.523)
		(width 0.127)
		(layer "In5.Cu")
		(net "M2_1_ALERT#")
	)
	(segment
		(start 66.01714 -121.3612)
		(end 63.246 -121.3612)
		(width 0.127)
		(layer "In5.Cu")
		(net "M2_1_ALERT#")
	)
	(segment
		(start 84.422234 -114.808)
		(end 77.80909 -114.808)
		(width 0.127)
		(layer "In5.Cu")
		(net "M2_1_ALERT#")
	)
	(segment
		(start 51.2064 -123.375166)
		(end 51.2064 -123.571)
		(width 0.127)
		(layer "In5.Cu")
		(net "M2_1_ALERT#")
	)
	(segment
		(start 85.946234 -116.332)
		(end 85.913468 -116.332)
		(width 0.127)
		(layer "In5.Cu")
		(net "M2_1_ALERT#")
	)
	(segment
		(start 63.246 -121.3612)
		(end 62.7888 -120.904)
		(width 0.127)
		(layer "In5.Cu")
		(net "M2_1_ALERT#")
	)
	(segment
		(start 62.7888 -120.904)
		(end 61.2902 -120.904)
		(width 0.127)
		(layer "In5.Cu")
		(net "M2_1_ALERT#")
	)
	(segment
		(start 87.648288 -118.034054)
		(end 85.946234 -116.332)
		(width 0.127)
		(layer "In5.Cu")
		(net "M2_1_ALERT#")
	)
	(segment
		(start 53.04282 -121.539)
		(end 52.48021 -122.10161)
		(width 0.127)
		(layer "In5.Cu")
		(net "M2_1_ALERT#")
	)
	(segment
		(start 52.48021 -122.10161)
		(end 52.324508 -122.257058)
		(width 0.127)
		(layer "In5.Cu")
		(net "M2_1_ALERT#")
	)
	(segment
		(start 204.284834 -121.216166)
		(end 205.0796 -121.216166)
		(width 0.127)
		(layer "In5.Cu")
		(net "M2_1_ALERT#")
	)
	(segment
		(start 55.070248 -121.539)
		(end 53.04282 -121.539)
		(width 0.127)
		(layer "In5.Cu")
		(net "M2_1_ALERT#")
	)
	(segment
		(start 129.2098 -20.2184)
		(end 132.04952 -17.37868)
		(width 0.127)
		(layer "In5.Cu")
		(net "M2_1_ALERT#")
	)
	(segment
		(start 179.4256 -121.4882)
		(end 204.0128 -121.4882)
		(width 0.127)
		(layer "In5.Cu")
		(net "M2_1_ALERT#")
	)
	(segment
		(start 85.3186 -115.737132)
		(end 85.3186 -115.704366)
		(width 0.127)
		(layer "In5.Cu")
		(net "M2_1_ALERT#")
	)
	(segment
		(start 60.9092 -120.523)
		(end 56.086248 -120.523)
		(width 0.127)
		(layer "In5.Cu")
		(net "M2_1_ALERT#")
	)
	(segment
		(start 88.069166 -118.0338)
		(end 88.068912 -118.034054)
		(width 0.127)
		(layer "In5.Cu")
		(net "M2_1_ALERT#")
	)
	(segment
		(start 85.3186 -115.704366)
		(end 84.422234 -114.808)
		(width 0.127)
		(layer "In5.Cu")
		(net "M2_1_ALERT#")
	)
	(segment
		(start 174.084488 -39.260018)
		(end 174.084488 -95.005398)
		(width 0.127)
		(layer "In5.Cu")
		(net "M2_1_ALERT#")
	)
	(segment
		(start 172.974 -120.058434)
		(end 176.613566 -123.698)
		(width 0.127)
		(layer "In5.Cu")
		(net "M2_1_ALERT#")
	)
	(segment
		(start 174.498 -116.136166)
		(end 172.974 -117.660166)
		(width 0.127)
		(layer "In5.Cu")
		(net "M2_1_ALERT#")
	)
	(segment
		(start 129.2098 -21.2344)
		(end 129.2098 -20.2184)
		(width 0.127)
		(layer "In5.Cu")
		(net "M2_1_ALERT#")
	)
	(segment
		(start 46.500034 -138.999976)
		(end 46.49978 -138.999976)
		(width 0.127)
		(layer "F.Cu")
		(net "IOM_LOC_INS_N")
	)
	(segment
		(start 46.49978 -138.999976)
		(end 46.100238 -138.600434)
		(width 0.127)
		(layer "F.Cu")
		(net "IOM_LOC_INS_N")
	)
	(via
		(at 87.1347 -111.4806)
		(size 0.508)
		(drill 0.254)
		(layers "F.Cu" "B.Cu")
		(net "IOM_LOC_INS_N")
	)
	(via
		(at 46.100238 -138.600434)
		(size 0.4572)
		(drill 0.2032)
		(layers "F.Cu" "B.Cu")
		(net "IOM_LOC_INS_N")
	)
	(via
		(at 45.432726 -129.487422)
		(size 0.508)
		(drill 0.254)
		(layers "F.Cu" "B.Cu")
		(net "IOM_LOC_INS_N")
	)
	(via
		(at 45.4914 -115.7732)
		(size 0.508)
		(drill 0.254)
		(layers "F.Cu" "B.Cu")
		(net "IOM_LOC_INS_N")
	)
	(segment
		(start 45.440092 -129.340356)
		(end 45.440092 -129.480056)
		(width 0.127)
		(layer "B.Cu")
		(net "IOM_LOC_INS_N")
	)
	(segment
		(start 45.466 -129.314448)
		(end 45.440092 -129.340356)
		(width 0.127)
		(layer "B.Cu")
		(net "IOM_LOC_INS_N")
	)
	(segment
		(start 45.440092 -129.480056)
		(end 45.432726 -129.487422)
		(width 0.127)
		(layer "B.Cu")
		(net "IOM_LOC_INS_N")
	)
	(segment
		(start 45.466 -128.6637)
		(end 45.466 -129.314448)
		(width 0.127)
		(layer "B.Cu")
		(net "IOM_LOC_INS_N")
	)
	(segment
		(start 89.2683 -101.115368)
		(end 87.9094 -99.756468)
		(width 0.127)
		(layer "In2.Cu")
		(net "IOM_LOC_INS_N")
	)
	(segment
		(start 134.671562 -30.663388)
		(end 134.671562 -40.028622)
		(width 0.127)
		(layer "In2.Cu")
		(net "IOM_LOC_INS_N")
	)
	(segment
		(start 45.4914 -126.0094)
		(end 45.9359 -126.4539)
		(width 0.127)
		(layer "In2.Cu")
		(net "IOM_LOC_INS_N")
	)
	(segment
		(start 84.087208 -31.750254)
		(end 84.087208 -10.9601)
		(width 0.127)
		(layer "In2.Cu")
		(net "IOM_LOC_INS_N")
	)
	(segment
		(start 45.9359 -128.984248)
		(end 45.432726 -129.487422)
		(width 0.127)
		(layer "In2.Cu")
		(net "IOM_LOC_INS_N")
	)
	(segment
		(start 46.100238 -138.357356)
		(end 46.100238 -138.600434)
		(width 0.127)
		(layer "In2.Cu")
		(net "IOM_LOC_INS_N")
	)
	(segment
		(start 93.99524 -10.540238)
		(end 93.99524 -15.20444)
		(width 0.127)
		(layer "In2.Cu")
		(net "IOM_LOC_INS_N")
	)
	(segment
		(start 87.1347 -111.4806)
		(end 87.1347 -111.012732)
		(width 0.127)
		(layer "In2.Cu")
		(net "IOM_LOC_INS_N")
	)
	(segment
		(start 89.2683 -108.879132)
		(end 89.2683 -101.115368)
		(width 0.127)
		(layer "In2.Cu")
		(net "IOM_LOC_INS_N")
	)
	(segment
		(start 45.922946 -134.347712)
		(end 45.922946 -134.655052)
		(width 0.127)
		(layer "In2.Cu")
		(net "IOM_LOC_INS_N")
	)
	(segment
		(start 46.101 -134.169658)
		(end 45.922946 -134.347712)
		(width 0.127)
		(layer "In2.Cu")
		(net "IOM_LOC_INS_N")
	)
	(segment
		(start 127.38608 -28.226512)
		(end 132.234686 -28.226512)
		(width 0.127)
		(layer "In2.Cu")
		(net "IOM_LOC_INS_N")
	)
	(segment
		(start 93.99524 -15.20444)
		(end 96.640904 -17.850104)
		(width 0.127)
		(layer "In2.Cu")
		(net "IOM_LOC_INS_N")
	)
	(segment
		(start 87.9602 -54.304438)
		(end 86.868 -53.212238)
		(width 0.127)
		(layer "In2.Cu")
		(net "IOM_LOC_INS_N")
	)
	(segment
		(start 96.640904 -17.850104)
		(end 115.1509 -17.850104)
		(width 0.127)
		(layer "In2.Cu")
		(net "IOM_LOC_INS_N")
	)
	(segment
		(start 119.606568 -20.447)
		(end 127.38608 -28.226512)
		(width 0.127)
		(layer "In2.Cu")
		(net "IOM_LOC_INS_N")
	)
	(segment
		(start 117.747796 -20.447)
		(end 119.606568 -20.447)
		(width 0.127)
		(layer "In2.Cu")
		(net "IOM_LOC_INS_N")
	)
	(segment
		(start 86.868 -34.531046)
		(end 84.087208 -31.750254)
		(width 0.127)
		(layer "In2.Cu")
		(net "IOM_LOC_INS_N")
	)
	(segment
		(start 87.9094 -98.103436)
		(end 87.39632 -97.590356)
		(width 0.127)
		(layer "In2.Cu")
		(net "IOM_LOC_INS_N")
	)
	(segment
		(start 87.1347 -111.012732)
		(end 89.2683 -108.879132)
		(width 0.127)
		(layer "In2.Cu")
		(net "IOM_LOC_INS_N")
	)
	(segment
		(start 45.7708 -130.937)
		(end 46.101 -131.2672)
		(width 0.127)
		(layer "In2.Cu")
		(net "IOM_LOC_INS_N")
	)
	(segment
		(start 45.4914 -115.7732)
		(end 45.4914 -126.0094)
		(width 0.127)
		(layer "In2.Cu")
		(net "IOM_LOC_INS_N")
	)
	(segment
		(start 87.9602 -94.315534)
		(end 87.9602 -54.304438)
		(width 0.127)
		(layer "In2.Cu")
		(net "IOM_LOC_INS_N")
	)
	(segment
		(start 87.39632 -97.590356)
		(end 87.39632 -94.879414)
		(width 0.127)
		(layer "In2.Cu")
		(net "IOM_LOC_INS_N")
	)
	(segment
		(start 45.7708 -129.825496)
		(end 45.7708 -130.937)
		(width 0.127)
		(layer "In2.Cu")
		(net "IOM_LOC_INS_N")
	)
	(segment
		(start 132.234686 -28.226512)
		(end 134.671562 -30.663388)
		(width 0.127)
		(layer "In2.Cu")
		(net "IOM_LOC_INS_N")
	)
	(segment
		(start 45.4406 -137.697718)
		(end 46.100238 -138.357356)
		(width 0.127)
		(layer "In2.Cu")
		(net "IOM_LOC_INS_N")
	)
	(segment
		(start 46.101 -131.2672)
		(end 46.101 -134.169658)
		(width 0.127)
		(layer "In2.Cu")
		(net "IOM_LOC_INS_N")
	)
	(segment
		(start 84.087208 -10.9601)
		(end 84.977732 -10.069576)
		(width 0.127)
		(layer "In2.Cu")
		(net "IOM_LOC_INS_N")
	)
	(segment
		(start 84.977732 -10.069576)
		(end 93.524578 -10.069576)
		(width 0.127)
		(layer "In2.Cu")
		(net "IOM_LOC_INS_N")
	)
	(segment
		(start 45.4406 -135.137398)
		(end 45.4406 -137.697718)
		(width 0.127)
		(layer "In2.Cu")
		(net "IOM_LOC_INS_N")
	)
	(segment
		(start 93.524578 -10.069576)
		(end 93.99524 -10.540238)
		(width 0.127)
		(layer "In2.Cu")
		(net "IOM_LOC_INS_N")
	)
	(segment
		(start 87.9094 -99.756468)
		(end 87.9094 -98.103436)
		(width 0.127)
		(layer "In2.Cu")
		(net "IOM_LOC_INS_N")
	)
	(segment
		(start 134.671562 -40.028622)
		(end 134.100062 -40.600122)
		(width 0.127)
		(layer "In2.Cu")
		(net "IOM_LOC_INS_N")
	)
	(segment
		(start 87.39632 -94.879414)
		(end 87.9602 -94.315534)
		(width 0.127)
		(layer "In2.Cu")
		(net "IOM_LOC_INS_N")
	)
	(segment
		(start 45.9359 -126.4539)
		(end 45.9359 -128.984248)
		(width 0.127)
		(layer "In2.Cu")
		(net "IOM_LOC_INS_N")
	)
	(segment
		(start 115.1509 -17.850104)
		(end 117.747796 -20.447)
		(width 0.127)
		(layer "In2.Cu")
		(net "IOM_LOC_INS_N")
	)
	(segment
		(start 45.432726 -129.487422)
		(end 45.7708 -129.825496)
		(width 0.127)
		(layer "In2.Cu")
		(net "IOM_LOC_INS_N")
	)
	(segment
		(start 86.868 -53.212238)
		(end 86.868 -34.531046)
		(width 0.127)
		(layer "In2.Cu")
		(net "IOM_LOC_INS_N")
	)
	(segment
		(start 45.922946 -134.655052)
		(end 45.4406 -135.137398)
		(width 0.127)
		(layer "In2.Cu")
		(net "IOM_LOC_INS_N")
	)
	(segment
		(start 76.808838 -111.379)
		(end 76.808584 -111.378746)
		(width 0.127)
		(layer "In5.Cu")
		(net "IOM_LOC_INS_N")
	)
	(segment
		(start 61.180218 -115.8621)
		(end 60.193428 -114.87531)
		(width 0.127)
		(layer "In5.Cu")
		(net "IOM_LOC_INS_N")
	)
	(segment
		(start 67.803268 -115.7224)
		(end 65.067434 -115.7224)
		(width 0.127)
		(layer "In5.Cu")
		(net "IOM_LOC_INS_N")
	)
	(segment
		(start 72.666606 -115.1001)
		(end 68.425568 -115.1001)
		(width 0.127)
		(layer "In5.Cu")
		(net "IOM_LOC_INS_N")
	)
	(segment
		(start 87.0331 -111.379)
		(end 76.808838 -111.379)
		(width 0.127)
		(layer "In5.Cu")
		(net "IOM_LOC_INS_N")
	)
	(segment
		(start 76.38796 -111.378746)
		(end 72.666606 -115.1001)
		(width 0.127)
		(layer "In5.Cu")
		(net "IOM_LOC_INS_N")
	)
	(segment
		(start 87.1347 -111.4806)
		(end 87.0331 -111.379)
		(width 0.127)
		(layer "In5.Cu")
		(net "IOM_LOC_INS_N")
	)
	(segment
		(start 60.193428 -114.87531)
		(end 46.38929 -114.87531)
		(width 0.127)
		(layer "In5.Cu")
		(net "IOM_LOC_INS_N")
	)
	(segment
		(start 76.808584 -111.378746)
		(end 76.38796 -111.378746)
		(width 0.127)
		(layer "In5.Cu")
		(net "IOM_LOC_INS_N")
	)
	(segment
		(start 46.38929 -114.87531)
		(end 45.4914 -115.7732)
		(width 0.127)
		(layer "In5.Cu")
		(net "IOM_LOC_INS_N")
	)
	(segment
		(start 65.067434 -115.7224)
		(end 64.92748 -115.8621)
		(width 0.127)
		(layer "In5.Cu")
		(net "IOM_LOC_INS_N")
	)
	(segment
		(start 64.92748 -115.8621)
		(end 61.180218 -115.8621)
		(width 0.127)
		(layer "In5.Cu")
		(net "IOM_LOC_INS_N")
	)
	(segment
		(start 68.425568 -115.1001)
		(end 67.803268 -115.7224)
		(width 0.127)
		(layer "In5.Cu")
		(net "IOM_LOC_INS_N")
	)
	(segment
		(start 45.69968 -138.999976)
		(end 45.299884 -138.60018)
		(width 0.127)
		(layer "F.Cu")
		(net "IOM_FULL_PWR_EN_R")
	)
	(segment
		(start 45.699934 -138.999976)
		(end 45.69968 -138.999976)
		(width 0.127)
		(layer "F.Cu")
		(net "IOM_FULL_PWR_EN_R")
	)
	(via
		(at 45.1104 -131.4196)
		(size 0.6096)
		(drill 0.3048)
		(layers "F.Cu" "B.Cu")
		(net "IOM_FULL_PWR_EN_R")
	)
	(via
		(at 45.299884 -138.60018)
		(size 0.4572)
		(drill 0.2032)
		(layers "F.Cu" "B.Cu")
		(net "IOM_FULL_PWR_EN_R")
	)
	(via
		(at 44.378118 -133.09854)
		(size 0.508)
		(drill 0.254)
		(layers "F.Cu" "B.Cu")
		(net "IOM_FULL_PWR_EN_R")
	)
	(segment
		(start 44.6278 -132.286502)
		(end 45.1104 -131.803902)
		(width 0.127)
		(layer "B.Cu")
		(net "IOM_FULL_PWR_EN_R")
	)
	(segment
		(start 45.246544 -131.283456)
		(end 45.246544 -130.345434)
		(width 0.127)
		(layer "B.Cu")
		(net "IOM_FULL_PWR_EN_R")
	)
	(segment
		(start 44.378118 -132.736082)
		(end 44.6278 -132.4864)
		(width 0.127)
		(layer "B.Cu")
		(net "IOM_FULL_PWR_EN_R")
	)
	(segment
		(start 45.1104 -131.803902)
		(end 45.1104 -131.4196)
		(width 0.127)
		(layer "B.Cu")
		(net "IOM_FULL_PWR_EN_R")
	)
	(segment
		(start 44.6278 -132.4864)
		(end 44.6278 -132.286502)
		(width 0.127)
		(layer "B.Cu")
		(net "IOM_FULL_PWR_EN_R")
	)
	(segment
		(start 45.1104 -131.4196)
		(end 45.246544 -131.283456)
		(width 0.127)
		(layer "B.Cu")
		(net "IOM_FULL_PWR_EN_R")
	)
	(segment
		(start 44.378118 -133.09854)
		(end 44.378118 -132.736082)
		(width 0.127)
		(layer "B.Cu")
		(net "IOM_FULL_PWR_EN_R")
	)
	(segment
		(start 44.378118 -133.09854)
		(end 44.378118 -133.652514)
		(width 0.127)
		(layer "In2.Cu")
		(net "IOM_FULL_PWR_EN_R")
	)
	(segment
		(start 45.1612 -138.1252)
		(end 45.1612 -138.461496)
		(width 0.127)
		(layer "In2.Cu")
		(net "IOM_FULL_PWR_EN_R")
	)
	(segment
		(start 44.378118 -133.652514)
		(end 44.743116 -134.017512)
		(width 0.127)
		(layer "In2.Cu")
		(net "IOM_FULL_PWR_EN_R")
	)
	(segment
		(start 45.1612 -138.461496)
		(end 45.299884 -138.60018)
		(width 0.127)
		(layer "In2.Cu")
		(net "IOM_FULL_PWR_EN_R")
	)
	(segment
		(start 44.743116 -137.707116)
		(end 45.1612 -138.1252)
		(width 0.127)
		(layer "In2.Cu")
		(net "IOM_FULL_PWR_EN_R")
	)
	(segment
		(start 44.743116 -134.017512)
		(end 44.743116 -137.707116)
		(width 0.127)
		(layer "In2.Cu")
		(net "IOM_FULL_PWR_EN_R")
	)
	(segment
		(start 88.392508 -60.16752)
		(end 88.0618 -59.836812)
		(width 0.127)
		(layer "F.Cu")
		(net "IOM_FULL_PWR_EN")
	)
	(segment
		(start 94.16542 -61.292232)
		(end 93.040708 -60.16752)
		(width 0.127)
		(layer "F.Cu")
		(net "IOM_FULL_PWR_EN")
	)
	(segment
		(start 82.874612 -57.169812)
		(end 82.296 -56.5912)
		(width 0.127)
		(layer "F.Cu")
		(net "IOM_FULL_PWR_EN")
	)
	(segment
		(start 93.040708 -60.16752)
		(end 88.392508 -60.16752)
		(width 0.127)
		(layer "F.Cu")
		(net "IOM_FULL_PWR_EN")
	)
	(segment
		(start 76.2508 -46.2788)
		(end 77.3684 -45.1612)
		(width 0.127)
		(layer "F.Cu")
		(net "IOM_FULL_PWR_EN")
	)
	(segment
		(start 94.742 -56.636412)
		(end 94.742 -61.782452)
		(width 0.127)
		(layer "F.Cu")
		(net "IOM_FULL_PWR_EN")
	)
	(segment
		(start 88.0618 -57.804812)
		(end 87.4268 -57.169812)
		(width 0.127)
		(layer "F.Cu")
		(net "IOM_FULL_PWR_EN")
	)
	(segment
		(start 77.3684 -45.1612)
		(end 81.4578 -45.1612)
		(width 0.127)
		(layer "F.Cu")
		(net "IOM_FULL_PWR_EN")
	)
	(segment
		(start 93.75013 -53.352446)
		(end 93.75013 -55.644542)
		(width 0.127)
		(layer "F.Cu")
		(net "IOM_FULL_PWR_EN")
	)
	(segment
		(start 93.75013 -55.644542)
		(end 94.742 -56.636412)
		(width 0.127)
		(layer "F.Cu")
		(net "IOM_FULL_PWR_EN")
	)
	(segment
		(start 87.4268 -57.169812)
		(end 82.874612 -57.169812)
		(width 0.127)
		(layer "F.Cu")
		(net "IOM_FULL_PWR_EN")
	)
	(segment
		(start 74.85888 -46.2788)
		(end 76.2508 -46.2788)
		(width 0.127)
		(layer "F.Cu")
		(net "IOM_FULL_PWR_EN")
	)
	(segment
		(start 94.16542 -61.292232)
		(end 94.16542 -62.359032)
		(width 0.127)
		(layer "F.Cu")
		(net "IOM_FULL_PWR_EN")
	)
	(segment
		(start 94.742 -61.782452)
		(end 94.16542 -62.359032)
		(width 0.127)
		(layer "F.Cu")
		(net "IOM_FULL_PWR_EN")
	)
	(segment
		(start 88.0618 -59.836812)
		(end 88.0618 -57.804812)
		(width 0.127)
		(layer "F.Cu")
		(net "IOM_FULL_PWR_EN")
	)
	(via
		(at 56.64073 -112.72647)
		(size 0.508)
		(drill 0.254)
		(layers "F.Cu" "B.Cu")
		(net "IOM_FULL_PWR_EN")
	)
	(via
		(at 82.296 -56.5912)
		(size 0.508)
		(drill 0.254)
		(layers "F.Cu" "B.Cu")
		(net "IOM_FULL_PWR_EN")
	)
	(via
		(at 74.85888 -46.2788)
		(size 0.508)
		(drill 0.254)
		(layers "F.Cu" "B.Cu")
		(net "IOM_FULL_PWR_EN")
	)
	(via
		(at 81.4578 -45.1612)
		(size 0.508)
		(drill 0.254)
		(layers "F.Cu" "B.Cu")
		(net "IOM_FULL_PWR_EN")
	)
	(via
		(at 44.9326 -126.111)
		(size 0.508)
		(drill 0.254)
		(layers "F.Cu" "B.Cu")
		(net "IOM_FULL_PWR_EN")
	)
	(segment
		(start 58.971688 -112.522)
		(end 58.590688 -112.141)
		(width 0.127)
		(layer "B.Cu")
		(net "IOM_FULL_PWR_EN")
	)
	(segment
		(start 44.357544 -130.267456)
		(end 44.9326 -129.6924)
		(width 0.127)
		(layer "B.Cu")
		(net "IOM_FULL_PWR_EN")
	)
	(segment
		(start 74.237342 -111.292894)
		(end 67.070478 -111.292894)
		(width 0.127)
		(layer "B.Cu")
		(net "IOM_FULL_PWR_EN")
	)
	(segment
		(start 83.877658 -107.945682)
		(end 82.4738 -109.34954)
		(width 0.127)
		(layer "B.Cu")
		(net "IOM_FULL_PWR_EN")
	)
	(segment
		(start 80.669638 -99.831144)
		(end 81.270094 -100.4316)
		(width 0.127)
		(layer "B.Cu")
		(net "IOM_FULL_PWR_EN")
	)
	(segment
		(start 44.357544 -130.345434)
		(end 44.357544 -130.267456)
		(width 0.127)
		(layer "B.Cu")
		(net "IOM_FULL_PWR_EN")
	)
	(segment
		(start 81.201006 -109.6772)
		(end 80.377792 -110.500414)
		(width 0.127)
		(layer "B.Cu")
		(net "IOM_FULL_PWR_EN")
	)
	(segment
		(start 81.971388 -100.4316)
		(end 83.877658 -102.33787)
		(width 0.127)
		(layer "B.Cu")
		(net "IOM_FULL_PWR_EN")
	)
	(segment
		(start 44.9326 -129.6924)
		(end 44.9326 -126.111)
		(width 0.127)
		(layer "B.Cu")
		(net "IOM_FULL_PWR_EN")
	)
	(segment
		(start 61.3918 -112.522)
		(end 58.971688 -112.522)
		(width 0.127)
		(layer "B.Cu")
		(net "IOM_FULL_PWR_EN")
	)
	(segment
		(start 80.377792 -110.500414)
		(end 75.029822 -110.500414)
		(width 0.127)
		(layer "B.Cu")
		(net "IOM_FULL_PWR_EN")
	)
	(segment
		(start 75.029822 -110.500414)
		(end 74.237342 -111.292894)
		(width 0.127)
		(layer "B.Cu")
		(net "IOM_FULL_PWR_EN")
	)
	(segment
		(start 77.078332 -99.831144)
		(end 80.669638 -99.831144)
		(width 0.127)
		(layer "B.Cu")
		(net "IOM_FULL_PWR_EN")
	)
	(segment
		(start 57.2262 -112.141)
		(end 56.64073 -112.72647)
		(width 0.127)
		(layer "B.Cu")
		(net "IOM_FULL_PWR_EN")
	)
	(segment
		(start 62.488826 -111.424974)
		(end 61.3918 -112.522)
		(width 0.127)
		(layer "B.Cu")
		(net "IOM_FULL_PWR_EN")
	)
	(segment
		(start 81.270094 -100.4316)
		(end 81.971388 -100.4316)
		(width 0.127)
		(layer "B.Cu")
		(net "IOM_FULL_PWR_EN")
	)
	(segment
		(start 82.01787 -109.34954)
		(end 81.69021 -109.6772)
		(width 0.127)
		(layer "B.Cu")
		(net "IOM_FULL_PWR_EN")
	)
	(segment
		(start 83.877658 -102.33787)
		(end 83.877658 -107.945682)
		(width 0.127)
		(layer "B.Cu")
		(net "IOM_FULL_PWR_EN")
	)
	(segment
		(start 58.590688 -112.141)
		(end 57.2262 -112.141)
		(width 0.127)
		(layer "B.Cu")
		(net "IOM_FULL_PWR_EN")
	)
	(segment
		(start 66.938398 -111.424974)
		(end 62.488826 -111.424974)
		(width 0.127)
		(layer "B.Cu")
		(net "IOM_FULL_PWR_EN")
	)
	(segment
		(start 82.4738 -109.34954)
		(end 82.01787 -109.34954)
		(width 0.127)
		(layer "B.Cu")
		(net "IOM_FULL_PWR_EN")
	)
	(segment
		(start 81.69021 -109.6772)
		(end 81.201006 -109.6772)
		(width 0.127)
		(layer "B.Cu")
		(net "IOM_FULL_PWR_EN")
	)
	(segment
		(start 74.23658 -46.9011)
		(end 74.23658 -96.989392)
		(width 0.127)
		(layer "B.Cu")
		(net "IOM_FULL_PWR_EN")
	)
	(segment
		(start 74.23658 -96.989392)
		(end 77.078332 -99.831144)
		(width 0.127)
		(layer "B.Cu")
		(net "IOM_FULL_PWR_EN")
	)
	(segment
		(start 67.070478 -111.292894)
		(end 66.938398 -111.424974)
		(width 0.127)
		(layer "B.Cu")
		(net "IOM_FULL_PWR_EN")
	)
	(segment
		(start 74.85888 -46.2788)
		(end 74.23658 -46.9011)
		(width 0.127)
		(layer "B.Cu")
		(net "IOM_FULL_PWR_EN")
	)
	(segment
		(start 45.1104 -118.80342)
		(end 44.9326 -118.98122)
		(width 0.127)
		(layer "In2.Cu")
		(net "IOM_FULL_PWR_EN")
	)
	(segment
		(start 46.888908 -112.72647)
		(end 44.9326 -114.682778)
		(width 0.127)
		(layer "In2.Cu")
		(net "IOM_FULL_PWR_EN")
	)
	(segment
		(start 44.9326 -114.682778)
		(end 44.9326 -116.671344)
		(width 0.127)
		(layer "In2.Cu")
		(net "IOM_FULL_PWR_EN")
	)
	(segment
		(start 45.1104 -116.849144)
		(end 45.1104 -118.80342)
		(width 0.127)
		(layer "In2.Cu")
		(net "IOM_FULL_PWR_EN")
	)
	(segment
		(start 56.64073 -112.72647)
		(end 46.888908 -112.72647)
		(width 0.127)
		(layer "In2.Cu")
		(net "IOM_FULL_PWR_EN")
	)
	(segment
		(start 44.9326 -116.671344)
		(end 45.1104 -116.849144)
		(width 0.127)
		(layer "In2.Cu")
		(net "IOM_FULL_PWR_EN")
	)
	(segment
		(start 44.9326 -118.98122)
		(end 44.9326 -126.111)
		(width 0.127)
		(layer "In2.Cu")
		(net "IOM_FULL_PWR_EN")
	)
	(segment
		(start 81.595468 -54.28234)
		(end 81.595468 -56.360568)
		(width 0.127)
		(layer "In5.Cu")
		(net "IOM_FULL_PWR_EN")
	)
	(segment
		(start 81.4578 -45.1612)
		(end 80.9752 -45.6438)
		(width 0.127)
		(layer "In5.Cu")
		(net "IOM_FULL_PWR_EN")
	)
	(segment
		(start 80.9752 -53.662072)
		(end 81.595468 -54.28234)
		(width 0.127)
		(layer "In5.Cu")
		(net "IOM_FULL_PWR_EN")
	)
	(segment
		(start 81.595468 -56.360568)
		(end 81.8261 -56.5912)
		(width 0.127)
		(layer "In5.Cu")
		(net "IOM_FULL_PWR_EN")
	)
	(segment
		(start 80.9752 -45.6438)
		(end 80.9752 -53.662072)
		(width 0.127)
		(layer "In5.Cu")
		(net "IOM_FULL_PWR_EN")
	)
	(segment
		(start 81.8261 -56.5912)
		(end 82.296 -56.5912)
		(width 0.127)
		(layer "In5.Cu")
		(net "IOM_FULL_PWR_EN")
	)
	(segment
		(start 85.02523 -143.202152)
		(end 83.8962 -143.202152)
		(width 0.127)
		(layer "F.Cu")
		(net "I2C_SCC_SDA_R")
	)
	(segment
		(start 83.867752 -143.2306)
		(end 83.733132 -143.2306)
		(width 0.127)
		(layer "F.Cu")
		(net "I2C_SCC_SDA_R")
	)
	(segment
		(start 83.733132 -143.2306)
		(end 82.631534 -142.129002)
		(width 0.127)
		(layer "F.Cu")
		(net "I2C_SCC_SDA_R")
	)
	(segment
		(start 82.631534 -142.129002)
		(end 81.616296 -142.129002)
		(width 0.127)
		(layer "F.Cu")
		(net "I2C_SCC_SDA_R")
	)
	(segment
		(start 83.8962 -143.202152)
		(end 83.867752 -143.2306)
		(width 0.127)
		(layer "F.Cu")
		(net "I2C_SCC_SDA_R")
	)
	(via
		(at 83.867752 -143.2306)
		(size 0.6604)
		(drill 0.3302)
		(layers "F.Cu" "B.Cu")
		(net "I2C_SCC_SDA_R")
	)
	(segment
		(start 65.118234 -145.5928)
		(end 64.72174 -145.196306)
		(width 0.127)
		(layer "F.Cu")
		(net "I2C_SCC_SDA_OUT")
	)
	(segment
		(start 77.26426 -142.56766)
		(end 77.052678 -142.779242)
		(width 0.127)
		(layer "F.Cu")
		(net "I2C_SCC_SDA_OUT")
	)
	(segment
		(start 78.0669 -142.56766)
		(end 77.26426 -142.56766)
		(width 0.127)
		(layer "F.Cu")
		(net "I2C_SCC_SDA_OUT")
	)
	(segment
		(start 66.3702 -145.879312)
		(end 66.3702 -145.1102)
		(width 0.127)
		(layer "F.Cu")
		(net "I2C_SCC_SDA_OUT")
	)
	(segment
		(start 66.073274 -146.022822)
		(end 66.22669 -146.022822)
		(width 0.127)
		(layer "F.Cu")
		(net "I2C_SCC_SDA_OUT")
	)
	(segment
		(start 64.72174 -145.196306)
		(end 63.604394 -145.196306)
		(width 0.127)
		(layer "F.Cu")
		(net "I2C_SCC_SDA_OUT")
	)
	(segment
		(start 66.073274 -146.022822)
		(end 65.643252 -145.5928)
		(width 0.127)
		(layer "F.Cu")
		(net "I2C_SCC_SDA_OUT")
	)
	(segment
		(start 77.052678 -142.779242)
		(end 75.977496 -142.779242)
		(width 0.127)
		(layer "F.Cu")
		(net "I2C_SCC_SDA_OUT")
	)
	(segment
		(start 65.643252 -145.5928)
		(end 65.118234 -145.5928)
		(width 0.127)
		(layer "F.Cu")
		(net "I2C_SCC_SDA_OUT")
	)
	(segment
		(start 66.22669 -146.022822)
		(end 66.3702 -145.879312)
		(width 0.127)
		(layer "F.Cu")
		(net "I2C_SCC_SDA_OUT")
	)
	(segment
		(start 63.1317 -145.669)
		(end 62.89929 -145.43659)
		(width 0.127)
		(layer "F.Cu")
		(net "I2C_SCC_SDA_OUT")
	)
	(segment
		(start 63.604394 -145.196306)
		(end 63.1317 -145.669)
		(width 0.127)
		(layer "F.Cu")
		(net "I2C_SCC_SDA_OUT")
	)
	(segment
		(start 62.89929 -145.43659)
		(end 62.126368 -145.43659)
		(width 0.127)
		(layer "F.Cu")
		(net "I2C_SCC_SDA_OUT")
	)
	(via
		(at 78.0669 -142.56766)
		(size 0.508)
		(drill 0.254)
		(layers "F.Cu" "B.Cu")
		(net "I2C_SCC_SDA_OUT")
	)
	(via
		(at 66.3702 -145.1102)
		(size 0.508)
		(drill 0.254)
		(layers "F.Cu" "B.Cu")
		(net "I2C_SCC_SDA_OUT")
	)
	(via
		(at 66.073274 -146.022822)
		(size 0.6604)
		(drill 0.3302)
		(layers "F.Cu" "B.Cu")
		(net "I2C_SCC_SDA_OUT")
	)
	(segment
		(start 77.521562 -143.746474)
		(end 76.653898 -143.746474)
		(width 0.127)
		(layer "In5.Cu")
		(net "I2C_SCC_SDA_OUT")
	)
	(segment
		(start 74.259948 -142.983458)
		(end 73.649078 -143.594328)
		(width 0.127)
		(layer "In5.Cu")
		(net "I2C_SCC_SDA_OUT")
	)
	(segment
		(start 73.649078 -143.594328)
		(end 69.555106 -143.594328)
		(width 0.127)
		(layer "In5.Cu")
		(net "I2C_SCC_SDA_OUT")
	)
	(segment
		(start 75.890882 -142.983458)
		(end 74.259948 -142.983458)
		(width 0.127)
		(layer "In5.Cu")
		(net "I2C_SCC_SDA_OUT")
	)
	(segment
		(start 76.653898 -143.746474)
		(end 75.890882 -142.983458)
		(width 0.127)
		(layer "In5.Cu")
		(net "I2C_SCC_SDA_OUT")
	)
	(segment
		(start 68.305934 -144.8435)
		(end 66.6369 -144.8435)
		(width 0.127)
		(layer "In5.Cu")
		(net "I2C_SCC_SDA_OUT")
	)
	(segment
		(start 69.555106 -143.594328)
		(end 68.305934 -144.8435)
		(width 0.127)
		(layer "In5.Cu")
		(net "I2C_SCC_SDA_OUT")
	)
	(segment
		(start 66.6369 -144.8435)
		(end 66.3702 -145.1102)
		(width 0.127)
		(layer "In5.Cu")
		(net "I2C_SCC_SDA_OUT")
	)
	(segment
		(start 78.0669 -143.201136)
		(end 77.521562 -143.746474)
		(width 0.127)
		(layer "In5.Cu")
		(net "I2C_SCC_SDA_OUT")
	)
	(segment
		(start 78.0669 -142.56766)
		(end 78.0669 -143.201136)
		(width 0.127)
		(layer "In5.Cu")
		(net "I2C_SCC_SDA_OUT")
	)
	(segment
		(start 135.754872 -24.056086)
		(end 140.642594 -28.943808)
		(width 0.127)
		(layer "F.Cu")
		(net "I2C_SCC_SDA")
	)
	(segment
		(start 94.461838 -113.822988)
		(end 91.506294 -113.822988)
		(width 0.127)
		(layer "F.Cu")
		(net "I2C_SCC_SDA")
	)
	(segment
		(start 87.8078 -96.2914)
		(end 88.6714 -96.2914)
		(width 0.127)
		(layer "F.Cu")
		(net "I2C_SCC_SDA")
	)
	(segment
		(start 86.692994 -143.202152)
		(end 86.702646 -143.1925)
		(width 0.127)
		(layer "F.Cu")
		(net "I2C_SCC_SDA")
	)
	(segment
		(start 87.550752 -117.77853)
		(end 87.550752 -125.449584)
		(width 0.127)
		(layer "F.Cu")
		(net "I2C_SCC_SDA")
	)
	(segment
		(start 140.642594 -28.943808)
		(end 140.642594 -40.657272)
		(width 0.127)
		(layer "F.Cu")
		(net "I2C_SCC_SDA")
	)
	(segment
		(start 87.0966 -95.5802)
		(end 87.8078 -96.2914)
		(width 0.127)
		(layer "F.Cu")
		(net "I2C_SCC_SDA")
	)
	(segment
		(start 85.91423 -143.202152)
		(end 86.692994 -143.202152)
		(width 0.127)
		(layer "F.Cu")
		(net "I2C_SCC_SDA")
	)
	(segment
		(start 126.619 -21.3868)
		(end 129.5908 -21.3868)
		(width 0.127)
		(layer "F.Cu")
		(net "I2C_SCC_SDA")
	)
	(segment
		(start 87.0966 -70.179184)
		(end 87.0966 -95.5802)
		(width 0.127)
		(layer "F.Cu")
		(net "I2C_SCC_SDA")
	)
	(segment
		(start 129.5908 -21.3868)
		(end 132.260086 -24.056086)
		(width 0.127)
		(layer "F.Cu")
		(net "I2C_SCC_SDA")
	)
	(segment
		(start 91.506294 -113.822988)
		(end 87.550752 -117.77853)
		(width 0.127)
		(layer "F.Cu")
		(net "I2C_SCC_SDA")
	)
	(segment
		(start 94.988126 -113.2967)
		(end 94.461838 -113.822988)
		(width 0.127)
		(layer "F.Cu")
		(net "I2C_SCC_SDA")
	)
	(segment
		(start 95.681038 -113.2967)
		(end 94.988126 -113.2967)
		(width 0.127)
		(layer "F.Cu")
		(net "I2C_SCC_SDA")
	)
	(segment
		(start 140.642594 -40.657272)
		(end 139.499848 -41.800018)
		(width 0.127)
		(layer "F.Cu")
		(net "I2C_SCC_SDA")
	)
	(segment
		(start 84.780628 -67.863212)
		(end 87.0966 -70.179184)
		(width 0.127)
		(layer "F.Cu")
		(net "I2C_SCC_SDA")
	)
	(segment
		(start 132.260086 -24.056086)
		(end 135.754872 -24.056086)
		(width 0.127)
		(layer "F.Cu")
		(net "I2C_SCC_SDA")
	)
	(via
		(at 88.6714 -96.2914)
		(size 0.508)
		(drill 0.254)
		(layers "F.Cu" "B.Cu")
		(net "I2C_SCC_SDA")
	)
	(via
		(at 86.702646 -143.1925)
		(size 0.508)
		(drill 0.254)
		(layers "F.Cu" "B.Cu")
		(net "I2C_SCC_SDA")
	)
	(via
		(at 95.681038 -113.2967)
		(size 0.508)
		(drill 0.254)
		(layers "F.Cu" "B.Cu")
		(net "I2C_SCC_SDA")
	)
	(via
		(at 86.1822 -133.6802)
		(size 0.6096)
		(drill 0.3048)
		(layers "F.Cu" "B.Cu")
		(net "I2C_SCC_SDA")
	)
	(via
		(at 87.550752 -125.449584)
		(size 0.508)
		(drill 0.254)
		(layers "F.Cu" "B.Cu")
		(net "I2C_SCC_SDA")
	)
	(via
		(at 126.619 -21.3868)
		(size 0.508)
		(drill 0.254)
		(layers "F.Cu" "B.Cu")
		(net "I2C_SCC_SDA")
	)
	(via
		(at 84.780628 -67.863212)
		(size 0.508)
		(drill 0.254)
		(layers "F.Cu" "B.Cu")
		(net "I2C_SCC_SDA")
	)
	(segment
		(start 86.1822 -133.6802)
		(end 86.1822 -134.210552)
		(width 0.127)
		(layer "B.Cu")
		(net "I2C_SCC_SDA")
	)
	(segment
		(start 86.810342 -130.669538)
		(end 86.810342 -127.964946)
		(width 0.127)
		(layer "B.Cu")
		(net "I2C_SCC_SDA")
	)
	(segment
		(start 86.702646 -143.1798)
		(end 86.702646 -143.1925)
		(width 0.127)
		(layer "B.Cu")
		(net "I2C_SCC_SDA")
	)
	(segment
		(start 86.1822 -134.210552)
		(end 87.74811 -135.776462)
		(width 0.127)
		(layer "B.Cu")
		(net "I2C_SCC_SDA")
	)
	(segment
		(start 87.74811 -135.776462)
		(end 87.74811 -142.134336)
		(width 0.127)
		(layer "B.Cu")
		(net "I2C_SCC_SDA")
	)
	(segment
		(start 88.109298 -126.66599)
		(end 88.109298 -126.00813)
		(width 0.127)
		(layer "B.Cu")
		(net "I2C_SCC_SDA")
	)
	(segment
		(start 85.651848 -132.794248)
		(end 85.651848 -131.828032)
		(width 0.127)
		(layer "B.Cu")
		(net "I2C_SCC_SDA")
	)
	(segment
		(start 86.1822 -133.6802)
		(end 86.1822 -133.3246)
		(width 0.127)
		(layer "B.Cu")
		(net "I2C_SCC_SDA")
	)
	(segment
		(start 86.1822 -133.3246)
		(end 85.651848 -132.794248)
		(width 0.127)
		(layer "B.Cu")
		(net "I2C_SCC_SDA")
	)
	(segment
		(start 87.74811 -142.134336)
		(end 86.702646 -143.1798)
		(width 0.127)
		(layer "B.Cu")
		(net "I2C_SCC_SDA")
	)
	(segment
		(start 88.109298 -126.00813)
		(end 87.550752 -125.449584)
		(width 0.127)
		(layer "B.Cu")
		(net "I2C_SCC_SDA")
	)
	(segment
		(start 85.651848 -131.828032)
		(end 86.810342 -130.669538)
		(width 0.127)
		(layer "B.Cu")
		(net "I2C_SCC_SDA")
	)
	(segment
		(start 86.810342 -127.964946)
		(end 88.109298 -126.66599)
		(width 0.127)
		(layer "B.Cu")
		(net "I2C_SCC_SDA")
	)
	(segment
		(start 119.0498 -26.035)
		(end 116.197634 -26.035)
		(width 0.127)
		(layer "In5.Cu")
		(net "I2C_SCC_SDA")
	)
	(segment
		(start 86.5505 -43.989498)
		(end 86.5505 -64.3763)
		(width 0.127)
		(layer "In5.Cu")
		(net "I2C_SCC_SDA")
	)
	(segment
		(start 86.5505 -64.3763)
		(end 84.450174 -66.476626)
		(width 0.127)
		(layer "In5.Cu")
		(net "I2C_SCC_SDA")
	)
	(segment
		(start 113.1824 -23.019766)
		(end 100.140516 -23.019766)
		(width 0.127)
		(layer "In5.Cu")
		(net "I2C_SCC_SDA")
	)
	(segment
		(start 84.450174 -66.476626)
		(end 84.450174 -67.532758)
		(width 0.127)
		(layer "In5.Cu")
		(net "I2C_SCC_SDA")
	)
	(segment
		(start 95.681038 -103.301038)
		(end 88.6714 -96.2914)
		(width 0.127)
		(layer "In5.Cu")
		(net "I2C_SCC_SDA")
	)
	(segment
		(start 95.681038 -113.2967)
		(end 95.681038 -103.301038)
		(width 0.127)
		(layer "In5.Cu")
		(net "I2C_SCC_SDA")
	)
	(segment
		(start 116.197634 -26.035)
		(end 113.1824 -23.019766)
		(width 0.127)
		(layer "In5.Cu")
		(net "I2C_SCC_SDA")
	)
	(segment
		(start 100.140516 -23.019766)
		(end 89.6874 -33.472882)
		(width 0.127)
		(layer "In5.Cu")
		(net "I2C_SCC_SDA")
	)
	(segment
		(start 89.6874 -40.852598)
		(end 86.5505 -43.989498)
		(width 0.127)
		(layer "In5.Cu")
		(net "I2C_SCC_SDA")
	)
	(segment
		(start 89.6874 -33.472882)
		(end 89.6874 -40.852598)
		(width 0.127)
		(layer "In5.Cu")
		(net "I2C_SCC_SDA")
	)
	(segment
		(start 84.450174 -67.532758)
		(end 84.780628 -67.863212)
		(width 0.127)
		(layer "In5.Cu")
		(net "I2C_SCC_SDA")
	)
	(segment
		(start 123.698 -21.3868)
		(end 119.0498 -26.035)
		(width 0.127)
		(layer "In5.Cu")
		(net "I2C_SCC_SDA")
	)
	(segment
		(start 126.619 -21.3868)
		(end 123.698 -21.3868)
		(width 0.127)
		(layer "In5.Cu")
		(net "I2C_SCC_SDA")
	)
	(segment
		(start 83.8708 -144.2974)
		(end 84.969858 -144.2974)
		(width 0.127)
		(layer "F.Cu")
		(net "I2C_SCC_SCL_R")
	)
	(segment
		(start 82.563208 -142.779242)
		(end 81.616296 -142.779242)
		(width 0.127)
		(layer "F.Cu")
		(net "I2C_SCC_SCL_R")
	)
	(segment
		(start 83.8708 -144.2974)
		(end 83.6168 -144.0434)
		(width 0.127)
		(layer "F.Cu")
		(net "I2C_SCC_SCL_R")
	)
	(segment
		(start 83.6168 -143.832834)
		(end 82.563208 -142.779242)
		(width 0.127)
		(layer "F.Cu")
		(net "I2C_SCC_SCL_R")
	)
	(segment
		(start 83.6168 -144.0434)
		(end 83.6168 -143.832834)
		(width 0.127)
		(layer "F.Cu")
		(net "I2C_SCC_SCL_R")
	)
	(segment
		(start 84.969858 -144.2974)
		(end 85.01507 -144.252188)
		(width 0.127)
		(layer "F.Cu")
		(net "I2C_SCC_SCL_R")
	)
	(via
		(at 83.8708 -144.2974)
		(size 0.6604)
		(drill 0.3302)
		(layers "F.Cu" "B.Cu")
		(net "I2C_SCC_SCL_R")
	)
	(segment
		(start 62.458092 -144.404588)
		(end 61.48705 -144.404588)
		(width 0.127)
		(layer "F.Cu")
		(net "I2C_SCC_SCL_OUT")
	)
	(segment
		(start 62.593982 -144.268698)
		(end 62.458092 -144.404588)
		(width 0.127)
		(layer "F.Cu")
		(net "I2C_SCC_SCL_OUT")
	)
	(segment
		(start 75.977496 -143.429482)
		(end 77.173836 -143.429482)
		(width 0.127)
		(layer "F.Cu")
		(net "I2C_SCC_SCL_OUT")
	)
	(segment
		(start 65.727834 -145.034)
		(end 65.278 -145.034)
		(width 0.127)
		(layer "F.Cu")
		(net "I2C_SCC_SCL_OUT")
	)
	(segment
		(start 66.47053 -144.291304)
		(end 65.727834 -145.034)
		(width 0.127)
		(layer "F.Cu")
		(net "I2C_SCC_SCL_OUT")
	)
	(segment
		(start 66.724276 -144.291304)
		(end 66.47053 -144.291304)
		(width 0.127)
		(layer "F.Cu")
		(net "I2C_SCC_SCL_OUT")
	)
	(segment
		(start 65.278 -145.034)
		(end 64.897 -144.653)
		(width 0.127)
		(layer "F.Cu")
		(net "I2C_SCC_SCL_OUT")
	)
	(segment
		(start 64.24041 -144.653)
		(end 63.67145 -144.08404)
		(width 0.127)
		(layer "F.Cu")
		(net "I2C_SCC_SCL_OUT")
	)
	(segment
		(start 64.897 -144.653)
		(end 64.24041 -144.653)
		(width 0.127)
		(layer "F.Cu")
		(net "I2C_SCC_SCL_OUT")
	)
	(segment
		(start 62.593982 -144.268698)
		(end 62.77864 -144.08404)
		(width 0.127)
		(layer "F.Cu")
		(net "I2C_SCC_SCL_OUT")
	)
	(segment
		(start 77.173836 -143.429482)
		(end 77.326744 -143.276574)
		(width 0.127)
		(layer "F.Cu")
		(net "I2C_SCC_SCL_OUT")
	)
	(segment
		(start 62.77864 -144.08404)
		(end 63.67145 -144.08404)
		(width 0.127)
		(layer "F.Cu")
		(net "I2C_SCC_SCL_OUT")
	)
	(via
		(at 66.724276 -144.291304)
		(size 0.508)
		(drill 0.254)
		(layers "F.Cu" "B.Cu")
		(net "I2C_SCC_SCL_OUT")
	)
	(via
		(at 62.593982 -144.268698)
		(size 0.6604)
		(drill 0.3302)
		(layers "F.Cu" "B.Cu")
		(net "I2C_SCC_SCL_OUT")
	)
	(via
		(at 77.326744 -143.276574)
		(size 0.508)
		(drill 0.254)
		(layers "F.Cu" "B.Cu")
		(net "I2C_SCC_SCL_OUT")
	)
	(segment
		(start 68.134738 -144.291304)
		(end 66.724276 -144.291304)
		(width 0.127)
		(layer "In5.Cu")
		(net "I2C_SCC_SCL_OUT")
	)
	(segment
		(start 69.383148 -143.042894)
		(end 68.134738 -144.291304)
		(width 0.127)
		(layer "In5.Cu")
		(net "I2C_SCC_SCL_OUT")
	)
	(segment
		(start 77.326744 -143.276574)
		(end 76.525628 -142.475458)
		(width 0.127)
		(layer "In5.Cu")
		(net "I2C_SCC_SCL_OUT")
	)
	(segment
		(start 73.481946 -143.042894)
		(end 69.383148 -143.042894)
		(width 0.127)
		(layer "In5.Cu")
		(net "I2C_SCC_SCL_OUT")
	)
	(segment
		(start 74.049382 -142.475458)
		(end 73.481946 -143.042894)
		(width 0.127)
		(layer "In5.Cu")
		(net "I2C_SCC_SCL_OUT")
	)
	(segment
		(start 76.525628 -142.475458)
		(end 74.049382 -142.475458)
		(width 0.127)
		(layer "In5.Cu")
		(net "I2C_SCC_SCL_OUT")
	)
	(segment
		(start 86.69655 -144.252188)
		(end 86.755732 -144.193006)
		(width 0.127)
		(layer "F.Cu")
		(net "I2C_SCC_SCL")
	)
	(segment
		(start 128.7272 -22.0472)
		(end 131.244086 -24.564086)
		(width 0.127)
		(layer "F.Cu")
		(net "I2C_SCC_SCL")
	)
	(segment
		(start 87.042752 -125.926596)
		(end 87.56777 -126.451614)
		(width 0.127)
		(layer "F.Cu")
		(net "I2C_SCC_SCL")
	)
	(segment
		(start 91.295728 -113.314988)
		(end 87.042752 -117.567964)
		(width 0.127)
		(layer "F.Cu")
		(net "I2C_SCC_SCL")
	)
	(segment
		(start 96.249998 -112.646714)
		(end 96.247712 -112.649)
		(width 0.127)
		(layer "F.Cu")
		(net "I2C_SCC_SCL")
	)
	(segment
		(start 87.9602 -70.324218)
		(end 86.3854 -68.749418)
		(width 0.127)
		(layer "F.Cu")
		(net "I2C_SCC_SCL")
	)
	(segment
		(start 135.544306 -24.564086)
		(end 140.134594 -29.154374)
		(width 0.127)
		(layer "F.Cu")
		(net "I2C_SCC_SCL")
	)
	(segment
		(start 87.042752 -117.567964)
		(end 87.042752 -125.926596)
		(width 0.127)
		(layer "F.Cu")
		(net "I2C_SCC_SCL")
	)
	(segment
		(start 86.3854 -68.426584)
		(end 84.958428 -66.999612)
		(width 0.127)
		(layer "F.Cu")
		(net "I2C_SCC_SCL")
	)
	(segment
		(start 86.3854 -68.749418)
		(end 86.3854 -68.426584)
		(width 0.127)
		(layer "F.Cu")
		(net "I2C_SCC_SCL")
	)
	(segment
		(start 94.251272 -113.314988)
		(end 91.295728 -113.314988)
		(width 0.127)
		(layer "F.Cu")
		(net "I2C_SCC_SCL")
	)
	(segment
		(start 140.134594 -29.154374)
		(end 140.134594 -39.765224)
		(width 0.127)
		(layer "F.Cu")
		(net "I2C_SCC_SCL")
	)
	(segment
		(start 127.2794 -22.0472)
		(end 128.7272 -22.0472)
		(width 0.127)
		(layer "F.Cu")
		(net "I2C_SCC_SCL")
	)
	(segment
		(start 131.244086 -24.564086)
		(end 135.544306 -24.564086)
		(width 0.127)
		(layer "F.Cu")
		(net "I2C_SCC_SCL")
	)
	(segment
		(start 96.247712 -112.649)
		(end 94.91726 -112.649)
		(width 0.127)
		(layer "F.Cu")
		(net "I2C_SCC_SCL")
	)
	(segment
		(start 87.9602 -95.1484)
		(end 87.9602 -70.324218)
		(width 0.127)
		(layer "F.Cu")
		(net "I2C_SCC_SCL")
	)
	(segment
		(start 140.134594 -39.765224)
		(end 139.499848 -40.39997)
		(width 0.127)
		(layer "F.Cu")
		(net "I2C_SCC_SCL")
	)
	(segment
		(start 85.90407 -144.252188)
		(end 86.69655 -144.252188)
		(width 0.127)
		(layer "F.Cu")
		(net "I2C_SCC_SCL")
	)
	(segment
		(start 94.91726 -112.649)
		(end 94.251272 -113.314988)
		(width 0.127)
		(layer "F.Cu")
		(net "I2C_SCC_SCL")
	)
	(via
		(at 85.7504 -130.937)
		(size 0.6096)
		(drill 0.3048)
		(layers "F.Cu" "B.Cu")
		(net "I2C_SCC_SCL")
	)
	(via
		(at 96.249998 -112.646714)
		(size 0.508)
		(drill 0.254)
		(layers "F.Cu" "B.Cu")
		(net "I2C_SCC_SCL")
	)
	(via
		(at 127.2794 -22.0472)
		(size 0.508)
		(drill 0.254)
		(layers "F.Cu" "B.Cu")
		(net "I2C_SCC_SCL")
	)
	(via
		(at 84.958428 -66.999612)
		(size 0.508)
		(drill 0.254)
		(layers "F.Cu" "B.Cu")
		(net "I2C_SCC_SCL")
	)
	(via
		(at 86.755732 -144.193006)
		(size 0.508)
		(drill 0.254)
		(layers "F.Cu" "B.Cu")
		(net "I2C_SCC_SCL")
	)
	(via
		(at 87.56777 -126.451614)
		(size 0.508)
		(drill 0.254)
		(layers "F.Cu" "B.Cu")
		(net "I2C_SCC_SCL")
	)
	(via
		(at 87.9602 -95.1484)
		(size 0.508)
		(drill 0.254)
		(layers "F.Cu" "B.Cu")
		(net "I2C_SCC_SCL")
	)
	(segment
		(start 86.302342 -127.717042)
		(end 87.56777 -126.451614)
		(width 0.127)
		(layer "B.Cu")
		(net "I2C_SCC_SCL")
	)
	(segment
		(start 84.987384 -131.700016)
		(end 85.7504 -130.937)
		(width 0.127)
		(layer "B.Cu")
		(net "I2C_SCC_SCL")
	)
	(segment
		(start 84.987384 -136.25322)
		(end 84.987384 -131.700016)
		(width 0.127)
		(layer "B.Cu")
		(net "I2C_SCC_SCL")
	)
	(segment
		(start 85.7504 -130.937)
		(end 85.7504 -130.4798)
		(width 0.127)
		(layer "B.Cu")
		(net "I2C_SCC_SCL")
	)
	(segment
		(start 86.755732 -144.193006)
		(end 86.135464 -143.572738)
		(width 0.127)
		(layer "B.Cu")
		(net "I2C_SCC_SCL")
	)
	(segment
		(start 86.135464 -143.572738)
		(end 86.135464 -137.4013)
		(width 0.127)
		(layer "B.Cu")
		(net "I2C_SCC_SCL")
	)
	(segment
		(start 85.7504 -130.4798)
		(end 86.302342 -129.927858)
		(width 0.127)
		(layer "B.Cu")
		(net "I2C_SCC_SCL")
	)
	(segment
		(start 86.135464 -137.4013)
		(end 84.987384 -136.25322)
		(width 0.127)
		(layer "B.Cu")
		(net "I2C_SCC_SCL")
	)
	(segment
		(start 86.302342 -129.927858)
		(end 86.302342 -127.717042)
		(width 0.127)
		(layer "B.Cu")
		(net "I2C_SCC_SCL")
	)
	(segment
		(start 87.0585 -64.89954)
		(end 84.958428 -66.999612)
		(width 0.127)
		(layer "In5.Cu")
		(net "I2C_SCC_SCL")
	)
	(segment
		(start 88.246966 -95.1484)
		(end 87.9602 -95.1484)
		(width 0.127)
		(layer "In5.Cu")
		(net "I2C_SCC_SCL")
	)
	(segment
		(start 123.7742 -22.0472)
		(end 119.2784 -26.543)
		(width 0.127)
		(layer "In5.Cu")
		(net "I2C_SCC_SCL")
	)
	(segment
		(start 119.2784 -26.543)
		(end 115.987068 -26.543)
		(width 0.127)
		(layer "In5.Cu")
		(net "I2C_SCC_SCL")
	)
	(segment
		(start 112.971834 -23.527766)
		(end 102.04831 -23.527766)
		(width 0.127)
		(layer "In5.Cu")
		(net "I2C_SCC_SCL")
	)
	(segment
		(start 90.2462 -35.329876)
		(end 90.2462 -41.012364)
		(width 0.127)
		(layer "In5.Cu")
		(net "I2C_SCC_SCL")
	)
	(segment
		(start 87.0585 -44.200064)
		(end 87.0585 -64.89954)
		(width 0.127)
		(layer "In5.Cu")
		(net "I2C_SCC_SCL")
	)
	(segment
		(start 96.249998 -103.151432)
		(end 88.246966 -95.1484)
		(width 0.127)
		(layer "In5.Cu")
		(net "I2C_SCC_SCL")
	)
	(segment
		(start 115.987068 -26.543)
		(end 112.971834 -23.527766)
		(width 0.127)
		(layer "In5.Cu")
		(net "I2C_SCC_SCL")
	)
	(segment
		(start 96.249998 -112.646714)
		(end 96.249998 -103.151432)
		(width 0.127)
		(layer "In5.Cu")
		(net "I2C_SCC_SCL")
	)
	(segment
		(start 127.2794 -22.0472)
		(end 123.7742 -22.0472)
		(width 0.127)
		(layer "In5.Cu")
		(net "I2C_SCC_SCL")
	)
	(segment
		(start 90.2462 -41.012364)
		(end 87.0585 -44.200064)
		(width 0.127)
		(layer "In5.Cu")
		(net "I2C_SCC_SCL")
	)
	(segment
		(start 102.04831 -23.527766)
		(end 90.2462 -35.329876)
		(width 0.127)
		(layer "In5.Cu")
		(net "I2C_SCC_SCL")
	)
	(segment
		(start 75.475084 -59.349894)
		(end 76.96073 -59.349894)
		(width 0.127)
		(layer "F.Cu")
		(net "I2C_MEZZ_ALERT_R_N")
	)
	(segment
		(start 85.970872 -58.973974)
		(end 85.743034 -59.201812)
		(width 0.127)
		(layer "F.Cu")
		(net "I2C_MEZZ_ALERT_R_N")
	)
	(segment
		(start 76.96073 -59.349894)
		(end 77.668628 -58.641996)
		(width 0.127)
		(layer "F.Cu")
		(net "I2C_MEZZ_ALERT_R_N")
	)
	(segment
		(start 86.428072 -58.973974)
		(end 85.970872 -58.973974)
		(width 0.127)
		(layer "F.Cu")
		(net "I2C_MEZZ_ALERT_R_N")
	)
	(segment
		(start 85.743034 -59.201812)
		(end 85.114892 -59.201812)
		(width 0.127)
		(layer "F.Cu")
		(net "I2C_MEZZ_ALERT_R_N")
	)
	(via
		(at 77.668628 -58.641996)
		(size 0.508)
		(drill 0.254)
		(layers "F.Cu" "B.Cu")
		(net "I2C_MEZZ_ALERT_R_N")
	)
	(via
		(at 85.114892 -59.201812)
		(size 0.508)
		(drill 0.254)
		(layers "F.Cu" "B.Cu")
		(net "I2C_MEZZ_ALERT_R_N")
	)
	(via
		(at 85.1154 -60.325)
		(size 0.6096)
		(drill 0.3048)
		(layers "F.Cu" "B.Cu")
		(net "I2C_MEZZ_ALERT_R_N")
	)
	(segment
		(start 85.1154 -60.325)
		(end 85.1154 -60.7314)
		(width 0.127)
		(layer "B.Cu")
		(net "I2C_MEZZ_ALERT_R_N")
	)
	(segment
		(start 85.1154 -60.325)
		(end 85.1154 -59.20232)
		(width 0.127)
		(layer "B.Cu")
		(net "I2C_MEZZ_ALERT_R_N")
	)
	(segment
		(start 80.088232 -61.0616)
		(end 77.668628 -58.641996)
		(width 0.127)
		(layer "B.Cu")
		(net "I2C_MEZZ_ALERT_R_N")
	)
	(segment
		(start 84.7852 -61.0616)
		(end 80.088232 -61.0616)
		(width 0.127)
		(layer "B.Cu")
		(net "I2C_MEZZ_ALERT_R_N")
	)
	(segment
		(start 85.1154 -59.20232)
		(end 85.114892 -59.201812)
		(width 0.127)
		(layer "B.Cu")
		(net "I2C_MEZZ_ALERT_R_N")
	)
	(segment
		(start 85.1154 -60.7314)
		(end 84.7852 -61.0616)
		(width 0.127)
		(layer "B.Cu")
		(net "I2C_MEZZ_ALERT_R_N")
	)
	(segment
		(start 88.9762 -112.649)
		(end 87.7824 -112.649)
		(width 0.127)
		(layer "F.Cu")
		(net "I2C_MEZZ_ALERT_N")
	)
	(segment
		(start 87.7824 -112.649)
		(end 87.6046 -112.4712)
		(width 0.127)
		(layer "F.Cu")
		(net "I2C_MEZZ_ALERT_N")
	)
	(segment
		(start 87.317072 -58.973974)
		(end 87.317072 -57.923938)
		(width 0.127)
		(layer "F.Cu")
		(net "I2C_MEZZ_ALERT_N")
	)
	(segment
		(start 97.3201 -108.27004)
		(end 93.672152 -111.917988)
		(width 0.127)
		(layer "F.Cu")
		(net "I2C_MEZZ_ALERT_N")
	)
	(segment
		(start 97.3201 -91.456002)
		(end 97.3201 -108.27004)
		(width 0.127)
		(layer "F.Cu")
		(net "I2C_MEZZ_ALERT_N")
	)
	(segment
		(start 94.172786 -64.71031)
		(end 94.172786 -88.308688)
		(width 0.127)
		(layer "F.Cu")
		(net "I2C_MEZZ_ALERT_N")
	)
	(segment
		(start 89.821258 -112.649)
		(end 88.9762 -112.649)
		(width 0.127)
		(layer "F.Cu")
		(net "I2C_MEZZ_ALERT_N")
	)
	(segment
		(start 94.172786 -88.308688)
		(end 97.3201 -91.456002)
		(width 0.127)
		(layer "F.Cu")
		(net "I2C_MEZZ_ALERT_N")
	)
	(segment
		(start 93.672152 -111.917988)
		(end 90.55227 -111.917988)
		(width 0.127)
		(layer "F.Cu")
		(net "I2C_MEZZ_ALERT_N")
	)
	(segment
		(start 90.471498 -61.009022)
		(end 94.172786 -64.71031)
		(width 0.127)
		(layer "F.Cu")
		(net "I2C_MEZZ_ALERT_N")
	)
	(segment
		(start 87.317072 -58.973974)
		(end 87.317072 -60.006484)
		(width 0.127)
		(layer "F.Cu")
		(net "I2C_MEZZ_ALERT_N")
	)
	(segment
		(start 87.317072 -60.006484)
		(end 88.31961 -61.009022)
		(width 0.127)
		(layer "F.Cu")
		(net "I2C_MEZZ_ALERT_N")
	)
	(segment
		(start 46.100238 -139.400534)
		(end 46.100492 -139.400534)
		(width 0.127)
		(layer "F.Cu")
		(net "I2C_MEZZ_ALERT_N")
	)
	(segment
		(start 88.31961 -61.009022)
		(end 90.471498 -61.009022)
		(width 0.127)
		(layer "F.Cu")
		(net "I2C_MEZZ_ALERT_N")
	)
	(segment
		(start 90.55227 -111.917988)
		(end 89.821258 -112.649)
		(width 0.127)
		(layer "F.Cu")
		(net "I2C_MEZZ_ALERT_N")
	)
	(segment
		(start 87.317072 -57.923938)
		(end 87.324692 -57.916318)
		(width 0.127)
		(layer "F.Cu")
		(net "I2C_MEZZ_ALERT_N")
	)
	(segment
		(start 46.100492 -139.400534)
		(end 46.500034 -139.800076)
		(width 0.127)
		(layer "F.Cu")
		(net "I2C_MEZZ_ALERT_N")
	)
	(via
		(at 46.100238 -139.400534)
		(size 0.4572)
		(drill 0.2032)
		(layers "F.Cu" "B.Cu")
		(net "I2C_MEZZ_ALERT_N")
	)
	(via
		(at 88.9762 -112.649)
		(size 0.6604)
		(drill 0.3302)
		(layers "F.Cu" "B.Cu")
		(net "I2C_MEZZ_ALERT_N")
	)
	(via
		(at 43.570398 -117.9576)
		(size 0.508)
		(drill 0.254)
		(layers "F.Cu" "B.Cu")
		(net "I2C_MEZZ_ALERT_N")
	)
	(via
		(at 87.6046 -112.4712)
		(size 0.508)
		(drill 0.254)
		(layers "F.Cu" "B.Cu")
		(net "I2C_MEZZ_ALERT_N")
	)
	(segment
		(start 45.085 -133.64083)
		(end 45.085 -137.725658)
		(width 0.127)
		(layer "In2.Cu")
		(net "I2C_MEZZ_ALERT_N")
	)
	(segment
		(start 44.983146 -133.538976)
		(end 45.085 -133.64083)
		(width 0.127)
		(layer "In2.Cu")
		(net "I2C_MEZZ_ALERT_N")
	)
	(segment
		(start 43.9547 -126.7079)
		(end 43.9547 -128.1811)
		(width 0.127)
		(layer "In2.Cu")
		(net "I2C_MEZZ_ALERT_N")
	)
	(segment
		(start 44.924472 -129.150872)
		(end 44.924472 -129.697734)
		(width 0.127)
		(layer "In2.Cu")
		(net "I2C_MEZZ_ALERT_N")
	)
	(segment
		(start 43.570398 -117.9576)
		(end 44.3865 -118.773702)
		(width 0.127)
		(layer "In2.Cu")
		(net "I2C_MEZZ_ALERT_N")
	)
	(segment
		(start 44.983146 -129.756408)
		(end 44.983146 -133.538976)
		(width 0.127)
		(layer "In2.Cu")
		(net "I2C_MEZZ_ALERT_N")
	)
	(segment
		(start 45.085 -137.725658)
		(end 45.693584 -138.334242)
		(width 0.127)
		(layer "In2.Cu")
		(net "I2C_MEZZ_ALERT_N")
	)
	(segment
		(start 44.3865 -126.2761)
		(end 43.9547 -126.7079)
		(width 0.127)
		(layer "In2.Cu")
		(net "I2C_MEZZ_ALERT_N")
	)
	(segment
		(start 44.3865 -118.773702)
		(end 44.3865 -126.2761)
		(width 0.127)
		(layer "In2.Cu")
		(net "I2C_MEZZ_ALERT_N")
	)
	(segment
		(start 44.924472 -129.697734)
		(end 44.983146 -129.756408)
		(width 0.127)
		(layer "In2.Cu")
		(net "I2C_MEZZ_ALERT_N")
	)
	(segment
		(start 43.9547 -128.1811)
		(end 44.924472 -129.150872)
		(width 0.127)
		(layer "In2.Cu")
		(net "I2C_MEZZ_ALERT_N")
	)
	(segment
		(start 45.693584 -138.334242)
		(end 45.693584 -138.99388)
		(width 0.127)
		(layer "In2.Cu")
		(net "I2C_MEZZ_ALERT_N")
	)
	(segment
		(start 45.693584 -138.99388)
		(end 46.100238 -139.400534)
		(width 0.127)
		(layer "In2.Cu")
		(net "I2C_MEZZ_ALERT_N")
	)
	(segment
		(start 68.636134 -115.6081)
		(end 68.013834 -116.2304)
		(width 0.127)
		(layer "In5.Cu")
		(net "I2C_MEZZ_ALERT_N")
	)
	(segment
		(start 46.096936 -117.2972)
		(end 44.230798 -117.2972)
		(width 0.127)
		(layer "In5.Cu")
		(net "I2C_MEZZ_ALERT_N")
	)
	(segment
		(start 53.737002 -115.944904)
		(end 53.730906 -115.951)
		(width 0.127)
		(layer "In5.Cu")
		(net "I2C_MEZZ_ALERT_N")
	)
	(segment
		(start 58.96229 -117.1702)
		(end 57.74309 -115.951)
		(width 0.127)
		(layer "In5.Cu")
		(net "I2C_MEZZ_ALERT_N")
	)
	(segment
		(start 53.730906 -115.951)
		(end 47.443136 -115.951)
		(width 0.127)
		(layer "In5.Cu")
		(net "I2C_MEZZ_ALERT_N")
	)
	(segment
		(start 85.747098 -111.887)
		(end 76.598272 -111.887)
		(width 0.127)
		(layer "In5.Cu")
		(net "I2C_MEZZ_ALERT_N")
	)
	(segment
		(start 72.877172 -115.6081)
		(end 68.636134 -115.6081)
		(width 0.127)
		(layer "In5.Cu")
		(net "I2C_MEZZ_ALERT_N")
	)
	(segment
		(start 65.278 -116.2304)
		(end 64.3382 -117.1702)
		(width 0.127)
		(layer "In5.Cu")
		(net "I2C_MEZZ_ALERT_N")
	)
	(segment
		(start 76.598272 -111.887)
		(end 72.877172 -115.6081)
		(width 0.127)
		(layer "In5.Cu")
		(net "I2C_MEZZ_ALERT_N")
	)
	(segment
		(start 87.6046 -112.4712)
		(end 86.331298 -112.4712)
		(width 0.127)
		(layer "In5.Cu")
		(net "I2C_MEZZ_ALERT_N")
	)
	(segment
		(start 54.54777 -115.944904)
		(end 53.737002 -115.944904)
		(width 0.127)
		(layer "In5.Cu")
		(net "I2C_MEZZ_ALERT_N")
	)
	(segment
		(start 54.553866 -115.951)
		(end 54.54777 -115.944904)
		(width 0.127)
		(layer "In5.Cu")
		(net "I2C_MEZZ_ALERT_N")
	)
	(segment
		(start 86.331298 -112.4712)
		(end 85.747098 -111.887)
		(width 0.127)
		(layer "In5.Cu")
		(net "I2C_MEZZ_ALERT_N")
	)
	(segment
		(start 64.3382 -117.1702)
		(end 58.96229 -117.1702)
		(width 0.127)
		(layer "In5.Cu")
		(net "I2C_MEZZ_ALERT_N")
	)
	(segment
		(start 47.443136 -115.951)
		(end 46.096936 -117.2972)
		(width 0.127)
		(layer "In5.Cu")
		(net "I2C_MEZZ_ALERT_N")
	)
	(segment
		(start 68.013834 -116.2304)
		(end 65.278 -116.2304)
		(width 0.127)
		(layer "In5.Cu")
		(net "I2C_MEZZ_ALERT_N")
	)
	(segment
		(start 57.74309 -115.951)
		(end 54.553866 -115.951)
		(width 0.127)
		(layer "In5.Cu")
		(net "I2C_MEZZ_ALERT_N")
	)
	(segment
		(start 44.230798 -117.2972)
		(end 43.570398 -117.9576)
		(width 0.127)
		(layer "In5.Cu")
		(net "I2C_MEZZ_ALERT_N")
	)
	(segment
		(start 83.0834 -144.018)
		(end 82.494882 -143.429482)
		(width 0.127)
		(layer "F.Cu")
		(net "I2C_EXP_RMT_SDA_R")
	)
	(segment
		(start 83.0834 -144.9578)
		(end 83.0834 -144.018)
		(width 0.127)
		(layer "F.Cu")
		(net "I2C_EXP_RMT_SDA_R")
	)
	(segment
		(start 82.494882 -143.429482)
		(end 81.616296 -143.429482)
		(width 0.127)
		(layer "F.Cu")
		(net "I2C_EXP_RMT_SDA_R")
	)
	(segment
		(start 83.3628 -145.2372)
		(end 83.0834 -144.9578)
		(width 0.127)
		(layer "F.Cu")
		(net "I2C_EXP_RMT_SDA_R")
	)
	(segment
		(start 85.026246 -145.471134)
		(end 83.596734 -145.471134)
		(width 0.127)
		(layer "F.Cu")
		(net "I2C_EXP_RMT_SDA_R")
	)
	(segment
		(start 83.596734 -145.471134)
		(end 83.3628 -145.2372)
		(width 0.127)
		(layer "F.Cu")
		(net "I2C_EXP_RMT_SDA_R")
	)
	(via
		(at 83.3628 -145.2372)
		(size 0.6604)
		(drill 0.3302)
		(layers "F.Cu" "B.Cu")
		(net "I2C_EXP_RMT_SDA_R")
	)
	(segment
		(start 68.15582 -141.70787)
		(end 69.72935 -143.2814)
		(width 0.127)
		(layer "F.Cu")
		(net "I2C_EXP_RMT_SDA_OUT")
	)
	(segment
		(start 61.733684 -142.341092)
		(end 62.540388 -141.534388)
		(width 0.127)
		(layer "F.Cu")
		(net "I2C_EXP_RMT_SDA_OUT")
	)
	(segment
		(start 67.641978 -141.712442)
		(end 67.64655 -141.70787)
		(width 0.127)
		(layer "F.Cu")
		(net "I2C_EXP_RMT_SDA_OUT")
	)
	(segment
		(start 69.72935 -143.2814)
		(end 73.73239 -143.2814)
		(width 0.127)
		(layer "F.Cu")
		(net "I2C_EXP_RMT_SDA_OUT")
	)
	(segment
		(start 62.616588 -141.534388)
		(end 62.657482 -141.493494)
		(width 0.127)
		(layer "F.Cu")
		(net "I2C_EXP_RMT_SDA_OUT")
	)
	(segment
		(start 65.505838 -141.979396)
		(end 65.772792 -141.712442)
		(width 0.127)
		(layer "F.Cu")
		(net "I2C_EXP_RMT_SDA_OUT")
	)
	(segment
		(start 74.530712 -144.079722)
		(end 75.977496 -144.079722)
		(width 0.127)
		(layer "F.Cu")
		(net "I2C_EXP_RMT_SDA_OUT")
	)
	(segment
		(start 62.540388 -141.534388)
		(end 62.616588 -141.534388)
		(width 0.127)
		(layer "F.Cu")
		(net "I2C_EXP_RMT_SDA_OUT")
	)
	(segment
		(start 62.657482 -141.493494)
		(end 62.978284 -141.493494)
		(width 0.127)
		(layer "F.Cu")
		(net "I2C_EXP_RMT_SDA_OUT")
	)
	(segment
		(start 67.64655 -141.70787)
		(end 68.15582 -141.70787)
		(width 0.127)
		(layer "F.Cu")
		(net "I2C_EXP_RMT_SDA_OUT")
	)
	(segment
		(start 73.73239 -143.2814)
		(end 74.530712 -144.079722)
		(width 0.127)
		(layer "F.Cu")
		(net "I2C_EXP_RMT_SDA_OUT")
	)
	(segment
		(start 62.978284 -141.493494)
		(end 63.464186 -141.979396)
		(width 0.127)
		(layer "F.Cu")
		(net "I2C_EXP_RMT_SDA_OUT")
	)
	(segment
		(start 63.464186 -141.979396)
		(end 65.505838 -141.979396)
		(width 0.127)
		(layer "F.Cu")
		(net "I2C_EXP_RMT_SDA_OUT")
	)
	(segment
		(start 65.772792 -141.712442)
		(end 67.641978 -141.712442)
		(width 0.127)
		(layer "F.Cu")
		(net "I2C_EXP_RMT_SDA_OUT")
	)
	(via
		(at 67.64655 -141.70787)
		(size 0.6604)
		(drill 0.3302)
		(layers "F.Cu" "B.Cu")
		(net "I2C_EXP_RMT_SDA_OUT")
	)
	(segment
		(start 87.295228 -143.503396)
		(end 87.582248 -143.216376)
		(width 0.127)
		(layer "F.Cu")
		(net "I2C_EXP_RMT_SDA")
	)
	(segment
		(start 86.710266 -145.471134)
		(end 86.9442 -145.2372)
		(width 0.127)
		(layer "F.Cu")
		(net "I2C_EXP_RMT_SDA")
	)
	(segment
		(start 87.295228 -144.886172)
		(end 87.295228 -143.503396)
		(width 0.127)
		(layer "F.Cu")
		(net "I2C_EXP_RMT_SDA")
	)
	(segment
		(start 86.9442 -145.2372)
		(end 87.295228 -144.886172)
		(width 0.127)
		(layer "F.Cu")
		(net "I2C_EXP_RMT_SDA")
	)
	(segment
		(start 85.915246 -145.471134)
		(end 86.710266 -145.471134)
		(width 0.127)
		(layer "F.Cu")
		(net "I2C_EXP_RMT_SDA")
	)
	(via
		(at 87.582248 -143.216376)
		(size 0.508)
		(drill 0.254)
		(layers "F.Cu" "B.Cu")
		(net "I2C_EXP_RMT_SDA")
	)
	(via
		(at 86.9442 -145.2372)
		(size 0.6604)
		(drill 0.3302)
		(layers "F.Cu" "B.Cu")
		(net "I2C_EXP_RMT_SDA")
	)
	(segment
		(start 114.308636 -19.882104)
		(end 116.905532 -22.479)
		(width 0.127)
		(layer "In2.Cu")
		(net "I2C_EXP_RMT_SDA")
	)
	(segment
		(start 88.627966 -132.931408)
		(end 88.627966 -126.667514)
		(width 0.127)
		(layer "In2.Cu")
		(net "I2C_EXP_RMT_SDA")
	)
	(segment
		(start 91.7956 -98.1456)
		(end 91.7956 -94.4118)
		(width 0.127)
		(layer "In2.Cu")
		(net "I2C_EXP_RMT_SDA")
	)
	(segment
		(start 88.99398 -143.38681)
		(end 88.99398 -133.297422)
		(width 0.127)
		(layer "In2.Cu")
		(net "I2C_EXP_RMT_SDA")
	)
	(segment
		(start 91.7956 -94.4118)
		(end 91.3765 -93.9927)
		(width 0.127)
		(layer "In2.Cu")
		(net "I2C_EXP_RMT_SDA")
	)
	(segment
		(start 94.26067 -28.322524)
		(end 102.70109 -19.882104)
		(width 0.127)
		(layer "In2.Cu")
		(net "I2C_EXP_RMT_SDA")
	)
	(segment
		(start 118.764304 -22.479)
		(end 126.543816 -30.258512)
		(width 0.127)
		(layer "In2.Cu")
		(net "I2C_EXP_RMT_SDA")
	)
	(segment
		(start 90.320368 -113.4618)
		(end 90.320368 -112.263936)
		(width 0.127)
		(layer "In2.Cu")
		(net "I2C_EXP_RMT_SDA")
	)
	(segment
		(start 90.7415 -48.1711)
		(end 91.862148 -47.050452)
		(width 0.127)
		(layer "In2.Cu")
		(net "I2C_EXP_RMT_SDA")
	)
	(segment
		(start 92.4052 -110.179104)
		(end 92.4052 -98.7552)
		(width 0.127)
		(layer "In2.Cu")
		(net "I2C_EXP_RMT_SDA")
	)
	(segment
		(start 131.132326 -40.63238)
		(end 132.299964 -41.800018)
		(width 0.127)
		(layer "In2.Cu")
		(net "I2C_EXP_RMT_SDA")
	)
	(segment
		(start 89.6874 -119.662702)
		(end 89.776554 -119.573548)
		(width 0.127)
		(layer "In2.Cu")
		(net "I2C_EXP_RMT_SDA")
	)
	(segment
		(start 91.862148 -35.048952)
		(end 94.26067 -32.65043)
		(width 0.127)
		(layer "In2.Cu")
		(net "I2C_EXP_RMT_SDA")
	)
	(segment
		(start 91.862148 -47.050452)
		(end 91.862148 -35.048952)
		(width 0.127)
		(layer "In2.Cu")
		(net "I2C_EXP_RMT_SDA")
	)
	(segment
		(start 94.26067 -32.65043)
		(end 94.26067 -28.322524)
		(width 0.127)
		(layer "In2.Cu")
		(net "I2C_EXP_RMT_SDA")
	)
	(segment
		(start 89.6874 -125.60808)
		(end 89.6874 -119.662702)
		(width 0.127)
		(layer "In2.Cu")
		(net "I2C_EXP_RMT_SDA")
	)
	(segment
		(start 91.3765 -53.283866)
		(end 90.7415 -52.648866)
		(width 0.127)
		(layer "In2.Cu")
		(net "I2C_EXP_RMT_SDA")
	)
	(segment
		(start 90.7415 -52.648866)
		(end 90.7415 -48.1711)
		(width 0.127)
		(layer "In2.Cu")
		(net "I2C_EXP_RMT_SDA")
	)
	(segment
		(start 89.776554 -114.005614)
		(end 90.320368 -113.4618)
		(width 0.127)
		(layer "In2.Cu")
		(net "I2C_EXP_RMT_SDA")
	)
	(segment
		(start 89.776554 -119.573548)
		(end 89.776554 -114.005614)
		(width 0.127)
		(layer "In2.Cu")
		(net "I2C_EXP_RMT_SDA")
	)
	(segment
		(start 131.132326 -30.724348)
		(end 131.132326 -40.63238)
		(width 0.127)
		(layer "In2.Cu")
		(net "I2C_EXP_RMT_SDA")
	)
	(segment
		(start 92.4052 -98.7552)
		(end 91.7956 -98.1456)
		(width 0.127)
		(layer "In2.Cu")
		(net "I2C_EXP_RMT_SDA")
	)
	(segment
		(start 126.543816 -30.258512)
		(end 130.66649 -30.258512)
		(width 0.127)
		(layer "In2.Cu")
		(net "I2C_EXP_RMT_SDA")
	)
	(segment
		(start 130.66649 -30.258512)
		(end 131.132326 -30.724348)
		(width 0.127)
		(layer "In2.Cu")
		(net "I2C_EXP_RMT_SDA")
	)
	(segment
		(start 88.627966 -126.667514)
		(end 89.6874 -125.60808)
		(width 0.127)
		(layer "In2.Cu")
		(net "I2C_EXP_RMT_SDA")
	)
	(segment
		(start 88.99398 -133.297422)
		(end 88.627966 -132.931408)
		(width 0.127)
		(layer "In2.Cu")
		(net "I2C_EXP_RMT_SDA")
	)
	(segment
		(start 88.696546 -143.684244)
		(end 88.99398 -143.38681)
		(width 0.127)
		(layer "In2.Cu")
		(net "I2C_EXP_RMT_SDA")
	)
	(segment
		(start 91.3765 -93.9927)
		(end 91.3765 -53.283866)
		(width 0.127)
		(layer "In2.Cu")
		(net "I2C_EXP_RMT_SDA")
	)
	(segment
		(start 102.70109 -19.882104)
		(end 114.308636 -19.882104)
		(width 0.127)
		(layer "In2.Cu")
		(net "I2C_EXP_RMT_SDA")
	)
	(segment
		(start 88.050116 -143.684244)
		(end 88.696546 -143.684244)
		(width 0.127)
		(layer "In2.Cu")
		(net "I2C_EXP_RMT_SDA")
	)
	(segment
		(start 90.320368 -112.263936)
		(end 92.4052 -110.179104)
		(width 0.127)
		(layer "In2.Cu")
		(net "I2C_EXP_RMT_SDA")
	)
	(segment
		(start 116.905532 -22.479)
		(end 118.764304 -22.479)
		(width 0.127)
		(layer "In2.Cu")
		(net "I2C_EXP_RMT_SDA")
	)
	(segment
		(start 87.582248 -143.216376)
		(end 88.050116 -143.684244)
		(width 0.127)
		(layer "In2.Cu")
		(net "I2C_EXP_RMT_SDA")
	)
	(segment
		(start 82.281522 -144.079722)
		(end 81.616296 -144.079722)
		(width 0.127)
		(layer "F.Cu")
		(net "I2C_EXP_RMT_SCL_R")
	)
	(segment
		(start 83.432396 -146.519646)
		(end 83.279996 -146.367246)
		(width 0.127)
		(layer "F.Cu")
		(net "I2C_EXP_RMT_SCL_R")
	)
	(segment
		(start 82.5754 -145.66265)
		(end 82.5754 -144.3736)
		(width 0.127)
		(layer "F.Cu")
		(net "I2C_EXP_RMT_SCL_R")
	)
	(segment
		(start 84.455762 -146.519646)
		(end 83.432396 -146.519646)
		(width 0.127)
		(layer "F.Cu")
		(net "I2C_EXP_RMT_SCL_R")
	)
	(segment
		(start 82.5754 -144.3736)
		(end 82.281522 -144.079722)
		(width 0.127)
		(layer "F.Cu")
		(net "I2C_EXP_RMT_SCL_R")
	)
	(segment
		(start 83.279996 -146.367246)
		(end 82.5754 -145.66265)
		(width 0.127)
		(layer "F.Cu")
		(net "I2C_EXP_RMT_SCL_R")
	)
	(via
		(at 83.279996 -146.367246)
		(size 0.6604)
		(drill 0.3302)
		(layers "F.Cu" "B.Cu")
		(net "I2C_EXP_RMT_SCL_R")
	)
	(segment
		(start 66.396616 -142.74419)
		(end 66.716402 -143.063976)
		(width 0.127)
		(layer "F.Cu")
		(net "I2C_EXP_RMT_SCL_OUT")
	)
	(segment
		(start 69.167248 -143.7894)
		(end 73.521824 -143.7894)
		(width 0.127)
		(layer "F.Cu")
		(net "I2C_EXP_RMT_SCL_OUT")
	)
	(segment
		(start 63.51143 -142.5067)
		(end 66.1543 -142.5067)
		(width 0.127)
		(layer "F.Cu")
		(net "I2C_EXP_RMT_SCL_OUT")
	)
	(segment
		(start 69.133212 -143.755364)
		(end 69.167248 -143.7894)
		(width 0.127)
		(layer "F.Cu")
		(net "I2C_EXP_RMT_SCL_OUT")
	)
	(segment
		(start 69.079364 -143.755364)
		(end 69.133212 -143.755364)
		(width 0.127)
		(layer "F.Cu")
		(net "I2C_EXP_RMT_SCL_OUT")
	)
	(segment
		(start 73.521824 -143.7894)
		(end 74.462386 -144.729962)
		(width 0.127)
		(layer "F.Cu")
		(net "I2C_EXP_RMT_SCL_OUT")
	)
	(segment
		(start 66.39179 -142.74419)
		(end 66.396616 -142.74419)
		(width 0.127)
		(layer "F.Cu")
		(net "I2C_EXP_RMT_SCL_OUT")
	)
	(segment
		(start 67.402964 -143.755364)
		(end 69.079364 -143.755364)
		(width 0.127)
		(layer "F.Cu")
		(net "I2C_EXP_RMT_SCL_OUT")
	)
	(segment
		(start 62.096904 -143.019272)
		(end 62.998858 -143.019272)
		(width 0.127)
		(layer "F.Cu")
		(net "I2C_EXP_RMT_SCL_OUT")
	)
	(segment
		(start 62.998858 -143.019272)
		(end 63.51143 -142.5067)
		(width 0.127)
		(layer "F.Cu")
		(net "I2C_EXP_RMT_SCL_OUT")
	)
	(segment
		(start 74.462386 -144.729962)
		(end 75.977496 -144.729962)
		(width 0.127)
		(layer "F.Cu")
		(net "I2C_EXP_RMT_SCL_OUT")
	)
	(segment
		(start 66.716402 -143.068802)
		(end 67.402964 -143.755364)
		(width 0.127)
		(layer "F.Cu")
		(net "I2C_EXP_RMT_SCL_OUT")
	)
	(segment
		(start 66.1543 -142.5067)
		(end 66.39179 -142.74419)
		(width 0.127)
		(layer "F.Cu")
		(net "I2C_EXP_RMT_SCL_OUT")
	)
	(segment
		(start 61.733684 -143.382492)
		(end 62.096904 -143.019272)
		(width 0.127)
		(layer "F.Cu")
		(net "I2C_EXP_RMT_SCL_OUT")
	)
	(segment
		(start 66.716402 -143.063976)
		(end 66.716402 -143.068802)
		(width 0.127)
		(layer "F.Cu")
		(net "I2C_EXP_RMT_SCL_OUT")
	)
	(via
		(at 69.079364 -143.755364)
		(size 0.6604)
		(drill 0.3302)
		(layers "F.Cu" "B.Cu")
		(net "I2C_EXP_RMT_SCL_OUT")
	)
	(segment
		(start 85.344762 -146.519646)
		(end 85.712046 -146.519646)
		(width 0.127)
		(layer "F.Cu")
		(net "I2C_EXP_RMT_SCL")
	)
	(segment
		(start 88.030558 -145.370042)
		(end 88.030558 -144.104106)
		(width 0.127)
		(layer "F.Cu")
		(net "I2C_EXP_RMT_SCL")
	)
	(segment
		(start 85.712046 -146.519646)
		(end 85.9028 -146.7104)
		(width 0.127)
		(layer "F.Cu")
		(net "I2C_EXP_RMT_SCL")
	)
	(segment
		(start 88.030558 -143.631666)
		(end 88.030558 -144.104106)
		(width 0.127)
		(layer "F.Cu")
		(net "I2C_EXP_RMT_SCL")
	)
	(segment
		(start 85.9028 -146.7104)
		(end 86.6902 -146.7104)
		(width 0.127)
		(layer "F.Cu")
		(net "I2C_EXP_RMT_SCL")
	)
	(segment
		(start 86.6902 -146.7104)
		(end 88.030558 -145.370042)
		(width 0.127)
		(layer "F.Cu")
		(net "I2C_EXP_RMT_SCL")
	)
	(segment
		(start 88.44788 -143.214344)
		(end 88.030558 -143.631666)
		(width 0.127)
		(layer "F.Cu")
		(net "I2C_EXP_RMT_SCL")
	)
	(via
		(at 88.44788 -143.214344)
		(size 0.508)
		(drill 0.254)
		(layers "F.Cu" "B.Cu")
		(net "I2C_EXP_RMT_SCL")
	)
	(via
		(at 88.030558 -144.104106)
		(size 0.6604)
		(drill 0.3302)
		(layers "F.Cu" "B.Cu")
		(net "I2C_EXP_RMT_SCL")
	)
	(segment
		(start 93.75267 -28.111958)
		(end 93.75267 -32.439864)
		(width 0.127)
		(layer "In2.Cu")
		(net "I2C_EXP_RMT_SCL")
	)
	(segment
		(start 90.853006 -45.900594)
		(end 89.4969 -47.2567)
		(width 0.127)
		(layer "In2.Cu")
		(net "I2C_EXP_RMT_SCL")
	)
	(segment
		(start 88.119966 -133.141974)
		(end 88.48598 -133.507988)
		(width 0.127)
		(layer "In2.Cu")
		(net "I2C_EXP_RMT_SCL")
	)
	(segment
		(start 88.48598 -133.507988)
		(end 88.48598 -143.176244)
		(width 0.127)
		(layer "In2.Cu")
		(net "I2C_EXP_RMT_SCL")
	)
	(segment
		(start 91.8972 -109.968538)
		(end 89.812368 -112.05337)
		(width 0.127)
		(layer "In2.Cu")
		(net "I2C_EXP_RMT_SCL")
	)
	(segment
		(start 90.8685 -53.494432)
		(end 90.8685 -94.2086)
		(width 0.127)
		(layer "In2.Cu")
		(net "I2C_EXP_RMT_SCL")
	)
	(segment
		(start 88.48598 -143.176244)
		(end 88.44788 -143.214344)
		(width 0.127)
		(layer "In2.Cu")
		(net "I2C_EXP_RMT_SCL")
	)
	(segment
		(start 93.75267 -32.439864)
		(end 90.853006 -35.339528)
		(width 0.127)
		(layer "In2.Cu")
		(net "I2C_EXP_RMT_SCL")
	)
	(segment
		(start 91.2876 -95.243142)
		(end 91.2876 -98.356166)
		(width 0.127)
		(layer "In2.Cu")
		(net "I2C_EXP_RMT_SCL")
	)
	(segment
		(start 132.299964 -40.39997)
		(end 131.640326 -39.740332)
		(width 0.127)
		(layer "In2.Cu")
		(net "I2C_EXP_RMT_SCL")
	)
	(segment
		(start 89.268554 -113.795048)
		(end 89.268554 -119.362982)
		(width 0.127)
		(layer "In2.Cu")
		(net "I2C_EXP_RMT_SCL")
	)
	(segment
		(start 90.7161 -94.671642)
		(end 91.2876 -95.243142)
		(width 0.127)
		(layer "In2.Cu")
		(net "I2C_EXP_RMT_SCL")
	)
	(segment
		(start 131.640326 -39.740332)
		(end 131.640326 -30.513782)
		(width 0.127)
		(layer "In2.Cu")
		(net "I2C_EXP_RMT_SCL")
	)
	(segment
		(start 90.853006 -35.339528)
		(end 90.853006 -45.900594)
		(width 0.127)
		(layer "In2.Cu")
		(net "I2C_EXP_RMT_SCL")
	)
	(segment
		(start 89.812368 -112.05337)
		(end 89.812368 -113.251234)
		(width 0.127)
		(layer "In2.Cu")
		(net "I2C_EXP_RMT_SCL")
	)
	(segment
		(start 89.812368 -113.251234)
		(end 89.268554 -113.795048)
		(width 0.127)
		(layer "In2.Cu")
		(net "I2C_EXP_RMT_SCL")
	)
	(segment
		(start 90.8685 -94.2086)
		(end 90.7161 -94.361)
		(width 0.127)
		(layer "In2.Cu")
		(net "I2C_EXP_RMT_SCL")
	)
	(segment
		(start 114.519202 -19.374104)
		(end 102.490524 -19.374104)
		(width 0.127)
		(layer "In2.Cu")
		(net "I2C_EXP_RMT_SCL")
	)
	(segment
		(start 89.4969 -52.122832)
		(end 90.8685 -53.494432)
		(width 0.127)
		(layer "In2.Cu")
		(net "I2C_EXP_RMT_SCL")
	)
	(segment
		(start 89.1794 -125.397514)
		(end 88.119966 -126.456948)
		(width 0.127)
		(layer "In2.Cu")
		(net "I2C_EXP_RMT_SCL")
	)
	(segment
		(start 117.116098 -21.971)
		(end 114.519202 -19.374104)
		(width 0.127)
		(layer "In2.Cu")
		(net "I2C_EXP_RMT_SCL")
	)
	(segment
		(start 91.8972 -98.965766)
		(end 91.8972 -109.968538)
		(width 0.127)
		(layer "In2.Cu")
		(net "I2C_EXP_RMT_SCL")
	)
	(segment
		(start 91.2876 -98.356166)
		(end 91.8972 -98.965766)
		(width 0.127)
		(layer "In2.Cu")
		(net "I2C_EXP_RMT_SCL")
	)
	(segment
		(start 89.4969 -47.2567)
		(end 89.4969 -52.122832)
		(width 0.127)
		(layer "In2.Cu")
		(net "I2C_EXP_RMT_SCL")
	)
	(segment
		(start 102.490524 -19.374104)
		(end 93.75267 -28.111958)
		(width 0.127)
		(layer "In2.Cu")
		(net "I2C_EXP_RMT_SCL")
	)
	(segment
		(start 130.877056 -29.750512)
		(end 126.754382 -29.750512)
		(width 0.127)
		(layer "In2.Cu")
		(net "I2C_EXP_RMT_SCL")
	)
	(segment
		(start 89.1794 -119.452136)
		(end 89.1794 -125.397514)
		(width 0.127)
		(layer "In2.Cu")
		(net "I2C_EXP_RMT_SCL")
	)
	(segment
		(start 89.268554 -119.362982)
		(end 89.1794 -119.452136)
		(width 0.127)
		(layer "In2.Cu")
		(net "I2C_EXP_RMT_SCL")
	)
	(segment
		(start 88.119966 -126.456948)
		(end 88.119966 -133.141974)
		(width 0.127)
		(layer "In2.Cu")
		(net "I2C_EXP_RMT_SCL")
	)
	(segment
		(start 126.754382 -29.750512)
		(end 118.97487 -21.971)
		(width 0.127)
		(layer "In2.Cu")
		(net "I2C_EXP_RMT_SCL")
	)
	(segment
		(start 131.640326 -30.513782)
		(end 130.877056 -29.750512)
		(width 0.127)
		(layer "In2.Cu")
		(net "I2C_EXP_RMT_SCL")
	)
	(segment
		(start 90.7161 -94.361)
		(end 90.7161 -94.671642)
		(width 0.127)
		(layer "In2.Cu")
		(net "I2C_EXP_RMT_SCL")
	)
	(segment
		(start 118.97487 -21.971)
		(end 117.116098 -21.971)
		(width 0.127)
		(layer "In2.Cu")
		(net "I2C_EXP_RMT_SCL")
	)
	(segment
		(start 81.616296 -144.729962)
		(end 80.76565 -144.729962)
		(width 0.127)
		(layer "F.Cu")
		(net "I2C_EXP_LOC_SDA_R")
	)
	(segment
		(start 80.76565 -144.729962)
		(end 80.236822 -144.201134)
		(width 0.127)
		(layer "F.Cu")
		(net "I2C_EXP_LOC_SDA_R")
	)
	(via
		(at 81.01838 -143.563086)
		(size 0.6096)
		(drill 0.3048)
		(layers "F.Cu" "B.Cu")
		(net "I2C_EXP_LOC_SDA_R")
	)
	(via
		(at 80.236822 -144.201134)
		(size 0.508)
		(drill 0.254)
		(layers "F.Cu" "B.Cu")
		(net "I2C_EXP_LOC_SDA_R")
	)
	(segment
		(start 80.236822 -144.201134)
		(end 80.380332 -144.201134)
		(width 0.127)
		(layer "B.Cu")
		(net "I2C_EXP_LOC_SDA_R")
	)
	(segment
		(start 80.380332 -144.201134)
		(end 81.01838 -143.563086)
		(width 0.127)
		(layer "B.Cu")
		(net "I2C_EXP_LOC_SDA_R")
	)
	(segment
		(start 81.45145 -143.130016)
		(end 81.01838 -143.563086)
		(width 0.127)
		(layer "B.Cu")
		(net "I2C_EXP_LOC_SDA_R")
	)
	(segment
		(start 81.45145 -141.750542)
		(end 81.45145 -143.130016)
		(width 0.127)
		(layer "B.Cu")
		(net "I2C_EXP_LOC_SDA_R")
	)
	(segment
		(start 74.336402 -145.380202)
		(end 73.6092 -144.653)
		(width 0.127)
		(layer "F.Cu")
		(net "I2C_EXP_LOC_SDA_OUT")
	)
	(segment
		(start 73.6092 -144.653)
		(end 73.6092 -144.572228)
		(width 0.127)
		(layer "F.Cu")
		(net "I2C_EXP_LOC_SDA_OUT")
	)
	(segment
		(start 75.977496 -145.380202)
		(end 74.336402 -145.380202)
		(width 0.127)
		(layer "F.Cu")
		(net "I2C_EXP_LOC_SDA_OUT")
	)
	(via
		(at 64.135 -143.0528)
		(size 0.6096)
		(drill 0.3048)
		(layers "F.Cu" "B.Cu")
		(net "I2C_EXP_LOC_SDA_OUT")
	)
	(via
		(at 73.6092 -144.572228)
		(size 0.508)
		(drill 0.254)
		(layers "F.Cu" "B.Cu")
		(net "I2C_EXP_LOC_SDA_OUT")
	)
	(segment
		(start 62.292992 -144.0434)
		(end 63.3603 -144.0434)
		(width 0.127)
		(layer "B.Cu")
		(net "I2C_EXP_LOC_SDA_OUT")
	)
	(segment
		(start 62.19952 -143.949928)
		(end 62.292992 -144.0434)
		(width 0.127)
		(layer "B.Cu")
		(net "I2C_EXP_LOC_SDA_OUT")
	)
	(segment
		(start 64.135 -143.0528)
		(end 63.3603 -143.8275)
		(width 0.127)
		(layer "B.Cu")
		(net "I2C_EXP_LOC_SDA_OUT")
	)
	(segment
		(start 69.792088 -140.755116)
		(end 67.65544 -140.755116)
		(width 0.127)
		(layer "B.Cu")
		(net "I2C_EXP_LOC_SDA_OUT")
	)
	(segment
		(start 66.361056 -142.0495)
		(end 65.1383 -142.0495)
		(width 0.127)
		(layer "B.Cu")
		(net "I2C_EXP_LOC_SDA_OUT")
	)
	(segment
		(start 63.3603 -143.8275)
		(end 63.3603 -144.0434)
		(width 0.127)
		(layer "B.Cu")
		(net "I2C_EXP_LOC_SDA_OUT")
	)
	(segment
		(start 65.1383 -142.0495)
		(end 64.135 -143.0528)
		(width 0.127)
		(layer "B.Cu")
		(net "I2C_EXP_LOC_SDA_OUT")
	)
	(segment
		(start 67.65544 -140.755116)
		(end 66.361056 -142.0495)
		(width 0.127)
		(layer "B.Cu")
		(net "I2C_EXP_LOC_SDA_OUT")
	)
	(segment
		(start 73.6092 -144.572228)
		(end 69.792088 -140.755116)
		(width 0.127)
		(layer "B.Cu")
		(net "I2C_EXP_LOC_SDA_OUT")
	)
	(via
		(at 83.5787 -140.28801)
		(size 0.508)
		(drill 0.254)
		(layers "F.Cu" "B.Cu")
		(net "I2C_EXP_LOC_SDA")
	)
	(via
		(at 83.315048 -141.368526)
		(size 0.6096)
		(drill 0.3048)
		(layers "F.Cu" "B.Cu")
		(net "I2C_EXP_LOC_SDA")
	)
	(segment
		(start 82.933032 -141.750542)
		(end 83.315048 -141.368526)
		(width 0.127)
		(layer "B.Cu")
		(net "I2C_EXP_LOC_SDA")
	)
	(segment
		(start 82.34045 -141.750542)
		(end 82.933032 -141.750542)
		(width 0.127)
		(layer "B.Cu")
		(net "I2C_EXP_LOC_SDA")
	)
	(segment
		(start 83.5787 -141.104874)
		(end 83.315048 -141.368526)
		(width 0.127)
		(layer "B.Cu")
		(net "I2C_EXP_LOC_SDA")
	)
	(segment
		(start 83.5787 -140.28801)
		(end 83.5787 -141.104874)
		(width 0.127)
		(layer "B.Cu")
		(net "I2C_EXP_LOC_SDA")
	)
	(segment
		(start 85.098382 -138.789156)
		(end 84.418678 -138.789156)
		(width 0.127)
		(layer "In2.Cu")
		(net "I2C_EXP_LOC_SDA")
	)
	(segment
		(start 96.0374 -19.6596)
		(end 96.0374 -22.649688)
		(width 0.127)
		(layer "In2.Cu")
		(net "I2C_EXP_LOC_SDA")
	)
	(segment
		(start 88.7476 -93.1926)
		(end 88.5952 -93.345)
		(width 0.127)
		(layer "In2.Cu")
		(net "I2C_EXP_LOC_SDA")
	)
	(segment
		(start 89.7763 -99.844606)
		(end 89.7763 -109.089698)
		(width 0.127)
		(layer "In2.Cu")
		(net "I2C_EXP_LOC_SDA")
	)
	(segment
		(start 85.097874 -131.866386)
		(end 85.097874 -136.089136)
		(width 0.127)
		(layer "In2.Cu")
		(net "I2C_EXP_LOC_SDA")
	)
	(segment
		(start 97.338896 -18.358104)
		(end 96.0374 -19.6596)
		(width 0.127)
		(layer "In2.Cu")
		(net "I2C_EXP_LOC_SDA")
	)
	(segment
		(start 85.141308 -131.822952)
		(end 85.097874 -131.866386)
		(width 0.127)
		(layer "In2.Cu")
		(net "I2C_EXP_LOC_SDA")
	)
	(segment
		(start 86.008972 -137.878566)
		(end 85.098382 -138.789156)
		(width 0.127)
		(layer "In2.Cu")
		(net "I2C_EXP_LOC_SDA")
	)
	(segment
		(start 85.062568 -130.786632)
		(end 85.141308 -130.865372)
		(width 0.127)
		(layer "In2.Cu")
		(net "I2C_EXP_LOC_SDA")
	)
	(segment
		(start 133.379464 -44.32046)
		(end 133.379464 -30.815788)
		(width 0.127)
		(layer "In2.Cu")
		(net "I2C_EXP_LOC_SDA")
	)
	(segment
		(start 114.940334 -18.358104)
		(end 97.338896 -18.358104)
		(width 0.127)
		(layer "In2.Cu")
		(net "I2C_EXP_LOC_SDA")
	)
	(segment
		(start 133.379464 -30.815788)
		(end 131.298188 -28.734512)
		(width 0.127)
		(layer "In2.Cu")
		(net "I2C_EXP_LOC_SDA")
	)
	(segment
		(start 87.691468 -111.17453)
		(end 87.691468 -111.7092)
		(width 0.127)
		(layer "In2.Cu")
		(net "I2C_EXP_LOC_SDA")
	)
	(segment
		(start 88.5952 -95.550482)
		(end 89.1667 -96.121982)
		(width 0.127)
		(layer "In2.Cu")
		(net "I2C_EXP_LOC_SDA")
	)
	(segment
		(start 86.008972 -137.000234)
		(end 86.008972 -137.878566)
		(width 0.127)
		(layer "In2.Cu")
		(net "I2C_EXP_LOC_SDA")
	)
	(segment
		(start 84.418678 -138.789156)
		(end 83.794346 -139.413488)
		(width 0.127)
		(layer "In2.Cu")
		(net "I2C_EXP_LOC_SDA")
	)
	(segment
		(start 132.299964 -45.39996)
		(end 133.379464 -44.32046)
		(width 0.127)
		(layer "In2.Cu")
		(net "I2C_EXP_LOC_SDA")
	)
	(segment
		(start 85.062568 -128.322832)
		(end 85.062568 -130.786632)
		(width 0.127)
		(layer "In2.Cu")
		(net "I2C_EXP_LOC_SDA")
	)
	(segment
		(start 87.0585 -123.14809)
		(end 85.5726 -124.63399)
		(width 0.127)
		(layer "In2.Cu")
		(net "I2C_EXP_LOC_SDA")
	)
	(segment
		(start 96.0374 -22.649688)
		(end 88.265 -30.422088)
		(width 0.127)
		(layer "In2.Cu")
		(net "I2C_EXP_LOC_SDA")
	)
	(segment
		(start 88.5952 -93.345)
		(end 88.5952 -95.550482)
		(width 0.127)
		(layer "In2.Cu")
		(net "I2C_EXP_LOC_SDA")
	)
	(segment
		(start 87.0585 -114.474752)
		(end 87.0585 -123.14809)
		(width 0.127)
		(layer "In2.Cu")
		(net "I2C_EXP_LOC_SDA")
	)
	(segment
		(start 89.7763 -109.089698)
		(end 87.691468 -111.17453)
		(width 0.127)
		(layer "In2.Cu")
		(net "I2C_EXP_LOC_SDA")
	)
	(segment
		(start 88.265 -30.422088)
		(end 88.265 -44.442634)
		(width 0.127)
		(layer "In2.Cu")
		(net "I2C_EXP_LOC_SDA")
	)
	(segment
		(start 87.691468 -111.7092)
		(end 87.1347 -112.265968)
		(width 0.127)
		(layer "In2.Cu")
		(net "I2C_EXP_LOC_SDA")
	)
	(segment
		(start 85.5726 -127.8128)
		(end 85.062568 -128.322832)
		(width 0.127)
		(layer "In2.Cu")
		(net "I2C_EXP_LOC_SDA")
	)
	(segment
		(start 127.175514 -28.734512)
		(end 119.396002 -20.955)
		(width 0.127)
		(layer "In2.Cu")
		(net "I2C_EXP_LOC_SDA")
	)
	(segment
		(start 89.1667 -99.235006)
		(end 89.7763 -99.844606)
		(width 0.127)
		(layer "In2.Cu")
		(net "I2C_EXP_LOC_SDA")
	)
	(segment
		(start 89.1667 -96.121982)
		(end 89.1667 -99.235006)
		(width 0.127)
		(layer "In2.Cu")
		(net "I2C_EXP_LOC_SDA")
	)
	(segment
		(start 85.097874 -136.089136)
		(end 86.008972 -137.000234)
		(width 0.127)
		(layer "In2.Cu")
		(net "I2C_EXP_LOC_SDA")
	)
	(segment
		(start 131.298188 -28.734512)
		(end 127.175514 -28.734512)
		(width 0.127)
		(layer "In2.Cu")
		(net "I2C_EXP_LOC_SDA")
	)
	(segment
		(start 88.7476 -54.373272)
		(end 88.7476 -93.1926)
		(width 0.127)
		(layer "In2.Cu")
		(net "I2C_EXP_LOC_SDA")
	)
	(segment
		(start 87.1347 -112.265968)
		(end 87.1347 -114.398552)
		(width 0.127)
		(layer "In2.Cu")
		(net "I2C_EXP_LOC_SDA")
	)
	(segment
		(start 88.265 -44.442634)
		(end 87.376 -45.331634)
		(width 0.127)
		(layer "In2.Cu")
		(net "I2C_EXP_LOC_SDA")
	)
	(segment
		(start 87.376 -53.001672)
		(end 88.7476 -54.373272)
		(width 0.127)
		(layer "In2.Cu")
		(net "I2C_EXP_LOC_SDA")
	)
	(segment
		(start 83.794346 -139.413488)
		(end 83.794346 -140.072364)
		(width 0.127)
		(layer "In2.Cu")
		(net "I2C_EXP_LOC_SDA")
	)
	(segment
		(start 85.141308 -130.865372)
		(end 85.141308 -131.822952)
		(width 0.127)
		(layer "In2.Cu")
		(net "I2C_EXP_LOC_SDA")
	)
	(segment
		(start 87.1347 -114.398552)
		(end 87.0585 -114.474752)
		(width 0.127)
		(layer "In2.Cu")
		(net "I2C_EXP_LOC_SDA")
	)
	(segment
		(start 117.53723 -20.955)
		(end 114.940334 -18.358104)
		(width 0.127)
		(layer "In2.Cu")
		(net "I2C_EXP_LOC_SDA")
	)
	(segment
		(start 85.5726 -124.63399)
		(end 85.5726 -127.8128)
		(width 0.127)
		(layer "In2.Cu")
		(net "I2C_EXP_LOC_SDA")
	)
	(segment
		(start 83.794346 -140.072364)
		(end 83.5787 -140.28801)
		(width 0.127)
		(layer "In2.Cu")
		(net "I2C_EXP_LOC_SDA")
	)
	(segment
		(start 87.376 -45.331634)
		(end 87.376 -53.001672)
		(width 0.127)
		(layer "In2.Cu")
		(net "I2C_EXP_LOC_SDA")
	)
	(segment
		(start 119.396002 -20.955)
		(end 117.53723 -20.955)
		(width 0.127)
		(layer "In2.Cu")
		(net "I2C_EXP_LOC_SDA")
	)
	(segment
		(start 80.166464 -145.241518)
		(end 80.305148 -145.380202)
		(width 0.127)
		(layer "F.Cu")
		(net "I2C_EXP_LOC_SCL_R")
	)
	(segment
		(start 80.305148 -145.380202)
		(end 81.616296 -145.380202)
		(width 0.127)
		(layer "F.Cu")
		(net "I2C_EXP_LOC_SCL_R")
	)
	(via
		(at 81.127854 -144.698212)
		(size 0.6096)
		(drill 0.3048)
		(layers "F.Cu" "B.Cu")
		(net "I2C_EXP_LOC_SCL_R")
	)
	(via
		(at 80.166464 -145.241518)
		(size 0.508)
		(drill 0.254)
		(layers "F.Cu" "B.Cu")
		(net "I2C_EXP_LOC_SCL_R")
	)
	(segment
		(start 81.127854 -144.698212)
		(end 81.677002 -144.149064)
		(width 0.127)
		(layer "B.Cu")
		(net "I2C_EXP_LOC_SCL_R")
	)
	(segment
		(start 82.004154 -143.814292)
		(end 82.43189 -143.814292)
		(width 0.127)
		(layer "B.Cu")
		(net "I2C_EXP_LOC_SCL_R")
	)
	(segment
		(start 80.166464 -145.241518)
		(end 80.221074 -145.186908)
		(width 0.127)
		(layer "B.Cu")
		(net "I2C_EXP_LOC_SCL_R")
	)
	(segment
		(start 81.677002 -144.141444)
		(end 82.004154 -143.814292)
		(width 0.127)
		(layer "B.Cu")
		(net "I2C_EXP_LOC_SCL_R")
	)
	(segment
		(start 81.677002 -144.149064)
		(end 81.677002 -144.141444)
		(width 0.127)
		(layer "B.Cu")
		(net "I2C_EXP_LOC_SCL_R")
	)
	(segment
		(start 80.221074 -145.186908)
		(end 80.639158 -145.186908)
		(width 0.127)
		(layer "B.Cu")
		(net "I2C_EXP_LOC_SCL_R")
	)
	(segment
		(start 80.639158 -145.186908)
		(end 81.127854 -144.698212)
		(width 0.127)
		(layer "B.Cu")
		(net "I2C_EXP_LOC_SCL_R")
	)
	(segment
		(start 75.977496 -146.030442)
		(end 74.201528 -146.030442)
		(width 0.127)
		(layer "F.Cu")
		(net "I2C_EXP_LOC_SCL_OUT")
	)
	(segment
		(start 74.201528 -146.030442)
		(end 74.169524 -145.998438)
		(width 0.127)
		(layer "F.Cu")
		(net "I2C_EXP_LOC_SCL_OUT")
	)
	(via
		(at 70.866 -140.97)
		(size 0.6096)
		(drill 0.3048)
		(layers "F.Cu" "B.Cu")
		(net "I2C_EXP_LOC_SCL_OUT")
	)
	(via
		(at 74.169524 -145.998438)
		(size 0.508)
		(drill 0.254)
		(layers "F.Cu" "B.Cu")
		(net "I2C_EXP_LOC_SCL_OUT")
	)
	(segment
		(start 62.605158 -142.880334)
		(end 62.73292 -142.752572)
		(width 0.127)
		(layer "B.Cu")
		(net "I2C_EXP_LOC_SCL_OUT")
	)
	(segment
		(start 74.169524 -144.273524)
		(end 74.169524 -145.998438)
		(width 0.127)
		(layer "B.Cu")
		(net "I2C_EXP_LOC_SCL_OUT")
	)
	(segment
		(start 67.444874 -140.247116)
		(end 66.15049 -141.5415)
		(width 0.127)
		(layer "B.Cu")
		(net "I2C_EXP_LOC_SCL_OUT")
	)
	(segment
		(start 70.866 -140.97)
		(end 70.143116 -140.247116)
		(width 0.127)
		(layer "B.Cu")
		(net "I2C_EXP_LOC_SCL_OUT")
	)
	(segment
		(start 64.675766 -141.5415)
		(end 63.464694 -142.752572)
		(width 0.127)
		(layer "B.Cu")
		(net "I2C_EXP_LOC_SCL_OUT")
	)
	(segment
		(start 70.143116 -140.247116)
		(end 67.444874 -140.247116)
		(width 0.127)
		(layer "B.Cu")
		(net "I2C_EXP_LOC_SCL_OUT")
	)
	(segment
		(start 70.866 -140.97)
		(end 74.169524 -144.273524)
		(width 0.127)
		(layer "B.Cu")
		(net "I2C_EXP_LOC_SCL_OUT")
	)
	(segment
		(start 66.15049 -141.5415)
		(end 64.675766 -141.5415)
		(width 0.127)
		(layer "B.Cu")
		(net "I2C_EXP_LOC_SCL_OUT")
	)
	(segment
		(start 61.71438 -142.880334)
		(end 62.605158 -142.880334)
		(width 0.127)
		(layer "B.Cu")
		(net "I2C_EXP_LOC_SCL_OUT")
	)
	(segment
		(start 63.464694 -142.752572)
		(end 62.73292 -142.752572)
		(width 0.127)
		(layer "B.Cu")
		(net "I2C_EXP_LOC_SCL_OUT")
	)
	(via
		(at 84.278724 -142.685008)
		(size 0.6096)
		(drill 0.3048)
		(layers "F.Cu" "B.Cu")
		(net "I2C_EXP_LOC_SCL")
	)
	(via
		(at 84.3026 -139.6238)
		(size 0.508)
		(drill 0.254)
		(layers "F.Cu" "B.Cu")
		(net "I2C_EXP_LOC_SCL")
	)
	(segment
		(start 83.32089 -143.814292)
		(end 83.930744 -143.814292)
		(width 0.127)
		(layer "B.Cu")
		(net "I2C_EXP_LOC_SCL")
	)
	(segment
		(start 83.930744 -143.814292)
		(end 84.3026 -143.442436)
		(width 0.127)
		(layer "B.Cu")
		(net "I2C_EXP_LOC_SCL")
	)
	(segment
		(start 84.3026 -142.685008)
		(end 84.3026 -139.6238)
		(width 0.127)
		(layer "B.Cu")
		(net "I2C_EXP_LOC_SCL")
	)
	(segment
		(start 84.278724 -142.685008)
		(end 84.3026 -142.685008)
		(width 0.127)
		(layer "B.Cu")
		(net "I2C_EXP_LOC_SCL")
	)
	(segment
		(start 84.3026 -143.442436)
		(end 84.3026 -142.685008)
		(width 0.127)
		(layer "B.Cu")
		(net "I2C_EXP_LOC_SCL")
	)
	(segment
		(start 86.085172 -136.357868)
		(end 86.085172 -133.457696)
		(width 0.127)
		(layer "In2.Cu")
		(net "I2C_EXP_LOC_SCL")
	)
	(segment
		(start 86.516972 -138.089132)
		(end 86.516972 -136.789668)
		(width 0.127)
		(layer "In2.Cu")
		(net "I2C_EXP_LOC_SCL")
	)
	(segment
		(start 87.884 -52.791106)
		(end 87.884 -45.5422)
		(width 0.127)
		(layer "In2.Cu")
		(net "I2C_EXP_LOC_SCL")
	)
	(segment
		(start 85.160866 -139.445238)
		(end 86.516972 -138.089132)
		(width 0.127)
		(layer "In2.Cu")
		(net "I2C_EXP_LOC_SCL")
	)
	(segment
		(start 89.2556 -54.162706)
		(end 87.884 -52.791106)
		(width 0.127)
		(layer "In2.Cu")
		(net "I2C_EXP_LOC_SCL")
	)
	(segment
		(start 132.871464 -31.026354)
		(end 132.871464 -43.428666)
		(width 0.127)
		(layer "In2.Cu")
		(net "I2C_EXP_LOC_SCL")
	)
	(segment
		(start 84.481162 -139.445238)
		(end 85.160866 -139.445238)
		(width 0.127)
		(layer "In2.Cu")
		(net "I2C_EXP_LOC_SCL")
	)
	(segment
		(start 89.1032 -93.599)
		(end 89.2556 -93.4466)
		(width 0.127)
		(layer "In2.Cu")
		(net "I2C_EXP_LOC_SCL")
	)
	(segment
		(start 89.6747 -99.02444)
		(end 89.6747 -95.911416)
		(width 0.127)
		(layer "In2.Cu")
		(net "I2C_EXP_LOC_SCL")
	)
	(segment
		(start 89.1032 -95.339916)
		(end 89.1032 -93.599)
		(width 0.127)
		(layer "In2.Cu")
		(net "I2C_EXP_LOC_SCL")
	)
	(segment
		(start 85.651848 -133.024372)
		(end 85.651848 -132.030978)
		(width 0.127)
		(layer "In2.Cu")
		(net "I2C_EXP_LOC_SCL")
	)
	(segment
		(start 87.655654 -114.596164)
		(end 87.655654 -113.658142)
		(width 0.127)
		(layer "In2.Cu")
		(net "I2C_EXP_LOC_SCL")
	)
	(segment
		(start 132.871464 -43.428666)
		(end 132.299964 -44.000166)
		(width 0.127)
		(layer "In2.Cu")
		(net "I2C_EXP_LOC_SCL")
	)
	(segment
		(start 85.651848 -132.030978)
		(end 86.0806 -131.602226)
		(width 0.127)
		(layer "In2.Cu")
		(net "I2C_EXP_LOC_SCL")
	)
	(segment
		(start 87.655654 -113.658142)
		(end 87.6554 -113.657888)
		(width 0.127)
		(layer "In2.Cu")
		(net "I2C_EXP_LOC_SCL")
	)
	(segment
		(start 101.610922 -19.53514)
		(end 102.279958 -18.866104)
		(width 0.127)
		(layer "In2.Cu")
		(net "I2C_EXP_LOC_SCL")
	)
	(segment
		(start 117.326664 -21.463)
		(end 119.185436 -21.463)
		(width 0.127)
		(layer "In2.Cu")
		(net "I2C_EXP_LOC_SCL")
	)
	(segment
		(start 86.516972 -136.789668)
		(end 86.085172 -136.357868)
		(width 0.127)
		(layer "In2.Cu")
		(net "I2C_EXP_LOC_SCL")
	)
	(segment
		(start 119.185436 -21.463)
		(end 126.964948 -29.242512)
		(width 0.127)
		(layer "In2.Cu")
		(net "I2C_EXP_LOC_SCL")
	)
	(segment
		(start 114.729768 -18.866104)
		(end 117.326664 -21.463)
		(width 0.127)
		(layer "In2.Cu")
		(net "I2C_EXP_LOC_SCL")
	)
	(segment
		(start 126.964948 -29.242512)
		(end 131.087622 -29.242512)
		(width 0.127)
		(layer "In2.Cu")
		(net "I2C_EXP_LOC_SCL")
	)
	(segment
		(start 102.279958 -18.866104)
		(end 114.729768 -18.866104)
		(width 0.127)
		(layer "In2.Cu")
		(net "I2C_EXP_LOC_SCL")
	)
	(segment
		(start 88.773 -30.632654)
		(end 96.5454 -22.860254)
		(width 0.127)
		(layer "In2.Cu")
		(net "I2C_EXP_LOC_SCL")
	)
	(segment
		(start 87.884 -45.5422)
		(end 88.773 -44.6532)
		(width 0.127)
		(layer "In2.Cu")
		(net "I2C_EXP_LOC_SCL")
	)
	(segment
		(start 88.199468 -112.58296)
		(end 88.199468 -111.385096)
		(width 0.127)
		(layer "In2.Cu")
		(net "I2C_EXP_LOC_SCL")
	)
	(segment
		(start 88.199468 -111.385096)
		(end 90.2843 -109.300264)
		(width 0.127)
		(layer "In2.Cu")
		(net "I2C_EXP_LOC_SCL")
	)
	(segment
		(start 87.6554 -113.657888)
		(end 87.6554 -113.127028)
		(width 0.127)
		(layer "In2.Cu")
		(net "I2C_EXP_LOC_SCL")
	)
	(segment
		(start 86.0806 -124.844556)
		(end 87.5665 -123.358656)
		(width 0.127)
		(layer "In2.Cu")
		(net "I2C_EXP_LOC_SCL")
	)
	(segment
		(start 131.087622 -29.242512)
		(end 132.871464 -31.026354)
		(width 0.127)
		(layer "In2.Cu")
		(net "I2C_EXP_LOC_SCL")
	)
	(segment
		(start 89.6747 -95.911416)
		(end 89.1032 -95.339916)
		(width 0.127)
		(layer "In2.Cu")
		(net "I2C_EXP_LOC_SCL")
	)
	(segment
		(start 87.5665 -123.358656)
		(end 87.5665 -114.685318)
		(width 0.127)
		(layer "In2.Cu")
		(net "I2C_EXP_LOC_SCL")
	)
	(segment
		(start 90.2843 -99.63404)
		(end 89.6747 -99.02444)
		(width 0.127)
		(layer "In2.Cu")
		(net "I2C_EXP_LOC_SCL")
	)
	(segment
		(start 96.5454 -19.9136)
		(end 96.92386 -19.53514)
		(width 0.127)
		(layer "In2.Cu")
		(net "I2C_EXP_LOC_SCL")
	)
	(segment
		(start 86.0806 -131.602226)
		(end 86.0806 -124.844556)
		(width 0.127)
		(layer "In2.Cu")
		(net "I2C_EXP_LOC_SCL")
	)
	(segment
		(start 86.085172 -133.457696)
		(end 85.651848 -133.024372)
		(width 0.127)
		(layer "In2.Cu")
		(net "I2C_EXP_LOC_SCL")
	)
	(segment
		(start 90.2843 -109.300264)
		(end 90.2843 -99.63404)
		(width 0.127)
		(layer "In2.Cu")
		(net "I2C_EXP_LOC_SCL")
	)
	(segment
		(start 87.5665 -114.685318)
		(end 87.655654 -114.596164)
		(width 0.127)
		(layer "In2.Cu")
		(net "I2C_EXP_LOC_SCL")
	)
	(segment
		(start 84.3026 -139.6238)
		(end 84.481162 -139.445238)
		(width 0.127)
		(layer "In2.Cu")
		(net "I2C_EXP_LOC_SCL")
	)
	(segment
		(start 96.92386 -19.53514)
		(end 101.610922 -19.53514)
		(width 0.127)
		(layer "In2.Cu")
		(net "I2C_EXP_LOC_SCL")
	)
	(segment
		(start 87.6554 -113.127028)
		(end 88.199468 -112.58296)
		(width 0.127)
		(layer "In2.Cu")
		(net "I2C_EXP_LOC_SCL")
	)
	(segment
		(start 96.5454 -22.860254)
		(end 96.5454 -19.9136)
		(width 0.127)
		(layer "In2.Cu")
		(net "I2C_EXP_LOC_SCL")
	)
	(segment
		(start 88.773 -44.6532)
		(end 88.773 -30.632654)
		(width 0.127)
		(layer "In2.Cu")
		(net "I2C_EXP_LOC_SCL")
	)
	(segment
		(start 89.2556 -93.4466)
		(end 89.2556 -54.162706)
		(width 0.127)
		(layer "In2.Cu")
		(net "I2C_EXP_LOC_SCL")
	)
	(segment
		(start 83.2866 -141.1986)
		(end 82.916522 -140.828522)
		(width 0.127)
		(layer "F.Cu")
		(net "I2C_DPB_SDA_R")
	)
	(segment
		(start 85.042756 -141.090142)
		(end 83.395058 -141.090142)
		(width 0.127)
		(layer "F.Cu")
		(net "I2C_DPB_SDA_R")
	)
	(segment
		(start 82.916522 -140.828522)
		(end 81.616296 -140.828522)
		(width 0.127)
		(layer "F.Cu")
		(net "I2C_DPB_SDA_R")
	)
	(segment
		(start 83.395058 -141.090142)
		(end 83.2866 -141.1986)
		(width 0.127)
		(layer "F.Cu")
		(net "I2C_DPB_SDA_R")
	)
	(via
		(at 83.2866 -141.1986)
		(size 0.6604)
		(drill 0.3302)
		(layers "F.Cu" "B.Cu")
		(net "I2C_DPB_SDA_R")
	)
	(segment
		(start 45.97019 -159.0421)
		(end 45.2628 -159.74949)
		(width 0.127)
		(layer "F.Cu")
		(net "I2C_DPB_SDA_OUT")
	)
	(segment
		(start 78.637384 -139.726162)
		(end 78.636368 -139.725146)
		(width 0.127)
		(layer "F.Cu")
		(net "I2C_DPB_SDA_OUT")
	)
	(segment
		(start 75.977496 -141.478762)
		(end 76.916026 -141.478762)
		(width 0.127)
		(layer "F.Cu")
		(net "I2C_DPB_SDA_OUT")
	)
	(segment
		(start 76.916026 -141.478762)
		(end 76.994766 -141.400022)
		(width 0.127)
		(layer "F.Cu")
		(net "I2C_DPB_SDA_OUT")
	)
	(segment
		(start 78.637384 -140.920216)
		(end 78.637384 -139.726162)
		(width 0.127)
		(layer "F.Cu")
		(net "I2C_DPB_SDA_OUT")
	)
	(segment
		(start 45.409104 -160.786572)
		(end 45.409104 -160.115504)
		(width 0.127)
		(layer "F.Cu")
		(net "I2C_DPB_SDA_OUT")
	)
	(segment
		(start 45.409104 -160.115504)
		(end 45.2628 -159.9692)
		(width 0.127)
		(layer "F.Cu")
		(net "I2C_DPB_SDA_OUT")
	)
	(segment
		(start 45.2628 -159.74949)
		(end 45.2628 -159.9692)
		(width 0.127)
		(layer "F.Cu")
		(net "I2C_DPB_SDA_OUT")
	)
	(segment
		(start 78.157578 -141.400022)
		(end 78.637384 -140.920216)
		(width 0.127)
		(layer "F.Cu")
		(net "I2C_DPB_SDA_OUT")
	)
	(segment
		(start 76.994766 -141.400022)
		(end 78.157578 -141.400022)
		(width 0.127)
		(layer "F.Cu")
		(net "I2C_DPB_SDA_OUT")
	)
	(segment
		(start 78.520544 -139.609322)
		(end 77.701902 -139.609322)
		(width 0.127)
		(layer "F.Cu")
		(net "I2C_DPB_SDA_OUT")
	)
	(segment
		(start 78.636368 -139.725146)
		(end 78.520544 -139.609322)
		(width 0.127)
		(layer "F.Cu")
		(net "I2C_DPB_SDA_OUT")
	)
	(via
		(at 99.187 -169.9768)
		(size 0.508)
		(drill 0.254)
		(layers "F.Cu" "B.Cu")
		(net "I2C_DPB_SDA_OUT")
	)
	(via
		(at 77.701902 -139.609322)
		(size 0.508)
		(drill 0.254)
		(layers "F.Cu" "B.Cu")
		(net "I2C_DPB_SDA_OUT")
	)
	(via
		(at 45.2628 -159.9692)
		(size 0.508)
		(drill 0.254)
		(layers "F.Cu" "B.Cu")
		(net "I2C_DPB_SDA_OUT")
	)
	(via
		(at 99.94011 -140.4874)
		(size 0.508)
		(drill 0.254)
		(layers "F.Cu" "B.Cu")
		(net "I2C_DPB_SDA_OUT")
	)
	(via
		(at 78.636368 -139.725146)
		(size 0.6604)
		(drill 0.3302)
		(layers "F.Cu" "B.Cu")
		(net "I2C_DPB_SDA_OUT")
	)
	(segment
		(start 99.7204 -165.641274)
		(end 98.6536 -166.708074)
		(width 0.127)
		(layer "In2.Cu")
		(net "I2C_DPB_SDA_OUT")
	)
	(segment
		(start 98.9838 -143.346932)
		(end 98.9838 -157.657546)
		(width 0.127)
		(layer "In2.Cu")
		(net "I2C_DPB_SDA_OUT")
	)
	(segment
		(start 99.7204 -158.394146)
		(end 99.7204 -165.641274)
		(width 0.127)
		(layer "In2.Cu")
		(net "I2C_DPB_SDA_OUT")
	)
	(segment
		(start 99.94011 -142.390622)
		(end 98.9838 -143.346932)
		(width 0.127)
		(layer "In2.Cu")
		(net "I2C_DPB_SDA_OUT")
	)
	(segment
		(start 98.9838 -157.657546)
		(end 99.7204 -158.394146)
		(width 0.127)
		(layer "In2.Cu")
		(net "I2C_DPB_SDA_OUT")
	)
	(segment
		(start 98.6536 -169.4434)
		(end 99.187 -169.9768)
		(width 0.127)
		(layer "In2.Cu")
		(net "I2C_DPB_SDA_OUT")
	)
	(segment
		(start 99.94011 -140.4874)
		(end 99.94011 -142.390622)
		(width 0.127)
		(layer "In2.Cu")
		(net "I2C_DPB_SDA_OUT")
	)
	(segment
		(start 98.6536 -166.708074)
		(end 98.6536 -169.4434)
		(width 0.127)
		(layer "In2.Cu")
		(net "I2C_DPB_SDA_OUT")
	)
	(segment
		(start 68.5673 -167.1955)
		(end 59.452002 -167.1955)
		(width 0.127)
		(layer "In5.Cu")
		(net "I2C_DPB_SDA_OUT")
	)
	(segment
		(start 97.992946 -140.97)
		(end 99.410012 -140.97)
		(width 0.127)
		(layer "In5.Cu")
		(net "I2C_DPB_SDA_OUT")
	)
	(segment
		(start 53.968142 -163.448746)
		(end 49.423828 -163.448746)
		(width 0.127)
		(layer "In5.Cu")
		(net "I2C_DPB_SDA_OUT")
	)
	(segment
		(start 95.046546 -142.7988)
		(end 95.333566 -142.7988)
		(width 0.127)
		(layer "In5.Cu")
		(net "I2C_DPB_SDA_OUT")
	)
	(segment
		(start 88.3793 -168.2877)
		(end 87.77605 -167.68445)
		(width 0.127)
		(layer "In5.Cu")
		(net "I2C_DPB_SDA_OUT")
	)
	(segment
		(start 97.535746 -141.4272)
		(end 97.992946 -140.97)
		(width 0.127)
		(layer "In5.Cu")
		(net "I2C_DPB_SDA_OUT")
	)
	(segment
		(start 83.948016 -167.68445)
		(end 83.674712 -167.411146)
		(width 0.127)
		(layer "In5.Cu")
		(net "I2C_DPB_SDA_OUT")
	)
	(segment
		(start 54.243224 -164.050218)
		(end 54.243224 -163.723828)
		(width 0.127)
		(layer "In5.Cu")
		(net "I2C_DPB_SDA_OUT")
	)
	(segment
		(start 87.77605 -167.68445)
		(end 83.948016 -167.68445)
		(width 0.127)
		(layer "In5.Cu")
		(net "I2C_DPB_SDA_OUT")
	)
	(segment
		(start 85.748622 -141.58468)
		(end 86.575392 -140.75791)
		(width 0.127)
		(layer "In5.Cu")
		(net "I2C_DPB_SDA_OUT")
	)
	(segment
		(start 94.358968 -168.2877)
		(end 88.3793 -168.2877)
		(width 0.127)
		(layer "In5.Cu")
		(net "I2C_DPB_SDA_OUT")
	)
	(segment
		(start 48.327818 -162.0139)
		(end 47.3075 -162.0139)
		(width 0.127)
		(layer "In5.Cu")
		(net "I2C_DPB_SDA_OUT")
	)
	(segment
		(start 48.6537 -162.678618)
		(end 48.6537 -162.339782)
		(width 0.127)
		(layer "In5.Cu")
		(net "I2C_DPB_SDA_OUT")
	)
	(segment
		(start 95.333566 -142.7988)
		(end 95.371666 -142.7607)
		(width 0.127)
		(layer "In5.Cu")
		(net "I2C_DPB_SDA_OUT")
	)
	(segment
		(start 68.782946 -167.411146)
		(end 68.5673 -167.1955)
		(width 0.127)
		(layer "In5.Cu")
		(net "I2C_DPB_SDA_OUT")
	)
	(segment
		(start 79.146654 -141.06652)
		(end 82.113374 -141.06652)
		(width 0.127)
		(layer "In5.Cu")
		(net "I2C_DPB_SDA_OUT")
	)
	(segment
		(start 99.410012 -140.97)
		(end 99.76231 -140.61821)
		(width 0.127)
		(layer "In5.Cu")
		(net "I2C_DPB_SDA_OUT")
	)
	(segment
		(start 88.068404 -140.75791)
		(end 90.149934 -142.83944)
		(width 0.127)
		(layer "In5.Cu")
		(net "I2C_DPB_SDA_OUT")
	)
	(segment
		(start 54.243224 -163.723828)
		(end 53.968142 -163.448746)
		(width 0.127)
		(layer "In5.Cu")
		(net "I2C_DPB_SDA_OUT")
	)
	(segment
		(start 95.021146 -142.8242)
		(end 95.046546 -142.7988)
		(width 0.127)
		(layer "In5.Cu")
		(net "I2C_DPB_SDA_OUT")
	)
	(segment
		(start 82.631534 -141.58468)
		(end 85.748622 -141.58468)
		(width 0.127)
		(layer "In5.Cu")
		(net "I2C_DPB_SDA_OUT")
	)
	(segment
		(start 83.674712 -167.411146)
		(end 68.782946 -167.411146)
		(width 0.127)
		(layer "In5.Cu")
		(net "I2C_DPB_SDA_OUT")
	)
	(segment
		(start 86.575392 -140.75791)
		(end 88.068404 -140.75791)
		(width 0.127)
		(layer "In5.Cu")
		(net "I2C_DPB_SDA_OUT")
	)
	(segment
		(start 95.371666 -142.7607)
		(end 95.407226 -142.7607)
		(width 0.127)
		(layer "In5.Cu")
		(net "I2C_DPB_SDA_OUT")
	)
	(segment
		(start 92.686378 -142.83944)
		(end 92.902278 -142.62354)
		(width 0.127)
		(layer "In5.Cu")
		(net "I2C_DPB_SDA_OUT")
	)
	(segment
		(start 49.423828 -163.448746)
		(end 48.6537 -162.678618)
		(width 0.127)
		(layer "In5.Cu")
		(net "I2C_DPB_SDA_OUT")
	)
	(segment
		(start 99.187 -169.9768)
		(end 96.048068 -169.9768)
		(width 0.127)
		(layer "In5.Cu")
		(net "I2C_DPB_SDA_OUT")
	)
	(segment
		(start 93.472762 -142.8242)
		(end 95.021146 -142.8242)
		(width 0.127)
		(layer "In5.Cu")
		(net "I2C_DPB_SDA_OUT")
	)
	(segment
		(start 58.994802 -166.7383)
		(end 56.931306 -166.7383)
		(width 0.127)
		(layer "In5.Cu")
		(net "I2C_DPB_SDA_OUT")
	)
	(segment
		(start 95.407226 -142.7607)
		(end 96.740726 -141.4272)
		(width 0.127)
		(layer "In5.Cu")
		(net "I2C_DPB_SDA_OUT")
	)
	(segment
		(start 96.740726 -141.4272)
		(end 97.535746 -141.4272)
		(width 0.127)
		(layer "In5.Cu")
		(net "I2C_DPB_SDA_OUT")
	)
	(segment
		(start 59.452002 -167.1955)
		(end 58.994802 -166.7383)
		(width 0.127)
		(layer "In5.Cu")
		(net "I2C_DPB_SDA_OUT")
	)
	(segment
		(start 56.931306 -166.7383)
		(end 54.243224 -164.050218)
		(width 0.127)
		(layer "In5.Cu")
		(net "I2C_DPB_SDA_OUT")
	)
	(segment
		(start 93.272102 -142.62354)
		(end 93.472762 -142.8242)
		(width 0.127)
		(layer "In5.Cu")
		(net "I2C_DPB_SDA_OUT")
	)
	(segment
		(start 77.865478 -139.785344)
		(end 79.146654 -141.06652)
		(width 0.127)
		(layer "In5.Cu")
		(net "I2C_DPB_SDA_OUT")
	)
	(segment
		(start 90.149934 -142.83944)
		(end 92.686378 -142.83944)
		(width 0.127)
		(layer "In5.Cu")
		(net "I2C_DPB_SDA_OUT")
	)
	(segment
		(start 48.6537 -162.339782)
		(end 48.327818 -162.0139)
		(width 0.127)
		(layer "In5.Cu")
		(net "I2C_DPB_SDA_OUT")
	)
	(segment
		(start 99.89312 -140.4874)
		(end 99.94011 -140.4874)
		(width 0.127)
		(layer "In5.Cu")
		(net "I2C_DPB_SDA_OUT")
	)
	(segment
		(start 47.3075 -162.0139)
		(end 45.2628 -159.9692)
		(width 0.127)
		(layer "In5.Cu")
		(net "I2C_DPB_SDA_OUT")
	)
	(segment
		(start 82.113374 -141.06652)
		(end 82.631534 -141.58468)
		(width 0.127)
		(layer "In5.Cu")
		(net "I2C_DPB_SDA_OUT")
	)
	(segment
		(start 77.701902 -139.609322)
		(end 77.865478 -139.772898)
		(width 0.127)
		(layer "In5.Cu")
		(net "I2C_DPB_SDA_OUT")
	)
	(segment
		(start 92.902278 -142.62354)
		(end 93.272102 -142.62354)
		(width 0.127)
		(layer "In5.Cu")
		(net "I2C_DPB_SDA_OUT")
	)
	(segment
		(start 77.865478 -139.772898)
		(end 77.865478 -139.785344)
		(width 0.127)
		(layer "In5.Cu")
		(net "I2C_DPB_SDA_OUT")
	)
	(segment
		(start 99.76231 -140.61821)
		(end 99.89312 -140.4874)
		(width 0.127)
		(layer "In5.Cu")
		(net "I2C_DPB_SDA_OUT")
	)
	(segment
		(start 96.048068 -169.9768)
		(end 94.358968 -168.2877)
		(width 0.127)
		(layer "In5.Cu")
		(net "I2C_DPB_SDA_OUT")
	)
	(segment
		(start 86.069424 -141.22781)
		(end 86.77021 -141.22781)
		(width 0.127)
		(layer "F.Cu")
		(net "I2C_DPB_SDA")
	)
	(segment
		(start 104.775762 -27.995118)
		(end 104.775762 -44.613576)
		(width 0.127)
		(layer "F.Cu")
		(net "I2C_DPB_SDA")
	)
	(segment
		(start 99.6442 -122.010932)
		(end 99.6442 -123.276868)
		(width 0.127)
		(layer "F.Cu")
		(net "I2C_DPB_SDA")
	)
	(segment
		(start 101.846126 -132.227574)
		(end 101.0031 -133.0706)
		(width 0.127)
		(layer "F.Cu")
		(net "I2C_DPB_SDA")
	)
	(segment
		(start 109.221016 -27.356816)
		(end 105.414064 -27.356816)
		(width 0.127)
		(layer "F.Cu")
		(net "I2C_DPB_SDA")
	)
	(segment
		(start 105.414064 -27.356816)
		(end 104.775762 -27.995118)
		(width 0.127)
		(layer "F.Cu")
		(net "I2C_DPB_SDA")
	)
	(segment
		(start 104.775762 -44.613576)
		(end 102.2858 -47.103538)
		(width 0.127)
		(layer "F.Cu")
		(net "I2C_DPB_SDA")
	)
	(segment
		(start 101.846126 -125.478794)
		(end 101.846126 -132.227574)
		(width 0.127)
		(layer "F.Cu")
		(net "I2C_DPB_SDA")
	)
	(segment
		(start 99.6442 -123.276868)
		(end 101.846126 -125.478794)
		(width 0.127)
		(layer "F.Cu")
		(net "I2C_DPB_SDA")
	)
	(segment
		(start 102.2858 -114.927634)
		(end 100.45192 -116.761514)
		(width 0.127)
		(layer "F.Cu")
		(net "I2C_DPB_SDA")
	)
	(segment
		(start 110.700058 -45.39996)
		(end 109.5502 -44.250102)
		(width 0.127)
		(layer "F.Cu")
		(net "I2C_DPB_SDA")
	)
	(segment
		(start 100.45192 -121.203212)
		(end 99.6442 -122.010932)
		(width 0.127)
		(layer "F.Cu")
		(net "I2C_DPB_SDA")
	)
	(segment
		(start 100.45192 -116.761514)
		(end 100.45192 -121.203212)
		(width 0.127)
		(layer "F.Cu")
		(net "I2C_DPB_SDA")
	)
	(segment
		(start 85.931756 -141.090142)
		(end 86.069424 -141.22781)
		(width 0.127)
		(layer "F.Cu")
		(net "I2C_DPB_SDA")
	)
	(segment
		(start 109.5502 -44.250102)
		(end 109.5502 -27.686)
		(width 0.127)
		(layer "F.Cu")
		(net "I2C_DPB_SDA")
	)
	(segment
		(start 109.5502 -27.686)
		(end 109.221016 -27.356816)
		(width 0.127)
		(layer "F.Cu")
		(net "I2C_DPB_SDA")
	)
	(segment
		(start 102.2858 -47.103538)
		(end 102.2858 -114.927634)
		(width 0.127)
		(layer "F.Cu")
		(net "I2C_DPB_SDA")
	)
	(via
		(at 85.586062 -135.764524)
		(size 0.508)
		(drill 0.254)
		(layers "F.Cu" "B.Cu")
		(net "I2C_DPB_SDA")
	)
	(via
		(at 86.77021 -141.22781)
		(size 0.508)
		(drill 0.254)
		(layers "F.Cu" "B.Cu")
		(net "I2C_DPB_SDA")
	)
	(via
		(at 101.0031 -133.0706)
		(size 0.508)
		(drill 0.254)
		(layers "F.Cu" "B.Cu")
		(net "I2C_DPB_SDA")
	)
	(segment
		(start 86.77021 -141.22781)
		(end 86.73211 -141.18971)
		(width 0.127)
		(layer "B.Cu")
		(net "I2C_DPB_SDA")
	)
	(segment
		(start 86.73211 -137.27938)
		(end 85.586062 -136.133332)
		(width 0.127)
		(layer "B.Cu")
		(net "I2C_DPB_SDA")
	)
	(segment
		(start 85.586062 -136.133332)
		(end 85.586062 -135.764524)
		(width 0.127)
		(layer "B.Cu")
		(net "I2C_DPB_SDA")
	)
	(segment
		(start 86.73211 -141.18971)
		(end 86.73211 -137.27938)
		(width 0.127)
		(layer "B.Cu")
		(net "I2C_DPB_SDA")
	)
	(segment
		(start 86.915244 -135.7249)
		(end 85.625686 -135.7249)
		(width 0.127)
		(layer "In5.Cu")
		(net "I2C_DPB_SDA")
	)
	(segment
		(start 99.659186 -134.414514)
		(end 99.659186 -134.86384)
		(width 0.127)
		(layer "In5.Cu")
		(net "I2C_DPB_SDA")
	)
	(segment
		(start 98.716592 -135.806434)
		(end 88.994742 -135.806434)
		(width 0.127)
		(layer "In5.Cu")
		(net "I2C_DPB_SDA")
	)
	(segment
		(start 88.994742 -135.806434)
		(end 88.822276 -135.9789)
		(width 0.127)
		(layer "In5.Cu")
		(net "I2C_DPB_SDA")
	)
	(segment
		(start 101.0031 -133.0706)
		(end 99.659186 -134.414514)
		(width 0.127)
		(layer "In5.Cu")
		(net "I2C_DPB_SDA")
	)
	(segment
		(start 85.625686 -135.7249)
		(end 85.586062 -135.764524)
		(width 0.127)
		(layer "In5.Cu")
		(net "I2C_DPB_SDA")
	)
	(segment
		(start 88.822276 -135.9789)
		(end 87.169244 -135.9789)
		(width 0.127)
		(layer "In5.Cu")
		(net "I2C_DPB_SDA")
	)
	(segment
		(start 99.659186 -134.86384)
		(end 98.716592 -135.806434)
		(width 0.127)
		(layer "In5.Cu")
		(net "I2C_DPB_SDA")
	)
	(segment
		(start 87.169244 -135.9789)
		(end 86.915244 -135.7249)
		(width 0.127)
		(layer "In5.Cu")
		(net "I2C_DPB_SDA")
	)
	(segment
		(start 85.027516 -142.124176)
		(end 83.8454 -142.124176)
		(width 0.127)
		(layer "F.Cu")
		(net "I2C_DPB_SCL_R")
	)
	(segment
		(start 82.69986 -141.478762)
		(end 81.616296 -141.478762)
		(width 0.127)
		(layer "F.Cu")
		(net "I2C_DPB_SCL_R")
	)
	(segment
		(start 83.8454 -142.124176)
		(end 83.345274 -142.124176)
		(width 0.127)
		(layer "F.Cu")
		(net "I2C_DPB_SCL_R")
	)
	(segment
		(start 83.345274 -142.124176)
		(end 82.69986 -141.478762)
		(width 0.127)
		(layer "F.Cu")
		(net "I2C_DPB_SCL_R")
	)
	(via
		(at 83.8454 -142.124176)
		(size 0.6604)
		(drill 0.3302)
		(layers "F.Cu" "B.Cu")
		(net "I2C_DPB_SCL_R")
	)
	(segment
		(start 47.01159 -159.0421)
		(end 46.2534 -159.80029)
		(width 0.127)
		(layer "F.Cu")
		(net "I2C_DPB_SCL_OUT")
	)
	(segment
		(start 46.450504 -160.166304)
		(end 46.2534 -159.9692)
		(width 0.127)
		(layer "F.Cu")
		(net "I2C_DPB_SCL_OUT")
	)
	(segment
		(start 79.702914 -141.581886)
		(end 79.376778 -141.908022)
		(width 0.127)
		(layer "F.Cu")
		(net "I2C_DPB_SCL_OUT")
	)
	(segment
		(start 79.376778 -141.908022)
		(end 77.205332 -141.908022)
		(width 0.127)
		(layer "F.Cu")
		(net "I2C_DPB_SCL_OUT")
	)
	(segment
		(start 79.702914 -139.756134)
		(end 79.702914 -141.581886)
		(width 0.127)
		(layer "F.Cu")
		(net "I2C_DPB_SCL_OUT")
	)
	(segment
		(start 76.984352 -142.129002)
		(end 75.977496 -142.129002)
		(width 0.127)
		(layer "F.Cu")
		(net "I2C_DPB_SCL_OUT")
	)
	(segment
		(start 79.702914 -139.756134)
		(end 78.80858 -138.8618)
		(width 0.127)
		(layer "F.Cu")
		(net "I2C_DPB_SCL_OUT")
	)
	(segment
		(start 46.2534 -159.80029)
		(end 46.2534 -159.9692)
		(width 0.127)
		(layer "F.Cu")
		(net "I2C_DPB_SCL_OUT")
	)
	(segment
		(start 77.205332 -141.908022)
		(end 76.984352 -142.129002)
		(width 0.127)
		(layer "F.Cu")
		(net "I2C_DPB_SCL_OUT")
	)
	(segment
		(start 78.80858 -138.8618)
		(end 78.1812 -138.8618)
		(width 0.127)
		(layer "F.Cu")
		(net "I2C_DPB_SCL_OUT")
	)
	(segment
		(start 46.450504 -160.786572)
		(end 46.450504 -160.166304)
		(width 0.127)
		(layer "F.Cu")
		(net "I2C_DPB_SCL_OUT")
	)
	(via
		(at 99.187 -169.1132)
		(size 0.508)
		(drill 0.254)
		(layers "F.Cu" "B.Cu")
		(net "I2C_DPB_SCL_OUT")
	)
	(via
		(at 46.2534 -159.9692)
		(size 0.508)
		(drill 0.254)
		(layers "F.Cu" "B.Cu")
		(net "I2C_DPB_SCL_OUT")
	)
	(via
		(at 78.1812 -138.8618)
		(size 0.508)
		(drill 0.254)
		(layers "F.Cu" "B.Cu")
		(net "I2C_DPB_SCL_OUT")
	)
	(via
		(at 79.702914 -139.756134)
		(size 0.6604)
		(drill 0.3302)
		(layers "F.Cu" "B.Cu")
		(net "I2C_DPB_SCL_OUT")
	)
	(via
		(at 100.29952 -139.36218)
		(size 0.508)
		(drill 0.254)
		(layers "F.Cu" "B.Cu")
		(net "I2C_DPB_SCL_OUT")
	)
	(segment
		(start 100.44811 -143.426434)
		(end 99.4918 -144.382744)
		(width 0.127)
		(layer "In2.Cu")
		(net "I2C_DPB_SCL_OUT")
	)
	(segment
		(start 99.187 -166.89324)
		(end 99.187 -169.1132)
		(width 0.127)
		(layer "In2.Cu")
		(net "I2C_DPB_SCL_OUT")
	)
	(segment
		(start 99.4918 -144.382744)
		(end 99.4918 -157.378146)
		(width 0.127)
		(layer "In2.Cu")
		(net "I2C_DPB_SCL_OUT")
	)
	(segment
		(start 100.29952 -139.36218)
		(end 100.44811 -139.51077)
		(width 0.127)
		(layer "In2.Cu")
		(net "I2C_DPB_SCL_OUT")
	)
	(segment
		(start 100.44811 -165.63213)
		(end 99.187 -166.89324)
		(width 0.127)
		(layer "In2.Cu")
		(net "I2C_DPB_SCL_OUT")
	)
	(segment
		(start 100.44811 -139.51077)
		(end 100.44811 -143.426434)
		(width 0.127)
		(layer "In2.Cu")
		(net "I2C_DPB_SCL_OUT")
	)
	(segment
		(start 99.4918 -157.378146)
		(end 100.44811 -158.334456)
		(width 0.127)
		(layer "In2.Cu")
		(net "I2C_DPB_SCL_OUT")
	)
	(segment
		(start 100.44811 -158.334456)
		(end 100.44811 -165.63213)
		(width 0.127)
		(layer "In2.Cu")
		(net "I2C_DPB_SCL_OUT")
	)
	(segment
		(start 87.857838 -140.24991)
		(end 87.858092 -140.249656)
		(width 0.127)
		(layer "In5.Cu")
		(net "I2C_DPB_SCL_OUT")
	)
	(segment
		(start 89.263474 -167.7797)
		(end 88.660224 -167.17645)
		(width 0.127)
		(layer "In5.Cu")
		(net "I2C_DPB_SCL_OUT")
	)
	(segment
		(start 82.32394 -140.55852)
		(end 82.8421 -141.07668)
		(width 0.127)
		(layer "In5.Cu")
		(net "I2C_DPB_SCL_OUT")
	)
	(segment
		(start 87.858092 -140.249656)
		(end 88.278716 -140.249656)
		(width 0.127)
		(layer "In5.Cu")
		(net "I2C_DPB_SCL_OUT")
	)
	(segment
		(start 54.178708 -162.940746)
		(end 51.591464 -162.940746)
		(width 0.127)
		(layer "In5.Cu")
		(net "I2C_DPB_SCL_OUT")
	)
	(segment
		(start 93.482414 -142.115286)
		(end 93.657928 -142.2908)
		(width 0.127)
		(layer "In5.Cu")
		(net "I2C_DPB_SCL_OUT")
	)
	(segment
		(start 54.585362 -163.3474)
		(end 54.178708 -162.940746)
		(width 0.127)
		(layer "In5.Cu")
		(net "I2C_DPB_SCL_OUT")
	)
	(segment
		(start 51.591464 -162.940746)
		(end 50.156618 -161.5059)
		(width 0.127)
		(layer "In5.Cu")
		(net "I2C_DPB_SCL_OUT")
	)
	(segment
		(start 95.903034 -169.1132)
		(end 94.569534 -167.7797)
		(width 0.127)
		(layer "In5.Cu")
		(net "I2C_DPB_SCL_OUT")
	)
	(segment
		(start 99.1997 -140.462)
		(end 99.403154 -140.2588)
		(width 0.127)
		(layer "In5.Cu")
		(net "I2C_DPB_SCL_OUT")
	)
	(segment
		(start 94.569534 -167.7797)
		(end 89.263474 -167.7797)
		(width 0.127)
		(layer "In5.Cu")
		(net "I2C_DPB_SCL_OUT")
	)
	(segment
		(start 92.475812 -142.33144)
		(end 92.691966 -142.115286)
		(width 0.127)
		(layer "In5.Cu")
		(net "I2C_DPB_SCL_OUT")
	)
	(segment
		(start 83.85175 -166.8526)
		(end 77.144118 -166.8526)
		(width 0.127)
		(layer "In5.Cu")
		(net "I2C_DPB_SCL_OUT")
	)
	(segment
		(start 100.01885 -139.64285)
		(end 100.29952 -139.36218)
		(width 0.127)
		(layer "In5.Cu")
		(net "I2C_DPB_SCL_OUT")
	)
	(segment
		(start 56.162448 -164.182552)
		(end 56.162448 -163.72713)
		(width 0.127)
		(layer "In5.Cu")
		(net "I2C_DPB_SCL_OUT")
	)
	(segment
		(start 58.151776 -166.17188)
		(end 56.162448 -164.182552)
		(width 0.127)
		(layer "In5.Cu")
		(net "I2C_DPB_SCL_OUT")
	)
	(segment
		(start 85.538056 -141.07668)
		(end 86.364826 -140.24991)
		(width 0.127)
		(layer "In5.Cu")
		(net "I2C_DPB_SCL_OUT")
	)
	(segment
		(start 63.1825 -166.17188)
		(end 58.151776 -166.17188)
		(width 0.127)
		(layer "In5.Cu")
		(net "I2C_DPB_SCL_OUT")
	)
	(segment
		(start 88.660224 -167.17645)
		(end 84.1756 -167.17645)
		(width 0.127)
		(layer "In5.Cu")
		(net "I2C_DPB_SCL_OUT")
	)
	(segment
		(start 95.1611 -142.2527)
		(end 95.19666 -142.2527)
		(width 0.127)
		(layer "In5.Cu")
		(net "I2C_DPB_SCL_OUT")
	)
	(segment
		(start 71.623174 -166.55288)
		(end 63.5635 -166.55288)
		(width 0.127)
		(layer "In5.Cu")
		(net "I2C_DPB_SCL_OUT")
	)
	(segment
		(start 95.123 -142.2908)
		(end 95.1611 -142.2527)
		(width 0.127)
		(layer "In5.Cu")
		(net "I2C_DPB_SCL_OUT")
	)
	(segment
		(start 50.156618 -161.5059)
		(end 47.7901 -161.5059)
		(width 0.127)
		(layer "In5.Cu")
		(net "I2C_DPB_SCL_OUT")
	)
	(segment
		(start 99.403154 -140.2588)
		(end 100.01885 -139.643104)
		(width 0.127)
		(layer "In5.Cu")
		(net "I2C_DPB_SCL_OUT")
	)
	(segment
		(start 99.187 -169.1132)
		(end 95.903034 -169.1132)
		(width 0.127)
		(layer "In5.Cu")
		(net "I2C_DPB_SCL_OUT")
	)
	(segment
		(start 55.782718 -163.3474)
		(end 54.585362 -163.3474)
		(width 0.127)
		(layer "In5.Cu")
		(net "I2C_DPB_SCL_OUT")
	)
	(segment
		(start 71.75246 -166.423594)
		(end 71.623174 -166.55288)
		(width 0.127)
		(layer "In5.Cu")
		(net "I2C_DPB_SCL_OUT")
	)
	(segment
		(start 84.1756 -167.17645)
		(end 83.85175 -166.8526)
		(width 0.127)
		(layer "In5.Cu")
		(net "I2C_DPB_SCL_OUT")
	)
	(segment
		(start 82.8421 -141.07668)
		(end 85.538056 -141.07668)
		(width 0.127)
		(layer "In5.Cu")
		(net "I2C_DPB_SCL_OUT")
	)
	(segment
		(start 86.364826 -140.24991)
		(end 87.857838 -140.24991)
		(width 0.127)
		(layer "In5.Cu")
		(net "I2C_DPB_SCL_OUT")
	)
	(segment
		(start 56.162448 -163.72713)
		(end 55.782718 -163.3474)
		(width 0.127)
		(layer "In5.Cu")
		(net "I2C_DPB_SCL_OUT")
	)
	(segment
		(start 63.5635 -166.55288)
		(end 63.1825 -166.17188)
		(width 0.127)
		(layer "In5.Cu")
		(net "I2C_DPB_SCL_OUT")
	)
	(segment
		(start 77.144118 -166.8526)
		(end 76.715112 -166.423594)
		(width 0.127)
		(layer "In5.Cu")
		(net "I2C_DPB_SCL_OUT")
	)
	(segment
		(start 76.715112 -166.423594)
		(end 71.75246 -166.423594)
		(width 0.127)
		(layer "In5.Cu")
		(net "I2C_DPB_SCL_OUT")
	)
	(segment
		(start 90.3605 -142.33144)
		(end 92.475812 -142.33144)
		(width 0.127)
		(layer "In5.Cu")
		(net "I2C_DPB_SCL_OUT")
	)
	(segment
		(start 95.19666 -142.2527)
		(end 96.98736 -140.462)
		(width 0.127)
		(layer "In5.Cu")
		(net "I2C_DPB_SCL_OUT")
	)
	(segment
		(start 88.278716 -140.249656)
		(end 90.3605 -142.33144)
		(width 0.127)
		(layer "In5.Cu")
		(net "I2C_DPB_SCL_OUT")
	)
	(segment
		(start 93.657928 -142.2908)
		(end 95.123 -142.2908)
		(width 0.127)
		(layer "In5.Cu")
		(net "I2C_DPB_SCL_OUT")
	)
	(segment
		(start 100.01885 -139.643104)
		(end 100.01885 -139.64285)
		(width 0.127)
		(layer "In5.Cu")
		(net "I2C_DPB_SCL_OUT")
	)
	(segment
		(start 79.87792 -140.55852)
		(end 82.32394 -140.55852)
		(width 0.127)
		(layer "In5.Cu")
		(net "I2C_DPB_SCL_OUT")
	)
	(segment
		(start 47.7901 -161.5059)
		(end 46.2534 -159.9692)
		(width 0.127)
		(layer "In5.Cu")
		(net "I2C_DPB_SCL_OUT")
	)
	(segment
		(start 96.98736 -140.462)
		(end 99.1997 -140.462)
		(width 0.127)
		(layer "In5.Cu")
		(net "I2C_DPB_SCL_OUT")
	)
	(segment
		(start 78.1812 -138.8618)
		(end 79.87792 -140.55852)
		(width 0.127)
		(layer "In5.Cu")
		(net "I2C_DPB_SCL_OUT")
	)
	(segment
		(start 92.691966 -142.115286)
		(end 93.482414 -142.115286)
		(width 0.127)
		(layer "In5.Cu")
		(net "I2C_DPB_SCL_OUT")
	)
	(segment
		(start 104.267762 -27.784552)
		(end 104.267762 -44.40301)
		(width 0.127)
		(layer "F.Cu")
		(net "I2C_DPB_SCL")
	)
	(segment
		(start 101.1682 -130.441446)
		(end 101.1682 -131.8006)
		(width 0.127)
		(layer "F.Cu")
		(net "I2C_DPB_SCL")
	)
	(segment
		(start 99.1362 -121.800366)
		(end 99.1362 -123.487434)
		(width 0.127)
		(layer "F.Cu")
		(net "I2C_DPB_SCL")
	)
	(segment
		(start 100.4316 -124.782834)
		(end 100.4316 -129.704846)
		(width 0.127)
		(layer "F.Cu")
		(net "I2C_DPB_SCL")
	)
	(segment
		(start 101.1682 -131.8006)
		(end 101.0412 -131.9276)
		(width 0.127)
		(layer "F.Cu")
		(net "I2C_DPB_SCL")
	)
	(segment
		(start 101.0412 -131.9276)
		(end 101.0031 -131.9276)
		(width 0.127)
		(layer "F.Cu")
		(net "I2C_DPB_SCL")
	)
	(segment
		(start 99.1362 -123.487434)
		(end 100.4316 -124.782834)
		(width 0.127)
		(layer "F.Cu")
		(net "I2C_DPB_SCL")
	)
	(segment
		(start 99.94392 -120.992646)
		(end 99.1362 -121.800366)
		(width 0.127)
		(layer "F.Cu")
		(net "I2C_DPB_SCL")
	)
	(segment
		(start 100.4316 -129.704846)
		(end 101.1682 -130.441446)
		(width 0.127)
		(layer "F.Cu")
		(net "I2C_DPB_SCL")
	)
	(segment
		(start 99.94392 -116.550948)
		(end 99.94392 -120.992646)
		(width 0.127)
		(layer "F.Cu")
		(net "I2C_DPB_SCL")
	)
	(segment
		(start 101.7778 -46.892972)
		(end 101.7778 -114.717068)
		(width 0.127)
		(layer "F.Cu")
		(net "I2C_DPB_SCL")
	)
	(segment
		(start 101.7778 -114.717068)
		(end 99.94392 -116.550948)
		(width 0.127)
		(layer "F.Cu")
		(net "I2C_DPB_SCL")
	)
	(segment
		(start 85.916516 -142.124176)
		(end 86.587076 -142.124176)
		(width 0.127)
		(layer "F.Cu")
		(net "I2C_DPB_SCL")
	)
	(segment
		(start 110.0582 -27.305762)
		(end 109.601254 -26.848816)
		(width 0.127)
		(layer "F.Cu")
		(net "I2C_DPB_SCL")
	)
	(segment
		(start 86.587076 -142.124176)
		(end 86.7156 -142.2527)
		(width 0.127)
		(layer "F.Cu")
		(net "I2C_DPB_SCL")
	)
	(segment
		(start 105.203498 -26.848816)
		(end 104.267762 -27.784552)
		(width 0.127)
		(layer "F.Cu")
		(net "I2C_DPB_SCL")
	)
	(segment
		(start 110.0582 -43.358308)
		(end 110.0582 -27.305762)
		(width 0.127)
		(layer "F.Cu")
		(net "I2C_DPB_SCL")
	)
	(segment
		(start 109.601254 -26.848816)
		(end 105.203498 -26.848816)
		(width 0.127)
		(layer "F.Cu")
		(net "I2C_DPB_SCL")
	)
	(segment
		(start 110.700058 -44.000166)
		(end 110.0582 -43.358308)
		(width 0.127)
		(layer "F.Cu")
		(net "I2C_DPB_SCL")
	)
	(segment
		(start 104.267762 -44.40301)
		(end 101.7778 -46.892972)
		(width 0.127)
		(layer "F.Cu")
		(net "I2C_DPB_SCL")
	)
	(via
		(at 101.0031 -131.9276)
		(size 0.508)
		(drill 0.254)
		(layers "F.Cu" "B.Cu")
		(net "I2C_DPB_SCL")
	)
	(via
		(at 86.7156 -142.2527)
		(size 0.508)
		(drill 0.254)
		(layers "F.Cu" "B.Cu")
		(net "I2C_DPB_SCL")
	)
	(via
		(at 85.567774 -134.745984)
		(size 0.508)
		(drill 0.254)
		(layers "F.Cu" "B.Cu")
		(net "I2C_DPB_SCL")
	)
	(segment
		(start 85.999574 -134.746492)
		(end 85.56752 -134.746492)
		(width 0.127)
		(layer "B.Cu")
		(net "I2C_DPB_SCL")
	)
	(segment
		(start 87.24011 -135.987028)
		(end 85.999574 -134.746492)
		(width 0.127)
		(layer "B.Cu")
		(net "I2C_DPB_SCL")
	)
	(segment
		(start 85.56752 -134.745984)
		(end 85.567774 -134.745984)
		(width 0.127)
		(layer "B.Cu")
		(net "I2C_DPB_SCL")
	)
	(segment
		(start 87.24011 -141.72819)
		(end 87.24011 -135.987028)
		(width 0.127)
		(layer "B.Cu")
		(net "I2C_DPB_SCL")
	)
	(segment
		(start 85.56752 -134.746492)
		(end 85.56752 -134.745984)
		(width 0.127)
		(layer "B.Cu")
		(net "I2C_DPB_SCL")
	)
	(segment
		(start 86.7156 -142.2527)
		(end 87.24011 -141.72819)
		(width 0.127)
		(layer "B.Cu")
		(net "I2C_DPB_SCL")
	)
	(segment
		(start 99.1362 -134.66826)
		(end 98.506026 -135.298434)
		(width 0.127)
		(layer "In5.Cu")
		(net "I2C_DPB_SCL")
	)
	(segment
		(start 88.61171 -135.4709)
		(end 87.37981 -135.4709)
		(width 0.127)
		(layer "In5.Cu")
		(net "I2C_DPB_SCL")
	)
	(segment
		(start 88.784176 -135.298434)
		(end 88.61171 -135.4709)
		(width 0.127)
		(layer "In5.Cu")
		(net "I2C_DPB_SCL")
	)
	(segment
		(start 98.506026 -135.298434)
		(end 88.784176 -135.298434)
		(width 0.127)
		(layer "In5.Cu")
		(net "I2C_DPB_SCL")
	)
	(segment
		(start 87.015066 -135.106156)
		(end 85.927946 -135.106156)
		(width 0.127)
		(layer "In5.Cu")
		(net "I2C_DPB_SCL")
	)
	(segment
		(start 85.927946 -135.106156)
		(end 85.567774 -134.745984)
		(width 0.127)
		(layer "In5.Cu")
		(net "I2C_DPB_SCL")
	)
	(segment
		(start 101.0031 -131.9276)
		(end 99.1362 -133.7945)
		(width 0.127)
		(layer "In5.Cu")
		(net "I2C_DPB_SCL")
	)
	(segment
		(start 99.1362 -133.7945)
		(end 99.1362 -134.66826)
		(width 0.127)
		(layer "In5.Cu")
		(net "I2C_DPB_SCL")
	)
	(segment
		(start 87.37981 -135.4709)
		(end 87.015066 -135.106156)
		(width 0.127)
		(layer "In5.Cu")
		(net "I2C_DPB_SCL")
	)
	(segment
		(start 97.8408 -82.187034)
		(end 97.8408 -87.097108)
		(width 0.127)
		(layer "F.Cu")
		(net "I2C_DPB_MISC_SDA")
	)
	(segment
		(start 121.9962 -18.3896)
		(end 118.6688 -18.3896)
		(width 0.127)
		(layer "F.Cu")
		(net "I2C_DPB_MISC_SDA")
	)
	(segment
		(start 98.043746 -26.181812)
		(end 98.043746 -63.418974)
		(width 0.127)
		(layer "F.Cu")
		(net "I2C_DPB_MISC_SDA")
	)
	(segment
		(start 118.6688 -18.3896)
		(end 117.2591 -16.9799)
		(width 0.127)
		(layer "F.Cu")
		(net "I2C_DPB_MISC_SDA")
	)
	(segment
		(start 106.387392 -20.477988)
		(end 103.74757 -20.477988)
		(width 0.127)
		(layer "F.Cu")
		(net "I2C_DPB_MISC_SDA")
	)
	(segment
		(start 97.54616 -81.892394)
		(end 97.8408 -82.187034)
		(width 0.127)
		(layer "F.Cu")
		(net "I2C_DPB_MISC_SDA")
	)
	(segment
		(start 98.043746 -63.418974)
		(end 97.54616 -63.91656)
		(width 0.127)
		(layer "F.Cu")
		(net "I2C_DPB_MISC_SDA")
	)
	(segment
		(start 97.8408 -87.097108)
		(end 96.722946 -88.214962)
		(width 0.127)
		(layer "F.Cu")
		(net "I2C_DPB_MISC_SDA")
	)
	(segment
		(start 122.4788 -17.907)
		(end 121.9962 -18.3896)
		(width 0.127)
		(layer "F.Cu")
		(net "I2C_DPB_MISC_SDA")
	)
	(segment
		(start 97.54616 -63.91656)
		(end 97.54616 -81.892394)
		(width 0.127)
		(layer "F.Cu")
		(net "I2C_DPB_MISC_SDA")
	)
	(segment
		(start 98.7425 -172.6692)
		(end 99.568 -172.6692)
		(width 0.127)
		(layer "F.Cu")
		(net "I2C_DPB_MISC_SDA")
	)
	(segment
		(start 117.2591 -16.9799)
		(end 117.0432 -16.9799)
		(width 0.127)
		(layer "F.Cu")
		(net "I2C_DPB_MISC_SDA")
	)
	(segment
		(start 109.88548 -16.9799)
		(end 106.387392 -20.477988)
		(width 0.127)
		(layer "F.Cu")
		(net "I2C_DPB_MISC_SDA")
	)
	(segment
		(start 103.74757 -20.477988)
		(end 98.043746 -26.181812)
		(width 0.127)
		(layer "F.Cu")
		(net "I2C_DPB_MISC_SDA")
	)
	(segment
		(start 117.0432 -16.9799)
		(end 109.88548 -16.9799)
		(width 0.127)
		(layer "F.Cu")
		(net "I2C_DPB_MISC_SDA")
	)
	(via
		(at 117.0432 -16.9799)
		(size 0.6604)
		(drill 0.3302)
		(layers "F.Cu" "B.Cu")
		(net "I2C_DPB_MISC_SDA")
	)
	(via
		(at 96.722946 -88.214962)
		(size 0.508)
		(drill 0.254)
		(layers "F.Cu" "B.Cu")
		(net "I2C_DPB_MISC_SDA")
	)
	(via
		(at 99.568 -172.6692)
		(size 0.508)
		(drill 0.254)
		(layers "F.Cu" "B.Cu")
		(net "I2C_DPB_MISC_SDA")
	)
	(via
		(at 122.4788 -17.907)
		(size 0.508)
		(drill 0.254)
		(layers "F.Cu" "B.Cu")
		(net "I2C_DPB_MISC_SDA")
	)
	(segment
		(start 101.0158 -92.507816)
		(end 96.722946 -88.214962)
		(width 0.127)
		(layer "B.Cu")
		(net "I2C_DPB_MISC_SDA")
	)
	(segment
		(start 101.0158 -127.9144)
		(end 101.0158 -92.507816)
		(width 0.127)
		(layer "B.Cu")
		(net "I2C_DPB_MISC_SDA")
	)
	(segment
		(start 101.1809 -164.973508)
		(end 101.1809 -137.477246)
		(width 0.127)
		(layer "B.Cu")
		(net "I2C_DPB_MISC_SDA")
	)
	(segment
		(start 100.324666 -128.605534)
		(end 101.0158 -127.9144)
		(width 0.127)
		(layer "B.Cu")
		(net "I2C_DPB_MISC_SDA")
	)
	(segment
		(start 100.324666 -136.621012)
		(end 100.324666 -128.605534)
		(width 0.127)
		(layer "B.Cu")
		(net "I2C_DPB_MISC_SDA")
	)
	(segment
		(start 99.568 -172.6692)
		(end 99.6696 -172.5676)
		(width 0.127)
		(layer "B.Cu")
		(net "I2C_DPB_MISC_SDA")
	)
	(segment
		(start 101.1809 -137.477246)
		(end 100.324666 -136.621012)
		(width 0.127)
		(layer "B.Cu")
		(net "I2C_DPB_MISC_SDA")
	)
	(segment
		(start 99.6696 -166.484808)
		(end 101.1809 -164.973508)
		(width 0.127)
		(layer "B.Cu")
		(net "I2C_DPB_MISC_SDA")
	)
	(segment
		(start 99.6696 -172.5676)
		(end 99.6696 -166.484808)
		(width 0.127)
		(layer "B.Cu")
		(net "I2C_DPB_MISC_SDA")
	)
	(segment
		(start 122.4788 -18.034)
		(end 127.127 -22.6822)
		(width 0.127)
		(layer "In2.Cu")
		(net "I2C_DPB_MISC_SDA")
	)
	(segment
		(start 134.380986 -22.6822)
		(end 140.579348 -28.880562)
		(width 0.127)
		(layer "In2.Cu")
		(net "I2C_DPB_MISC_SDA")
	)
	(segment
		(start 140.579348 -28.880562)
		(end 140.579348 -44.32046)
		(width 0.127)
		(layer "In2.Cu")
		(net "I2C_DPB_MISC_SDA")
	)
	(segment
		(start 127.127 -22.6822)
		(end 134.380986 -22.6822)
		(width 0.127)
		(layer "In2.Cu")
		(net "I2C_DPB_MISC_SDA")
	)
	(segment
		(start 140.579348 -44.32046)
		(end 139.499848 -45.39996)
		(width 0.127)
		(layer "In2.Cu")
		(net "I2C_DPB_MISC_SDA")
	)
	(segment
		(start 122.4788 -17.907)
		(end 122.4788 -18.034)
		(width 0.127)
		(layer "In2.Cu")
		(net "I2C_DPB_MISC_SDA")
	)
	(segment
		(start 121.56186 -17.85874)
		(end 118.856506 -17.85874)
		(width 0.127)
		(layer "F.Cu")
		(net "I2C_DPB_MISC_SCL")
	)
	(segment
		(start 97.155 -86.974172)
		(end 96.776286 -87.352886)
		(width 0.127)
		(layer "F.Cu")
		(net "I2C_DPB_MISC_SCL")
	)
	(segment
		(start 117.329966 -16.3322)
		(end 109.814614 -16.3322)
		(width 0.127)
		(layer "F.Cu")
		(net "I2C_DPB_MISC_SCL")
	)
	(segment
		(start 97.535746 -63.208408)
		(end 96.8756 -63.868554)
		(width 0.127)
		(layer "F.Cu")
		(net "I2C_DPB_MISC_SCL")
	)
	(segment
		(start 96.8756 -63.868554)
		(end 96.8756 -81.9404)
		(width 0.127)
		(layer "F.Cu")
		(net "I2C_DPB_MISC_SCL")
	)
	(segment
		(start 103.537004 -19.969988)
		(end 97.535746 -25.971246)
		(width 0.127)
		(layer "F.Cu")
		(net "I2C_DPB_MISC_SCL")
	)
	(segment
		(start 109.814614 -16.3322)
		(end 106.176826 -19.969988)
		(width 0.127)
		(layer "F.Cu")
		(net "I2C_DPB_MISC_SCL")
	)
	(segment
		(start 96.8756 -81.9404)
		(end 97.3328 -82.3976)
		(width 0.127)
		(layer "F.Cu")
		(net "I2C_DPB_MISC_SCL")
	)
	(segment
		(start 97.535746 -25.971246)
		(end 97.535746 -63.208408)
		(width 0.127)
		(layer "F.Cu")
		(net "I2C_DPB_MISC_SCL")
	)
	(segment
		(start 97.3328 -86.1314)
		(end 97.155 -86.3092)
		(width 0.127)
		(layer "F.Cu")
		(net "I2C_DPB_MISC_SCL")
	)
	(segment
		(start 97.155 -86.3092)
		(end 97.155 -86.974172)
		(width 0.127)
		(layer "F.Cu")
		(net "I2C_DPB_MISC_SCL")
	)
	(segment
		(start 118.856506 -17.85874)
		(end 117.329966 -16.3322)
		(width 0.127)
		(layer "F.Cu")
		(net "I2C_DPB_MISC_SCL")
	)
	(segment
		(start 106.176826 -19.969988)
		(end 103.537004 -19.969988)
		(width 0.127)
		(layer "F.Cu")
		(net "I2C_DPB_MISC_SCL")
	)
	(segment
		(start 97.3328 -82.3976)
		(end 97.3328 -86.1314)
		(width 0.127)
		(layer "F.Cu")
		(net "I2C_DPB_MISC_SCL")
	)
	(segment
		(start 98.7679 -173.7106)
		(end 99.5934 -173.7106)
		(width 0.127)
		(layer "F.Cu")
		(net "I2C_DPB_MISC_SCL")
	)
	(via
		(at 121.56186 -17.85874)
		(size 0.508)
		(drill 0.254)
		(layers "F.Cu" "B.Cu")
		(net "I2C_DPB_MISC_SCL")
	)
	(via
		(at 96.776286 -87.352886)
		(size 0.508)
		(drill 0.254)
		(layers "F.Cu" "B.Cu")
		(net "I2C_DPB_MISC_SCL")
	)
	(via
		(at 97.155 -86.3092)
		(size 0.6604)
		(drill 0.3302)
		(layers "F.Cu" "B.Cu")
		(net "I2C_DPB_MISC_SCL")
	)
	(via
		(at 99.5934 -173.7106)
		(size 0.508)
		(drill 0.254)
		(layers "F.Cu" "B.Cu")
		(net "I2C_DPB_MISC_SCL")
	)
	(segment
		(start 101.6889 -165.184074)
		(end 101.6889 -135.1915)
		(width 0.127)
		(layer "B.Cu")
		(net "I2C_DPB_MISC_SCL")
	)
	(segment
		(start 101.5238 -92.1004)
		(end 96.776286 -87.352886)
		(width 0.127)
		(layer "B.Cu")
		(net "I2C_DPB_MISC_SCL")
	)
	(segment
		(start 101.5238 -135.0264)
		(end 101.5238 -92.1004)
		(width 0.127)
		(layer "B.Cu")
		(net "I2C_DPB_MISC_SCL")
	)
	(segment
		(start 99.5934 -173.7106)
		(end 100.1776 -173.1264)
		(width 0.127)
		(layer "B.Cu")
		(net "I2C_DPB_MISC_SCL")
	)
	(segment
		(start 100.1776 -173.1264)
		(end 100.1776 -166.695374)
		(width 0.127)
		(layer "B.Cu")
		(net "I2C_DPB_MISC_SCL")
	)
	(segment
		(start 100.1776 -166.695374)
		(end 101.6889 -165.184074)
		(width 0.127)
		(layer "B.Cu")
		(net "I2C_DPB_MISC_SCL")
	)
	(segment
		(start 101.6889 -135.1915)
		(end 101.5238 -135.0264)
		(width 0.127)
		(layer "B.Cu")
		(net "I2C_DPB_MISC_SCL")
	)
	(segment
		(start 134.17042 -23.1902)
		(end 140.071348 -29.091128)
		(width 0.127)
		(layer "In2.Cu")
		(net "I2C_DPB_MISC_SCL")
	)
	(segment
		(start 121.56186 -17.85874)
		(end 126.89332 -23.1902)
		(width 0.127)
		(layer "In2.Cu")
		(net "I2C_DPB_MISC_SCL")
	)
	(segment
		(start 140.071348 -43.428666)
		(end 139.499848 -44.000166)
		(width 0.127)
		(layer "In2.Cu")
		(net "I2C_DPB_MISC_SCL")
	)
	(segment
		(start 126.89332 -23.1902)
		(end 134.17042 -23.1902)
		(width 0.127)
		(layer "In2.Cu")
		(net "I2C_DPB_MISC_SCL")
	)
	(segment
		(start 140.071348 -29.091128)
		(end 140.071348 -43.428666)
		(width 0.127)
		(layer "In2.Cu")
		(net "I2C_DPB_MISC_SCL")
	)
	(segment
		(start 98.514916 -145.628106)
		(end 97.521776 -145.628106)
		(width 0.127)
		(layer "F.Cu")
		(net "I2C_DEBUG_SDA_R")
	)
	(segment
		(start 97.521776 -145.628106)
		(end 97.473516 -145.579846)
		(width 0.127)
		(layer "F.Cu")
		(net "I2C_DEBUG_SDA_R")
	)
	(segment
		(start 97.473516 -145.579846)
		(end 95.996506 -145.579846)
		(width 0.127)
		(layer "F.Cu")
		(net "I2C_DEBUG_SDA_R")
	)
	(segment
		(start 98.601276 -145.541746)
		(end 98.514916 -145.628106)
		(width 0.127)
		(layer "F.Cu")
		(net "I2C_DEBUG_SDA_R")
	)
	(via
		(at 97.521776 -145.628106)
		(size 0.6604)
		(drill 0.3302)
		(layers "F.Cu" "B.Cu")
		(net "I2C_DEBUG_SDA_R")
	)
	(segment
		(start 94.62008 -13.4112)
		(end 94.62008 -14.34592)
		(width 0.127)
		(layer "F.Cu")
		(net "I2C_DEBUG_SDA")
	)
	(segment
		(start 89.799922 -15.979902)
		(end 90.412824 -15.367)
		(width 0.127)
		(layer "F.Cu")
		(net "I2C_DEBUG_SDA")
	)
	(segment
		(start 92.456 -15.367)
		(end 94.4118 -13.4112)
		(width 0.127)
		(layer "F.Cu")
		(net "I2C_DEBUG_SDA")
	)
	(segment
		(start 94.4118 -13.4112)
		(end 94.62008 -13.4112)
		(width 0.127)
		(layer "F.Cu")
		(net "I2C_DEBUG_SDA")
	)
	(segment
		(start 94.62008 -14.34592)
		(end 94.615 -14.351)
		(width 0.127)
		(layer "F.Cu")
		(net "I2C_DEBUG_SDA")
	)
	(segment
		(start 90.412824 -15.367)
		(end 92.456 -15.367)
		(width 0.127)
		(layer "F.Cu")
		(net "I2C_DEBUG_SDA")
	)
	(via
		(at 81.5594 -97.757996)
		(size 0.508)
		(drill 0.254)
		(layers "F.Cu" "B.Cu")
		(net "I2C_DEBUG_SDA")
	)
	(via
		(at 68.8594 -123.4186)
		(size 0.508)
		(drill 0.254)
		(layers "F.Cu" "B.Cu")
		(net "I2C_DEBUG_SDA")
	)
	(via
		(at 71.032116 -126.30277)
		(size 0.6096)
		(drill 0.3048)
		(layers "F.Cu" "B.Cu")
		(net "I2C_DEBUG_SDA")
	)
	(via
		(at 94.615 -14.351)
		(size 0.508)
		(drill 0.254)
		(layers "F.Cu" "B.Cu")
		(net "I2C_DEBUG_SDA")
	)
	(segment
		(start 77.701394 -147.774406)
		(end 77.701394 -145.982436)
		(width 0.127)
		(layer "B.Cu")
		(net "I2C_DEBUG_SDA")
	)
	(segment
		(start 74.617834 -148.089366)
		(end 74.42073 -148.28647)
		(width 0.127)
		(layer "B.Cu")
		(net "I2C_DEBUG_SDA")
	)
	(segment
		(start 75.512168 -148.089366)
		(end 76.105766 -148.089366)
		(width 0.127)
		(layer "B.Cu")
		(net "I2C_DEBUG_SDA")
	)
	(segment
		(start 80.4037 -134.610856)
		(end 80.4037 -134.605776)
		(width 0.127)
		(layer "B.Cu")
		(net "I2C_DEBUG_SDA")
	)
	(segment
		(start 78.37805 -145.30578)
		(end 78.37805 -144.135348)
		(width 0.127)
		(layer "B.Cu")
		(net "I2C_DEBUG_SDA")
	)
	(segment
		(start 71.9328 -127.814578)
		(end 71.9328 -127.203454)
		(width 0.127)
		(layer "B.Cu")
		(net "I2C_DEBUG_SDA")
	)
	(segment
		(start 80.4037 -134.605776)
		(end 74.744834 -128.94691)
		(width 0.127)
		(layer "B.Cu")
		(net "I2C_DEBUG_SDA")
	)
	(segment
		(start 71.9328 -127.203454)
		(end 71.032116 -126.30277)
		(width 0.127)
		(layer "B.Cu")
		(net "I2C_DEBUG_SDA")
	)
	(segment
		(start 76.105766 -148.089366)
		(end 76.3524 -148.336)
		(width 0.127)
		(layer "B.Cu")
		(net "I2C_DEBUG_SDA")
	)
	(segment
		(start 68.8594 -125.087634)
		(end 70.074536 -126.30277)
		(width 0.127)
		(layer "B.Cu")
		(net "I2C_DEBUG_SDA")
	)
	(segment
		(start 73.065132 -128.94691)
		(end 71.9328 -127.814578)
		(width 0.127)
		(layer "B.Cu")
		(net "I2C_DEBUG_SDA")
	)
	(segment
		(start 77.701394 -145.982436)
		(end 78.37805 -145.30578)
		(width 0.127)
		(layer "B.Cu")
		(net "I2C_DEBUG_SDA")
	)
	(segment
		(start 76.3524 -148.336)
		(end 77.1398 -148.336)
		(width 0.127)
		(layer "B.Cu")
		(net "I2C_DEBUG_SDA")
	)
	(segment
		(start 74.42073 -148.28647)
		(end 73.224644 -148.28647)
		(width 0.127)
		(layer "B.Cu")
		(net "I2C_DEBUG_SDA")
	)
	(segment
		(start 68.8594 -123.4186)
		(end 68.8594 -125.087634)
		(width 0.127)
		(layer "B.Cu")
		(net "I2C_DEBUG_SDA")
	)
	(segment
		(start 74.744834 -128.94691)
		(end 73.065132 -128.94691)
		(width 0.127)
		(layer "B.Cu")
		(net "I2C_DEBUG_SDA")
	)
	(segment
		(start 80.607154 -138.970512)
		(end 80.607154 -134.81431)
		(width 0.127)
		(layer "B.Cu")
		(net "I2C_DEBUG_SDA")
	)
	(segment
		(start 79.758032 -142.755366)
		(end 79.758032 -139.819634)
		(width 0.127)
		(layer "B.Cu")
		(net "I2C_DEBUG_SDA")
	)
	(segment
		(start 70.074536 -126.30277)
		(end 71.032116 -126.30277)
		(width 0.127)
		(layer "B.Cu")
		(net "I2C_DEBUG_SDA")
	)
	(segment
		(start 78.37805 -144.135348)
		(end 79.758032 -142.755366)
		(width 0.127)
		(layer "B.Cu")
		(net "I2C_DEBUG_SDA")
	)
	(segment
		(start 80.607154 -134.81431)
		(end 80.4037 -134.610856)
		(width 0.127)
		(layer "B.Cu")
		(net "I2C_DEBUG_SDA")
	)
	(segment
		(start 77.1398 -148.336)
		(end 77.701394 -147.774406)
		(width 0.127)
		(layer "B.Cu")
		(net "I2C_DEBUG_SDA")
	)
	(segment
		(start 75.512168 -148.089366)
		(end 74.617834 -148.089366)
		(width 0.127)
		(layer "B.Cu")
		(net "I2C_DEBUG_SDA")
	)
	(segment
		(start 79.758032 -139.819634)
		(end 80.607154 -138.970512)
		(width 0.127)
		(layer "B.Cu")
		(net "I2C_DEBUG_SDA")
	)
	(segment
		(start 78.779624 -109.9312)
		(end 73.03262 -115.678204)
		(width 0.127)
		(layer "In2.Cu")
		(net "I2C_DEBUG_SDA")
	)
	(segment
		(start 82.350102 -99.817936)
		(end 85.7123 -103.180134)
		(width 0.127)
		(layer "In2.Cu")
		(net "I2C_DEBUG_SDA")
	)
	(segment
		(start 72.009 -116.725192)
		(end 72.009 -119.626888)
		(width 0.127)
		(layer "In2.Cu")
		(net "I2C_DEBUG_SDA")
	)
	(segment
		(start 81.5594 -97.757996)
		(end 82.350102 -98.548698)
		(width 0.127)
		(layer "In2.Cu")
		(net "I2C_DEBUG_SDA")
	)
	(segment
		(start 82.361278 -109.9312)
		(end 78.779624 -109.9312)
		(width 0.127)
		(layer "In2.Cu")
		(net "I2C_DEBUG_SDA")
	)
	(segment
		(start 73.03262 -115.678204)
		(end 73.03262 -115.701572)
		(width 0.127)
		(layer "In2.Cu")
		(net "I2C_DEBUG_SDA")
	)
	(segment
		(start 85.7123 -106.580178)
		(end 82.361278 -109.9312)
		(width 0.127)
		(layer "In2.Cu")
		(net "I2C_DEBUG_SDA")
	)
	(segment
		(start 68.8594 -122.776488)
		(end 68.8594 -123.4186)
		(width 0.127)
		(layer "In2.Cu")
		(net "I2C_DEBUG_SDA")
	)
	(segment
		(start 82.350102 -98.548698)
		(end 82.350102 -99.817936)
		(width 0.127)
		(layer "In2.Cu")
		(net "I2C_DEBUG_SDA")
	)
	(segment
		(start 73.03262 -115.701572)
		(end 72.009 -116.725192)
		(width 0.127)
		(layer "In2.Cu")
		(net "I2C_DEBUG_SDA")
	)
	(segment
		(start 85.7123 -103.180134)
		(end 85.7123 -106.580178)
		(width 0.127)
		(layer "In2.Cu")
		(net "I2C_DEBUG_SDA")
	)
	(segment
		(start 72.009 -119.626888)
		(end 68.8594 -122.776488)
		(width 0.127)
		(layer "In2.Cu")
		(net "I2C_DEBUG_SDA")
	)
	(segment
		(start 92.48521 -9.906762)
		(end 84.880958 -9.906762)
		(width 0.127)
		(layer "In5.Cu")
		(net "I2C_DEBUG_SDA")
	)
	(segment
		(start 80.0862 -57.203086)
		(end 80.518 -57.634886)
		(width 0.127)
		(layer "In5.Cu")
		(net "I2C_DEBUG_SDA")
	)
	(segment
		(start 84.078572 -40.186102)
		(end 80.0862 -44.178474)
		(width 0.127)
		(layer "In5.Cu")
		(net "I2C_DEBUG_SDA")
	)
	(segment
		(start 80.3148 -96.513396)
		(end 81.5594 -97.757996)
		(width 0.127)
		(layer "In5.Cu")
		(net "I2C_DEBUG_SDA")
	)
	(segment
		(start 80.518 -92.807028)
		(end 80.3148 -93.010228)
		(width 0.127)
		(layer "In5.Cu")
		(net "I2C_DEBUG_SDA")
	)
	(segment
		(start 84.880958 -9.906762)
		(end 84.078572 -10.709148)
		(width 0.127)
		(layer "In5.Cu")
		(net "I2C_DEBUG_SDA")
	)
	(segment
		(start 94.615 -14.351)
		(end 94.615 -12.036552)
		(width 0.127)
		(layer "In5.Cu")
		(net "I2C_DEBUG_SDA")
	)
	(segment
		(start 80.518 -57.634886)
		(end 80.518 -92.807028)
		(width 0.127)
		(layer "In5.Cu")
		(net "I2C_DEBUG_SDA")
	)
	(segment
		(start 80.0862 -44.178474)
		(end 80.0862 -57.203086)
		(width 0.127)
		(layer "In5.Cu")
		(net "I2C_DEBUG_SDA")
	)
	(segment
		(start 80.3148 -93.010228)
		(end 80.3148 -96.513396)
		(width 0.127)
		(layer "In5.Cu")
		(net "I2C_DEBUG_SDA")
	)
	(segment
		(start 84.078572 -10.709148)
		(end 84.078572 -40.186102)
		(width 0.127)
		(layer "In5.Cu")
		(net "I2C_DEBUG_SDA")
	)
	(segment
		(start 94.615 -12.036552)
		(end 92.48521 -9.906762)
		(width 0.127)
		(layer "In5.Cu")
		(net "I2C_DEBUG_SDA")
	)
	(segment
		(start 97.66173 -144.5514)
		(end 97.283524 -144.929606)
		(width 0.127)
		(layer "F.Cu")
		(net "I2C_DEBUG_SCL_R")
	)
	(segment
		(start 97.283524 -144.929606)
		(end 95.996506 -144.929606)
		(width 0.127)
		(layer "F.Cu")
		(net "I2C_DEBUG_SCL_R")
	)
	(segment
		(start 97.66173 -144.5514)
		(end 98.418904 -144.5514)
		(width 0.127)
		(layer "F.Cu")
		(net "I2C_DEBUG_SCL_R")
	)
	(segment
		(start 98.418904 -144.5514)
		(end 98.58883 -144.381474)
		(width 0.127)
		(layer "F.Cu")
		(net "I2C_DEBUG_SCL_R")
	)
	(via
		(at 97.66173 -144.5514)
		(size 0.6604)
		(drill 0.3302)
		(layers "F.Cu" "B.Cu")
		(net "I2C_DEBUG_SCL_R")
	)
	(segment
		(start 94.62008 -11.30808)
		(end 94.615 -11.303)
		(width 0.127)
		(layer "F.Cu")
		(net "I2C_DEBUG_SCL")
	)
	(segment
		(start 89.799922 -13.979906)
		(end 90.399616 -14.5796)
		(width 0.127)
		(layer "F.Cu")
		(net "I2C_DEBUG_SCL")
	)
	(segment
		(start 94.3102 -12.2428)
		(end 94.62008 -12.2428)
		(width 0.127)
		(layer "F.Cu")
		(net "I2C_DEBUG_SCL")
	)
	(segment
		(start 90.399616 -14.5796)
		(end 91.9734 -14.5796)
		(width 0.127)
		(layer "F.Cu")
		(net "I2C_DEBUG_SCL")
	)
	(segment
		(start 91.9734 -14.5796)
		(end 94.3102 -12.2428)
		(width 0.127)
		(layer "F.Cu")
		(net "I2C_DEBUG_SCL")
	)
	(segment
		(start 94.62008 -12.2428)
		(end 94.62008 -11.30808)
		(width 0.127)
		(layer "F.Cu")
		(net "I2C_DEBUG_SCL")
	)
	(via
		(at 94.615 -11.303)
		(size 0.508)
		(drill 0.254)
		(layers "F.Cu" "B.Cu")
		(net "I2C_DEBUG_SCL")
	)
	(via
		(at 81.752186 -98.63201)
		(size 0.508)
		(drill 0.254)
		(layers "F.Cu" "B.Cu")
		(net "I2C_DEBUG_SCL")
	)
	(via
		(at 73.80986 -129.504186)
		(size 0.6096)
		(drill 0.3048)
		(layers "F.Cu" "B.Cu")
		(net "I2C_DEBUG_SCL")
	)
	(via
		(at 67.98818 -123.41098)
		(size 0.508)
		(drill 0.254)
		(layers "F.Cu" "B.Cu")
		(net "I2C_DEBUG_SCL")
	)
	(segment
		(start 73.86955 -147.483576)
		(end 73.647554 -147.26158)
		(width 0.127)
		(layer "B.Cu")
		(net "I2C_DEBUG_SCL")
	)
	(segment
		(start 77.193394 -146.68881)
		(end 76.443078 -147.439126)
		(width 0.127)
		(layer "B.Cu")
		(net "I2C_DEBUG_SCL")
	)
	(segment
		(start 77.87005 -145.095214)
		(end 77.193394 -145.77187)
		(width 0.127)
		(layer "B.Cu")
		(net "I2C_DEBUG_SCL")
	)
	(segment
		(start 80.095598 -135.02132)
		(end 80.095598 -138.758422)
		(width 0.127)
		(layer "B.Cu")
		(net "I2C_DEBUG_SCL")
	)
	(segment
		(start 68.348352 -123.771152)
		(end 68.348352 -125.295152)
		(width 0.127)
		(layer "B.Cu")
		(net "I2C_DEBUG_SCL")
	)
	(segment
		(start 74.578464 -129.504186)
		(end 80.095598 -135.02132)
		(width 0.127)
		(layer "B.Cu")
		(net "I2C_DEBUG_SCL")
	)
	(segment
		(start 73.80986 -129.504186)
		(end 74.578464 -129.504186)
		(width 0.127)
		(layer "B.Cu")
		(net "I2C_DEBUG_SCL")
	)
	(segment
		(start 74.384662 -147.483576)
		(end 73.86955 -147.483576)
		(width 0.127)
		(layer "B.Cu")
		(net "I2C_DEBUG_SCL")
	)
	(segment
		(start 73.647554 -147.26158)
		(end 73.224644 -147.26158)
		(width 0.127)
		(layer "B.Cu")
		(net "I2C_DEBUG_SCL")
	)
	(segment
		(start 68.348352 -125.295152)
		(end 70.14591 -127.09271)
		(width 0.127)
		(layer "B.Cu")
		(net "I2C_DEBUG_SCL")
	)
	(segment
		(start 80.095598 -138.758422)
		(end 79.249778 -139.604242)
		(width 0.127)
		(layer "B.Cu")
		(net "I2C_DEBUG_SCL")
	)
	(segment
		(start 74.429112 -147.439126)
		(end 74.384662 -147.483576)
		(width 0.127)
		(layer "B.Cu")
		(net "I2C_DEBUG_SCL")
	)
	(segment
		(start 70.487286 -127.09271)
		(end 72.898762 -129.504186)
		(width 0.127)
		(layer "B.Cu")
		(net "I2C_DEBUG_SCL")
	)
	(segment
		(start 79.249778 -142.545054)
		(end 77.87005 -143.924782)
		(width 0.127)
		(layer "B.Cu")
		(net "I2C_DEBUG_SCL")
	)
	(segment
		(start 77.193394 -145.77187)
		(end 77.193394 -146.68881)
		(width 0.127)
		(layer "B.Cu")
		(net "I2C_DEBUG_SCL")
	)
	(segment
		(start 67.98818 -123.41098)
		(end 68.348352 -123.771152)
		(width 0.127)
		(layer "B.Cu")
		(net "I2C_DEBUG_SCL")
	)
	(segment
		(start 77.87005 -143.924782)
		(end 77.87005 -145.095214)
		(width 0.127)
		(layer "B.Cu")
		(net "I2C_DEBUG_SCL")
	)
	(segment
		(start 70.14591 -127.09271)
		(end 70.487286 -127.09271)
		(width 0.127)
		(layer "B.Cu")
		(net "I2C_DEBUG_SCL")
	)
	(segment
		(start 79.249778 -139.604242)
		(end 79.249778 -142.545054)
		(width 0.127)
		(layer "B.Cu")
		(net "I2C_DEBUG_SCL")
	)
	(segment
		(start 76.443078 -147.439126)
		(end 75.512168 -147.439126)
		(width 0.127)
		(layer "B.Cu")
		(net "I2C_DEBUG_SCL")
	)
	(segment
		(start 75.512168 -147.439126)
		(end 74.429112 -147.439126)
		(width 0.127)
		(layer "B.Cu")
		(net "I2C_DEBUG_SCL")
	)
	(segment
		(start 72.898762 -129.504186)
		(end 73.80986 -129.504186)
		(width 0.127)
		(layer "B.Cu")
		(net "I2C_DEBUG_SCL")
	)
	(segment
		(start 70.734682 -114.8842)
		(end 68.49491 -117.123972)
		(width 0.127)
		(layer "In2.Cu")
		(net "I2C_DEBUG_SCL")
	)
	(segment
		(start 85.2043 -103.3907)
		(end 85.2043 -106.369612)
		(width 0.127)
		(layer "In2.Cu")
		(net "I2C_DEBUG_SCL")
	)
	(segment
		(start 78.238604 -109.7534)
		(end 73.107804 -114.8842)
		(width 0.127)
		(layer "In2.Cu")
		(net "I2C_DEBUG_SCL")
	)
	(segment
		(start 73.107804 -114.8842)
		(end 70.734682 -114.8842)
		(width 0.127)
		(layer "In2.Cu")
		(net "I2C_DEBUG_SCL")
	)
	(segment
		(start 78.238858 -109.7534)
		(end 78.238604 -109.7534)
		(width 0.127)
		(layer "In2.Cu")
		(net "I2C_DEBUG_SCL")
	)
	(segment
		(start 85.2043 -106.369612)
		(end 82.150712 -109.4232)
		(width 0.127)
		(layer "In2.Cu")
		(net "I2C_DEBUG_SCL")
	)
	(segment
		(start 68.49491 -120.580658)
		(end 67.655186 -121.420382)
		(width 0.127)
		(layer "In2.Cu")
		(net "I2C_DEBUG_SCL")
	)
	(segment
		(start 81.752186 -98.63201)
		(end 81.752186 -99.938586)
		(width 0.127)
		(layer "In2.Cu")
		(net "I2C_DEBUG_SCL")
	)
	(segment
		(start 81.752186 -99.938586)
		(end 85.2043 -103.3907)
		(width 0.127)
		(layer "In2.Cu")
		(net "I2C_DEBUG_SCL")
	)
	(segment
		(start 68.49491 -117.123972)
		(end 68.49491 -120.580658)
		(width 0.127)
		(layer "In2.Cu")
		(net "I2C_DEBUG_SCL")
	)
	(segment
		(start 82.150712 -109.4232)
		(end 78.569058 -109.4232)
		(width 0.127)
		(layer "In2.Cu")
		(net "I2C_DEBUG_SCL")
	)
	(segment
		(start 67.655186 -123.077986)
		(end 67.98818 -123.41098)
		(width 0.127)
		(layer "In2.Cu")
		(net "I2C_DEBUG_SCL")
	)
	(segment
		(start 67.655186 -121.420382)
		(end 67.655186 -123.077986)
		(width 0.127)
		(layer "In2.Cu")
		(net "I2C_DEBUG_SCL")
	)
	(segment
		(start 78.569058 -109.4232)
		(end 78.238858 -109.7534)
		(width 0.127)
		(layer "In2.Cu")
		(net "I2C_DEBUG_SCL")
	)
	(segment
		(start 79.8068 -92.799662)
		(end 79.8068 -96.723962)
		(width 0.127)
		(layer "In5.Cu")
		(net "I2C_DEBUG_SCL")
	)
	(segment
		(start 84.670392 -9.398762)
		(end 83.570572 -10.498582)
		(width 0.127)
		(layer "In5.Cu")
		(net "I2C_DEBUG_SCL")
	)
	(segment
		(start 79.8068 -96.723962)
		(end 81.349088 -98.26625)
		(width 0.127)
		(layer "In5.Cu")
		(net "I2C_DEBUG_SCL")
	)
	(segment
		(start 94.615 -11.303)
		(end 92.710762 -9.398762)
		(width 0.127)
		(layer "In5.Cu")
		(net "I2C_DEBUG_SCL")
	)
	(segment
		(start 80.01 -92.596462)
		(end 79.8068 -92.799662)
		(width 0.127)
		(layer "In5.Cu")
		(net "I2C_DEBUG_SCL")
	)
	(segment
		(start 79.5782 -43.967908)
		(end 79.5782 -57.413652)
		(width 0.127)
		(layer "In5.Cu")
		(net "I2C_DEBUG_SCL")
	)
	(segment
		(start 83.570572 -39.975536)
		(end 79.5782 -43.967908)
		(width 0.127)
		(layer "In5.Cu")
		(net "I2C_DEBUG_SCL")
	)
	(segment
		(start 79.5782 -57.413652)
		(end 80.01 -57.845452)
		(width 0.127)
		(layer "In5.Cu")
		(net "I2C_DEBUG_SCL")
	)
	(segment
		(start 83.570572 -10.498582)
		(end 83.570572 -39.975536)
		(width 0.127)
		(layer "In5.Cu")
		(net "I2C_DEBUG_SCL")
	)
	(segment
		(start 92.710762 -9.398762)
		(end 84.670392 -9.398762)
		(width 0.127)
		(layer "In5.Cu")
		(net "I2C_DEBUG_SCL")
	)
	(segment
		(start 81.349088 -98.26625)
		(end 81.386426 -98.26625)
		(width 0.127)
		(layer "In5.Cu")
		(net "I2C_DEBUG_SCL")
	)
	(segment
		(start 80.01 -57.845452)
		(end 80.01 -92.596462)
		(width 0.127)
		(layer "In5.Cu")
		(net "I2C_DEBUG_SCL")
	)
	(segment
		(start 81.386426 -98.26625)
		(end 81.752186 -98.63201)
		(width 0.127)
		(layer "In5.Cu")
		(net "I2C_DEBUG_SCL")
	)
	(segment
		(start 39.174928 -152.968198)
		(end 37.9476 -154.195526)
		(width 0.127)
		(layer "F.Cu")
		(net "FAN_PWM1_BMC")
	)
	(segment
		(start 36.900866 -156.79039)
		(end 37.404548 -156.286708)
		(width 0.127)
		(layer "F.Cu")
		(net "FAN_PWM1_BMC")
	)
	(segment
		(start 37.9476 -155.743656)
		(end 37.404548 -156.286708)
		(width 0.127)
		(layer "F.Cu")
		(net "FAN_PWM1_BMC")
	)
	(segment
		(start 41.1226 -152.968198)
		(end 39.174928 -152.968198)
		(width 0.127)
		(layer "F.Cu")
		(net "FAN_PWM1_BMC")
	)
	(segment
		(start 41.699942 -152.599898)
		(end 41.4909 -152.599898)
		(width 0.127)
		(layer "F.Cu")
		(net "FAN_PWM1_BMC")
	)
	(segment
		(start 36.900866 -157.25648)
		(end 36.900866 -156.79039)
		(width 0.127)
		(layer "F.Cu")
		(net "FAN_PWM1_BMC")
	)
	(segment
		(start 41.4909 -152.599898)
		(end 41.1226 -152.968198)
		(width 0.127)
		(layer "F.Cu")
		(net "FAN_PWM1_BMC")
	)
	(segment
		(start 37.9476 -154.195526)
		(end 37.9476 -155.743656)
		(width 0.127)
		(layer "F.Cu")
		(net "FAN_PWM1_BMC")
	)
	(via
		(at 37.404548 -156.286708)
		(size 0.6604)
		(drill 0.3302)
		(layers "F.Cu" "B.Cu")
		(net "FAN_PWM1_BMC")
	)
	(segment
		(start 41.268142 -153.346658)
		(end 41.557702 -153.057098)
		(width 0.127)
		(layer "F.Cu")
		(net "FAN_PWM0_BMC")
	)
	(segment
		(start 42.042842 -153.057098)
		(end 42.500042 -152.599898)
		(width 0.127)
		(layer "F.Cu")
		(net "FAN_PWM0_BMC")
	)
	(segment
		(start 41.268142 -153.552652)
		(end 41.268142 -153.346658)
		(width 0.127)
		(layer "F.Cu")
		(net "FAN_PWM0_BMC")
	)
	(segment
		(start 37.9476 -158.2801)
		(end 37.9476 -157.2514)
		(width 0.127)
		(layer "F.Cu")
		(net "FAN_PWM0_BMC")
	)
	(segment
		(start 38.0492 -157.1498)
		(end 38.4048 -156.7942)
		(width 0.127)
		(layer "F.Cu")
		(net "FAN_PWM0_BMC")
	)
	(segment
		(start 41.557702 -153.057098)
		(end 42.042842 -153.057098)
		(width 0.127)
		(layer "F.Cu")
		(net "FAN_PWM0_BMC")
	)
	(segment
		(start 38.989 -156.5656)
		(end 38.989 -155.831794)
		(width 0.127)
		(layer "F.Cu")
		(net "FAN_PWM0_BMC")
	)
	(segment
		(start 38.4048 -156.7942)
		(end 38.7604 -156.7942)
		(width 0.127)
		(layer "F.Cu")
		(net "FAN_PWM0_BMC")
	)
	(segment
		(start 38.989 -155.831794)
		(end 41.268142 -153.552652)
		(width 0.127)
		(layer "F.Cu")
		(net "FAN_PWM0_BMC")
	)
	(segment
		(start 37.9476 -157.2514)
		(end 38.0492 -157.1498)
		(width 0.127)
		(layer "F.Cu")
		(net "FAN_PWM0_BMC")
	)
	(segment
		(start 38.7604 -156.7942)
		(end 38.989 -156.5656)
		(width 0.127)
		(layer "F.Cu")
		(net "FAN_PWM0_BMC")
	)
	(via
		(at 38.0492 -157.1498)
		(size 0.6604)
		(drill 0.3302)
		(layers "F.Cu" "B.Cu")
		(net "FAN_PWM0_BMC")
	)
	(segment
		(start 55.299864 -137.40003)
		(end 55.566056 -137.40003)
		(width 0.127)
		(layer "F.Cu")
		(net "EXP_SPARE_1_R")
	)
	(segment
		(start 57.809384 -133.9088)
		(end 58.039 -133.9088)
		(width 0.127)
		(layer "F.Cu")
		(net "EXP_SPARE_1_R")
	)
	(segment
		(start 59.6646 -131.064)
		(end 59.8297 -131.2291)
		(width 0.127)
		(layer "F.Cu")
		(net "EXP_SPARE_1_R")
	)
	(segment
		(start 59.004454 -132.943346)
		(end 59.004454 -131.470146)
		(width 0.127)
		(layer "F.Cu")
		(net "EXP_SPARE_1_R")
	)
	(segment
		(start 56.3245 -136.96823)
		(end 57.2643 -136.02843)
		(width 0.127)
		(layer "F.Cu")
		(net "EXP_SPARE_1_R")
	)
	(segment
		(start 59.8297 -131.2291)
		(end 59.8297 -132.223002)
		(width 0.127)
		(layer "F.Cu")
		(net "EXP_SPARE_1_R")
	)
	(segment
		(start 57.2643 -136.02843)
		(end 57.2643 -134.453884)
		(width 0.127)
		(layer "F.Cu")
		(net "EXP_SPARE_1_R")
	)
	(segment
		(start 58.039 -133.9088)
		(end 59.004454 -132.943346)
		(width 0.127)
		(layer "F.Cu")
		(net "EXP_SPARE_1_R")
	)
	(segment
		(start 59.004454 -131.470146)
		(end 59.4106 -131.064)
		(width 0.127)
		(layer "F.Cu")
		(net "EXP_SPARE_1_R")
	)
	(segment
		(start 55.997856 -136.96823)
		(end 56.3245 -136.96823)
		(width 0.127)
		(layer "F.Cu")
		(net "EXP_SPARE_1_R")
	)
	(segment
		(start 59.4106 -131.064)
		(end 59.6646 -131.064)
		(width 0.127)
		(layer "F.Cu")
		(net "EXP_SPARE_1_R")
	)
	(segment
		(start 57.2643 -134.453884)
		(end 57.809384 -133.9088)
		(width 0.127)
		(layer "F.Cu")
		(net "EXP_SPARE_1_R")
	)
	(segment
		(start 55.566056 -137.40003)
		(end 55.997856 -136.96823)
		(width 0.127)
		(layer "F.Cu")
		(net "EXP_SPARE_1_R")
	)
	(via
		(at 59.4106 -131.064)
		(size 0.6604)
		(drill 0.3302)
		(layers "F.Cu" "B.Cu")
		(net "EXP_SPARE_1_R")
	)
	(segment
		(start 60.427362 -124.4092)
		(end 59.5757 -125.260862)
		(width 0.127)
		(layer "F.Cu")
		(net "EXP_SPARE_1")
	)
	(segment
		(start 60.285376 -130.414776)
		(end 60.7187 -130.8481)
		(width 0.127)
		(layer "F.Cu")
		(net "EXP_SPARE_1")
	)
	(segment
		(start 59.849004 -129.978404)
		(end 60.285376 -130.414776)
		(width 0.127)
		(layer "F.Cu")
		(net "EXP_SPARE_1")
	)
	(segment
		(start 59.5757 -128.261618)
		(end 59.849004 -128.534922)
		(width 0.127)
		(layer "F.Cu")
		(net "EXP_SPARE_1")
	)
	(segment
		(start 59.849004 -128.534922)
		(end 59.849004 -129.978404)
		(width 0.127)
		(layer "F.Cu")
		(net "EXP_SPARE_1")
	)
	(segment
		(start 60.7187 -130.8481)
		(end 60.7187 -132.223002)
		(width 0.127)
		(layer "F.Cu")
		(net "EXP_SPARE_1")
	)
	(segment
		(start 59.5757 -125.260862)
		(end 59.5757 -128.261618)
		(width 0.127)
		(layer "F.Cu")
		(net "EXP_SPARE_1")
	)
	(via
		(at 60.427362 -124.4092)
		(size 0.508)
		(drill 0.254)
		(layers "F.Cu" "B.Cu")
		(net "EXP_SPARE_1")
	)
	(via
		(at 100.317808 -123.2662)
		(size 0.508)
		(drill 0.254)
		(layers "F.Cu" "B.Cu")
		(net "EXP_SPARE_1")
	)
	(via
		(at 60.285376 -130.414776)
		(size 0.6604)
		(drill 0.3302)
		(layers "F.Cu" "B.Cu")
		(net "EXP_SPARE_1")
	)
	(segment
		(start 106.185462 -41.441878)
		(end 100.965 -46.66234)
		(width 0.127)
		(layer "In2.Cu")
		(net "EXP_SPARE_1")
	)
	(segment
		(start 100.965 -46.66234)
		(end 100.965 -122.619008)
		(width 0.127)
		(layer "In2.Cu")
		(net "EXP_SPARE_1")
	)
	(segment
		(start 107.33659 -31.528512)
		(end 106.863134 -31.528512)
		(width 0.127)
		(layer "In2.Cu")
		(net "EXP_SPARE_1")
	)
	(segment
		(start 100.965 -122.619008)
		(end 100.317808 -123.2662)
		(width 0.127)
		(layer "In2.Cu")
		(net "EXP_SPARE_1")
	)
	(segment
		(start 108.89996 -44.200064)
		(end 107.851448 -43.151552)
		(width 0.127)
		(layer "In2.Cu")
		(net "EXP_SPARE_1")
	)
	(segment
		(start 106.185462 -32.206184)
		(end 106.185462 -41.441878)
		(width 0.127)
		(layer "In2.Cu")
		(net "EXP_SPARE_1")
	)
	(segment
		(start 107.851448 -32.04337)
		(end 107.33659 -31.528512)
		(width 0.127)
		(layer "In2.Cu")
		(net "EXP_SPARE_1")
	)
	(segment
		(start 107.851448 -43.151552)
		(end 107.851448 -32.04337)
		(width 0.127)
		(layer "In2.Cu")
		(net "EXP_SPARE_1")
	)
	(segment
		(start 106.863134 -31.528512)
		(end 106.185462 -32.206184)
		(width 0.127)
		(layer "In2.Cu")
		(net "EXP_SPARE_1")
	)
	(segment
		(start 76.9112 -127.1524)
		(end 82.931 -127.1524)
		(width 0.127)
		(layer "In5.Cu")
		(net "EXP_SPARE_1")
	)
	(segment
		(start 60.427362 -124.4092)
		(end 69.236082 -124.4092)
		(width 0.127)
		(layer "In5.Cu")
		(net "EXP_SPARE_1")
	)
	(segment
		(start 85.0646 -125.0188)
		(end 85.927692 -125.0188)
		(width 0.127)
		(layer "In5.Cu")
		(net "EXP_SPARE_1")
	)
	(segment
		(start 74.7649 -125.0061)
		(end 76.9112 -127.1524)
		(width 0.127)
		(layer "In5.Cu")
		(net "EXP_SPARE_1")
	)
	(segment
		(start 98.830892 -123.2662)
		(end 100.317808 -123.2662)
		(width 0.127)
		(layer "In5.Cu")
		(net "EXP_SPARE_1")
	)
	(segment
		(start 69.236082 -124.4092)
		(end 69.832982 -125.0061)
		(width 0.127)
		(layer "In5.Cu")
		(net "EXP_SPARE_1")
	)
	(segment
		(start 89.05367 -121.914412)
		(end 97.479104 -121.914412)
		(width 0.127)
		(layer "In5.Cu")
		(net "EXP_SPARE_1")
	)
	(segment
		(start 69.832982 -125.0061)
		(end 74.7649 -125.0061)
		(width 0.127)
		(layer "In5.Cu")
		(net "EXP_SPARE_1")
	)
	(segment
		(start 86.000082 -124.968)
		(end 89.05367 -121.914412)
		(width 0.127)
		(layer "In5.Cu")
		(net "EXP_SPARE_1")
	)
	(segment
		(start 85.927692 -125.0188)
		(end 85.978492 -124.968)
		(width 0.127)
		(layer "In5.Cu")
		(net "EXP_SPARE_1")
	)
	(segment
		(start 82.931 -127.1524)
		(end 85.0646 -125.0188)
		(width 0.127)
		(layer "In5.Cu")
		(net "EXP_SPARE_1")
	)
	(segment
		(start 97.479104 -121.914412)
		(end 98.830892 -123.2662)
		(width 0.127)
		(layer "In5.Cu")
		(net "EXP_SPARE_1")
	)
	(segment
		(start 85.978492 -124.968)
		(end 86.000082 -124.968)
		(width 0.127)
		(layer "In5.Cu")
		(net "EXP_SPARE_1")
	)
	(segment
		(start 55.439564 -136.275572)
		(end 55.439564 -136.285986)
		(width 0.127)
		(layer "F.Cu")
		(net "EXP_SPARE_0_R")
	)
	(segment
		(start 55.299864 -136.425686)
		(end 55.299864 -136.59993)
		(width 0.127)
		(layer "F.Cu")
		(net "EXP_SPARE_0_R")
	)
	(segment
		(start 57.216548 -132.525008)
		(end 56.137556 -133.604)
		(width 0.127)
		(layer "F.Cu")
		(net "EXP_SPARE_0_R")
	)
	(segment
		(start 56.137556 -133.604)
		(end 56.137556 -135.57758)
		(width 0.127)
		(layer "F.Cu")
		(net "EXP_SPARE_0_R")
	)
	(segment
		(start 56.137556 -135.57758)
		(end 55.439564 -136.275572)
		(width 0.127)
		(layer "F.Cu")
		(net "EXP_SPARE_0_R")
	)
	(segment
		(start 57.216548 -131.73202)
		(end 57.216548 -132.525008)
		(width 0.127)
		(layer "F.Cu")
		(net "EXP_SPARE_0_R")
	)
	(segment
		(start 55.439564 -136.285986)
		(end 55.299864 -136.425686)
		(width 0.127)
		(layer "F.Cu")
		(net "EXP_SPARE_0_R")
	)
	(via
		(at 56.137556 -133.604)
		(size 0.6604)
		(drill 0.3302)
		(layers "F.Cu" "B.Cu")
		(net "EXP_SPARE_0_R")
	)
	(segment
		(start 58.547 -126.3142)
		(end 58.547 -124.6378)
		(width 0.127)
		(layer "F.Cu")
		(net "EXP_SPARE_0")
	)
	(segment
		(start 101.012752 -121.592848)
		(end 100.936552 -121.669048)
		(width 0.127)
		(layer "F.Cu")
		(net "EXP_SPARE_0")
	)
	(segment
		(start 105.62463 -27.864816)
		(end 105.283762 -28.205684)
		(width 0.127)
		(layer "F.Cu")
		(net "EXP_SPARE_0")
	)
	(segment
		(start 105.283762 -28.205684)
		(end 105.283762 -44.824142)
		(width 0.127)
		(layer "F.Cu")
		(net "EXP_SPARE_0")
	)
	(segment
		(start 105.283762 -44.824142)
		(end 102.7938 -47.314104)
		(width 0.127)
		(layer "F.Cu")
		(net "EXP_SPARE_0")
	)
	(segment
		(start 57.216548 -130.139948)
		(end 57.023 -129.9464)
		(width 0.127)
		(layer "F.Cu")
		(net "EXP_SPARE_0")
	)
	(segment
		(start 107.7722 -27.864816)
		(end 105.62463 -27.864816)
		(width 0.127)
		(layer "F.Cu")
		(net "EXP_SPARE_0")
	)
	(segment
		(start 108.89996 -42.800016)
		(end 107.94746 -41.847516)
		(width 0.127)
		(layer "F.Cu")
		(net "EXP_SPARE_0")
	)
	(segment
		(start 57.023 -127.8382)
		(end 58.547 -126.3142)
		(width 0.127)
		(layer "F.Cu")
		(net "EXP_SPARE_0")
	)
	(segment
		(start 57.023 -129.9464)
		(end 57.023 -127.8382)
		(width 0.127)
		(layer "F.Cu")
		(net "EXP_SPARE_0")
	)
	(segment
		(start 102.7938 -115.1382)
		(end 101.012752 -116.919248)
		(width 0.127)
		(layer "F.Cu")
		(net "EXP_SPARE_0")
	)
	(segment
		(start 101.012752 -116.919248)
		(end 101.012752 -121.592848)
		(width 0.127)
		(layer "F.Cu")
		(net "EXP_SPARE_0")
	)
	(segment
		(start 107.94746 -41.847516)
		(end 107.94746 -28.040076)
		(width 0.127)
		(layer "F.Cu")
		(net "EXP_SPARE_0")
	)
	(segment
		(start 58.547 -124.6378)
		(end 58.7756 -124.4092)
		(width 0.127)
		(layer "F.Cu")
		(net "EXP_SPARE_0")
	)
	(segment
		(start 100.936552 -121.669048)
		(end 100.2538 -122.3518)
		(width 0.127)
		(layer "F.Cu")
		(net "EXP_SPARE_0")
	)
	(segment
		(start 102.7938 -47.314104)
		(end 102.7938 -115.1382)
		(width 0.127)
		(layer "F.Cu")
		(net "EXP_SPARE_0")
	)
	(segment
		(start 57.216548 -130.84302)
		(end 57.216548 -130.139948)
		(width 0.127)
		(layer "F.Cu")
		(net "EXP_SPARE_0")
	)
	(segment
		(start 107.94746 -28.040076)
		(end 107.7722 -27.864816)
		(width 0.127)
		(layer "F.Cu")
		(net "EXP_SPARE_0")
	)
	(via
		(at 100.2538 -122.3518)
		(size 0.508)
		(drill 0.254)
		(layers "F.Cu" "B.Cu")
		(net "EXP_SPARE_0")
	)
	(via
		(at 100.936552 -121.669048)
		(size 0.6604)
		(drill 0.3302)
		(layers "F.Cu" "B.Cu")
		(net "EXP_SPARE_0")
	)
	(via
		(at 58.7756 -124.4092)
		(size 0.508)
		(drill 0.254)
		(layers "F.Cu" "B.Cu")
		(net "EXP_SPARE_0")
	)
	(segment
		(start 59.429904 -124.4092)
		(end 58.7756 -124.4092)
		(width 0.127)
		(layer "In5.Cu")
		(net "EXP_SPARE_0")
	)
	(segment
		(start 74.264774 -123.9393)
		(end 59.899804 -123.9393)
		(width 0.127)
		(layer "In5.Cu")
		(net "EXP_SPARE_0")
	)
	(segment
		(start 88.874092 -121.533412)
		(end 85.769704 -124.6378)
		(width 0.127)
		(layer "In5.Cu")
		(net "EXP_SPARE_0")
	)
	(segment
		(start 77.096874 -126.7714)
		(end 74.264774 -123.9393)
		(width 0.127)
		(layer "In5.Cu")
		(net "EXP_SPARE_0")
	)
	(segment
		(start 59.899804 -123.9393)
		(end 59.429904 -124.4092)
		(width 0.127)
		(layer "In5.Cu")
		(net "EXP_SPARE_0")
	)
	(segment
		(start 84.906612 -124.6378)
		(end 82.773012 -126.7714)
		(width 0.127)
		(layer "In5.Cu")
		(net "EXP_SPARE_0")
	)
	(segment
		(start 98.45548 -122.3518)
		(end 97.637092 -121.533412)
		(width 0.127)
		(layer "In5.Cu")
		(net "EXP_SPARE_0")
	)
	(segment
		(start 97.637092 -121.533412)
		(end 88.874092 -121.533412)
		(width 0.127)
		(layer "In5.Cu")
		(net "EXP_SPARE_0")
	)
	(segment
		(start 85.769704 -124.6378)
		(end 84.906612 -124.6378)
		(width 0.127)
		(layer "In5.Cu")
		(net "EXP_SPARE_0")
	)
	(segment
		(start 82.773012 -126.7714)
		(end 77.096874 -126.7714)
		(width 0.127)
		(layer "In5.Cu")
		(net "EXP_SPARE_0")
	)
	(segment
		(start 100.2538 -122.3518)
		(end 98.45548 -122.3518)
		(width 0.127)
		(layer "In5.Cu")
		(net "EXP_SPARE_0")
	)
	(segment
		(start 86.997794 -133.12775)
		(end 86.994238 -133.124194)
		(width 0.127)
		(layer "F.Cu")
		(net "EEPROM_A2")
	)
	(segment
		(start 90.235024 -134.081774)
		(end 89.281 -133.12775)
		(width 0.127)
		(layer "F.Cu")
		(net "EEPROM_A2")
	)
	(segment
		(start 88.092026 -133.12775)
		(end 86.997794 -133.12775)
		(width 0.127)
		(layer "F.Cu")
		(net "EEPROM_A2")
	)
	(segment
		(start 89.281 -133.12775)
		(end 88.092026 -133.12775)
		(width 0.127)
		(layer "F.Cu")
		(net "EEPROM_A2")
	)
	(segment
		(start 91.208352 -134.081774)
		(end 90.235024 -134.081774)
		(width 0.127)
		(layer "F.Cu")
		(net "EEPROM_A2")
	)
	(via
		(at 89.281 -133.12775)
		(size 0.6604)
		(drill 0.3302)
		(layers "F.Cu" "B.Cu")
		(net "EEPROM_A2")
	)
	(segment
		(start 88.004142 -135.1153)
		(end 89.0016 -135.1153)
		(width 0.127)
		(layer "F.Cu")
		(net "EEPROM_A1")
	)
	(segment
		(start 86.671404 -134.228586)
		(end 87.117428 -134.228586)
		(width 0.127)
		(layer "F.Cu")
		(net "EEPROM_A1")
	)
	(segment
		(start 87.849456 -134.960614)
		(end 88.004142 -135.1153)
		(width 0.127)
		(layer "F.Cu")
		(net "EEPROM_A1")
	)
	(segment
		(start 87.117428 -134.228586)
		(end 87.849456 -134.960614)
		(width 0.127)
		(layer "F.Cu")
		(net "EEPROM_A1")
	)
	(segment
		(start 89.238074 -135.351774)
		(end 91.208352 -135.351774)
		(width 0.127)
		(layer "F.Cu")
		(net "EEPROM_A1")
	)
	(segment
		(start 89.0016 -135.1153)
		(end 89.238074 -135.351774)
		(width 0.127)
		(layer "F.Cu")
		(net "EEPROM_A1")
	)
	(via
		(at 87.849456 -134.960614)
		(size 0.6604)
		(drill 0.3302)
		(layers "F.Cu" "B.Cu")
		(net "EEPROM_A1")
	)
	(segment
		(start 87.6427 -137.0838)
		(end 87.6554 -137.0711)
		(width 0.127)
		(layer "F.Cu")
		(net "EEPROM_A0")
	)
	(segment
		(start 90.212418 -136.621774)
		(end 90.087958 -136.746234)
		(width 0.127)
		(layer "F.Cu")
		(net "EEPROM_A0")
	)
	(segment
		(start 88.983566 -136.746234)
		(end 88.7984 -136.9314)
		(width 0.127)
		(layer "F.Cu")
		(net "EEPROM_A0")
	)
	(segment
		(start 87.6427 -138.1252)
		(end 87.6427 -137.0838)
		(width 0.127)
		(layer "F.Cu")
		(net "EEPROM_A0")
	)
	(segment
		(start 91.208352 -136.621774)
		(end 90.212418 -136.621774)
		(width 0.127)
		(layer "F.Cu")
		(net "EEPROM_A0")
	)
	(segment
		(start 88.7984 -136.9314)
		(end 88.6587 -137.0711)
		(width 0.127)
		(layer "F.Cu")
		(net "EEPROM_A0")
	)
	(segment
		(start 90.087958 -136.746234)
		(end 88.983566 -136.746234)
		(width 0.127)
		(layer "F.Cu")
		(net "EEPROM_A0")
	)
	(segment
		(start 88.6587 -137.0711)
		(end 87.6554 -137.0711)
		(width 0.127)
		(layer "F.Cu")
		(net "EEPROM_A0")
	)
	(via
		(at 88.7984 -136.9314)
		(size 0.6604)
		(drill 0.3302)
		(layers "F.Cu" "B.Cu")
		(net "EEPROM_A0")
	)
	(segment
		(start 98.044 -123.3678)
		(end 98.044 -127.331724)
		(width 0.127)
		(layer "F.Cu")
		(net "DPB_MISC_ALERT")
	)
	(segment
		(start 98.044 -120.824752)
		(end 98.044 -123.3678)
		(width 0.127)
		(layer "F.Cu")
		(net "DPB_MISC_ALERT")
	)
	(segment
		(start 91.596718 -172.0596)
		(end 90.590878 -173.06544)
		(width 0.127)
		(layer "F.Cu")
		(net "DPB_MISC_ALERT")
	)
	(segment
		(start 101.959664 -135.433562)
		(end 101.959664 -168.973754)
		(width 0.127)
		(layer "F.Cu")
		(net "DPB_MISC_ALERT")
	)
	(segment
		(start 100.0252 -130.735578)
		(end 100.0252 -133.499098)
		(width 0.127)
		(layer "F.Cu")
		(net "DPB_MISC_ALERT")
	)
	(segment
		(start 98.7552 -128.042924)
		(end 98.7552 -129.465578)
		(width 0.127)
		(layer "F.Cu")
		(net "DPB_MISC_ALERT")
	)
	(segment
		(start 92.7608 -172.0596)
		(end 91.596718 -172.0596)
		(width 0.127)
		(layer "F.Cu")
		(net "DPB_MISC_ALERT")
	)
	(segment
		(start 98.679 -120.189752)
		(end 98.044 -120.824752)
		(width 0.127)
		(layer "F.Cu")
		(net "DPB_MISC_ALERT")
	)
	(segment
		(start 98.044 -127.331724)
		(end 98.7552 -128.042924)
		(width 0.127)
		(layer "F.Cu")
		(net "DPB_MISC_ALERT")
	)
	(segment
		(start 98.679 -118.7069)
		(end 98.679 -120.189752)
		(width 0.127)
		(layer "F.Cu")
		(net "DPB_MISC_ALERT")
	)
	(segment
		(start 98.5393 -118.5672)
		(end 98.679 -118.7069)
		(width 0.127)
		(layer "F.Cu")
		(net "DPB_MISC_ALERT")
	)
	(segment
		(start 94.1324 -170.688)
		(end 92.7608 -172.0596)
		(width 0.127)
		(layer "F.Cu")
		(net "DPB_MISC_ALERT")
	)
	(segment
		(start 98.7552 -129.465578)
		(end 100.0252 -130.735578)
		(width 0.127)
		(layer "F.Cu")
		(net "DPB_MISC_ALERT")
	)
	(segment
		(start 101.959664 -168.973754)
		(end 100.245418 -170.688)
		(width 0.127)
		(layer "F.Cu")
		(net "DPB_MISC_ALERT")
	)
	(segment
		(start 90.590878 -173.06544)
		(end 89.4334 -173.06544)
		(width 0.127)
		(layer "F.Cu")
		(net "DPB_MISC_ALERT")
	)
	(segment
		(start 100.0252 -133.499098)
		(end 101.959664 -135.433562)
		(width 0.127)
		(layer "F.Cu")
		(net "DPB_MISC_ALERT")
	)
	(segment
		(start 100.245418 -170.688)
		(end 94.1324 -170.688)
		(width 0.127)
		(layer "F.Cu")
		(net "DPB_MISC_ALERT")
	)
	(via
		(at 98.5393 -118.5672)
		(size 0.508)
		(drill 0.254)
		(layers "F.Cu" "B.Cu")
		(net "DPB_MISC_ALERT")
	)
	(via
		(at 98.044 -123.3678)
		(size 0.6604)
		(drill 0.3302)
		(layers "F.Cu" "B.Cu")
		(net "DPB_MISC_ALERT")
	)
	(segment
		(start 97.79 -116.713)
		(end 97.79 -83.032346)
		(width 0.127)
		(layer "In2.Cu")
		(net "DPB_MISC_ALERT")
	)
	(segment
		(start 117.306344 -41.593516)
		(end 116.099844 -42.800016)
		(width 0.127)
		(layer "In2.Cu")
		(net "DPB_MISC_ALERT")
	)
	(segment
		(start 97.79 -83.032346)
		(end 96.662494 -81.90484)
		(width 0.127)
		(layer "In2.Cu")
		(net "DPB_MISC_ALERT")
	)
	(segment
		(start 98.5393 -118.5672)
		(end 98.5393 -117.4623)
		(width 0.127)
		(layer "In2.Cu")
		(net "DPB_MISC_ALERT")
	)
	(segment
		(start 97.155 -37.512752)
		(end 99.62007 -35.047682)
		(width 0.127)
		(layer "In2.Cu")
		(net "DPB_MISC_ALERT")
	)
	(segment
		(start 96.662494 -66.303906)
		(end 97.155 -65.8114)
		(width 0.127)
		(layer "In2.Cu")
		(net "DPB_MISC_ALERT")
	)
	(segment
		(start 98.5393 -117.4623)
		(end 97.79 -116.713)
		(width 0.127)
		(layer "In2.Cu")
		(net "DPB_MISC_ALERT")
	)
	(segment
		(start 99.62007 -30.328362)
		(end 104.826816 -25.121616)
		(width 0.127)
		(layer "In2.Cu")
		(net "DPB_MISC_ALERT")
	)
	(segment
		(start 117.306344 -28.837382)
		(end 117.306344 -41.593516)
		(width 0.127)
		(layer "In2.Cu")
		(net "DPB_MISC_ALERT")
	)
	(segment
		(start 96.662494 -81.90484)
		(end 96.662494 -66.303906)
		(width 0.127)
		(layer "In2.Cu")
		(net "DPB_MISC_ALERT")
	)
	(segment
		(start 104.826816 -25.121616)
		(end 113.590578 -25.121616)
		(width 0.127)
		(layer "In2.Cu")
		(net "DPB_MISC_ALERT")
	)
	(segment
		(start 113.590578 -25.121616)
		(end 117.306344 -28.837382)
		(width 0.127)
		(layer "In2.Cu")
		(net "DPB_MISC_ALERT")
	)
	(segment
		(start 97.155 -65.8114)
		(end 97.155 -37.512752)
		(width 0.127)
		(layer "In2.Cu")
		(net "DPB_MISC_ALERT")
	)
	(segment
		(start 99.62007 -35.047682)
		(end 99.62007 -30.328362)
		(width 0.127)
		(layer "In2.Cu")
		(net "DPB_MISC_ALERT")
	)
	(segment
		(start 95.996506 -143.629126)
		(end 95.214186 -143.629126)
		(width 0.127)
		(layer "F.Cu")
		(net "DEBUG_HDR_UART_SEL")
	)
	(segment
		(start 95.214186 -143.629126)
		(end 92.324936 -140.739876)
		(width 0.127)
		(layer "F.Cu")
		(net "DEBUG_HDR_UART_SEL")
	)
	(segment
		(start 92.324936 -140.739876)
		(end 92.145104 -140.739876)
		(width 0.127)
		(layer "F.Cu")
		(net "DEBUG_HDR_UART_SEL")
	)
	(segment
		(start 83.1342 -135.001)
		(end 83.1342 -137.1854)
		(width 0.127)
		(layer "F.Cu")
		(net "DEBUG_HDR_UART_SEL")
	)
	(segment
		(start 79.987394 -133.918706)
		(end 80.2767 -133.6294)
		(width 0.127)
		(layer "F.Cu")
		(net "DEBUG_HDR_UART_SEL")
	)
	(segment
		(start 81.7118 -134.1247)
		(end 80.772 -134.1247)
		(width 0.127)
		(layer "F.Cu")
		(net "DEBUG_HDR_UART_SEL")
	)
	(segment
		(start 82.2325 -133.604)
		(end 81.7118 -134.1247)
		(width 0.127)
		(layer "F.Cu")
		(net "DEBUG_HDR_UART_SEL")
	)
	(segment
		(start 82.2325 -134.0993)
		(end 83.1342 -135.001)
		(width 0.127)
		(layer "F.Cu")
		(net "DEBUG_HDR_UART_SEL")
	)
	(segment
		(start 92.145104 -140.739876)
		(end 92.01912 -140.86586)
		(width 0.127)
		(layer "F.Cu")
		(net "DEBUG_HDR_UART_SEL")
	)
	(segment
		(start 82.2325 -133.604)
		(end 82.2325 -134.0993)
		(width 0.127)
		(layer "F.Cu")
		(net "DEBUG_HDR_UART_SEL")
	)
	(segment
		(start 78.084426 -133.918706)
		(end 79.987394 -133.918706)
		(width 0.127)
		(layer "F.Cu")
		(net "DEBUG_HDR_UART_SEL")
	)
	(segment
		(start 80.772 -134.1247)
		(end 80.2767 -133.6294)
		(width 0.127)
		(layer "F.Cu")
		(net "DEBUG_HDR_UART_SEL")
	)
	(via
		(at 90.774266 -140.339572)
		(size 0.6096)
		(drill 0.3048)
		(layers "F.Cu" "B.Cu")
		(net "DEBUG_HDR_UART_SEL")
	)
	(via
		(at 92.01912 -140.86586)
		(size 0.508)
		(drill 0.254)
		(layers "F.Cu" "B.Cu")
		(net "DEBUG_HDR_UART_SEL")
	)
	(via
		(at 83.1342 -137.1854)
		(size 0.508)
		(drill 0.254)
		(layers "F.Cu" "B.Cu")
		(net "DEBUG_HDR_UART_SEL")
	)
	(segment
		(start 92.01912 -140.86586)
		(end 91.95816 -140.8049)
		(width 0.127)
		(layer "B.Cu")
		(net "DEBUG_HDR_UART_SEL")
	)
	(segment
		(start 90.96248 -139.104116)
		(end 90.96248 -139.509246)
		(width 0.127)
		(layer "B.Cu")
		(net "DEBUG_HDR_UART_SEL")
	)
	(segment
		(start 90.774266 -139.69746)
		(end 90.774266 -140.339572)
		(width 0.127)
		(layer "B.Cu")
		(net "DEBUG_HDR_UART_SEL")
	)
	(segment
		(start 90.901266 -140.8049)
		(end 90.774266 -140.6779)
		(width 0.127)
		(layer "B.Cu")
		(net "DEBUG_HDR_UART_SEL")
	)
	(segment
		(start 90.96248 -139.509246)
		(end 90.774266 -139.69746)
		(width 0.127)
		(layer "B.Cu")
		(net "DEBUG_HDR_UART_SEL")
	)
	(segment
		(start 91.95816 -140.8049)
		(end 90.901266 -140.8049)
		(width 0.127)
		(layer "B.Cu")
		(net "DEBUG_HDR_UART_SEL")
	)
	(segment
		(start 90.774266 -140.6779)
		(end 90.774266 -140.339572)
		(width 0.127)
		(layer "B.Cu")
		(net "DEBUG_HDR_UART_SEL")
	)
	(segment
		(start 91.92768 -140.77442)
		(end 92.01912 -140.86586)
		(width 0.127)
		(layer "In5.Cu")
		(net "DEBUG_HDR_UART_SEL")
	)
	(segment
		(start 87.331296 -138.97991)
		(end 87.33155 -138.979656)
		(width 0.127)
		(layer "In5.Cu")
		(net "DEBUG_HDR_UART_SEL")
	)
	(segment
		(start 90.600022 -140.77442)
		(end 91.92768 -140.77442)
		(width 0.127)
		(layer "In5.Cu")
		(net "DEBUG_HDR_UART_SEL")
	)
	(segment
		(start 83.45551 -137.50671)
		(end 84.674964 -137.50671)
		(width 0.127)
		(layer "In5.Cu")
		(net "DEBUG_HDR_UART_SEL")
	)
	(segment
		(start 88.805258 -138.979656)
		(end 90.600022 -140.77442)
		(width 0.127)
		(layer "In5.Cu")
		(net "DEBUG_HDR_UART_SEL")
	)
	(segment
		(start 87.33155 -138.979656)
		(end 88.805258 -138.979656)
		(width 0.127)
		(layer "In5.Cu")
		(net "DEBUG_HDR_UART_SEL")
	)
	(segment
		(start 84.674964 -137.50671)
		(end 86.148164 -138.97991)
		(width 0.127)
		(layer "In5.Cu")
		(net "DEBUG_HDR_UART_SEL")
	)
	(segment
		(start 86.148164 -138.97991)
		(end 87.331296 -138.97991)
		(width 0.127)
		(layer "In5.Cu")
		(net "DEBUG_HDR_UART_SEL")
	)
	(segment
		(start 83.1342 -137.1854)
		(end 83.45551 -137.50671)
		(width 0.127)
		(layer "In5.Cu")
		(net "DEBUG_HDR_UART_SEL")
	)
	(segment
		(start 15.222474 -135.478266)
		(end 15.432786 -135.478266)
		(width 0.127)
		(layer "F.Cu")
		(net "DDR4_RST_N")
	)
	(segment
		(start 15.432786 -135.478266)
		(end 15.58163 -135.62711)
		(width 0.127)
		(layer "F.Cu")
		(net "DDR4_RST_N")
	)
	(segment
		(start 35.153854 -137.97534)
		(end 33.922716 -136.744202)
		(width 0.127)
		(layer "F.Cu")
		(net "DDR4_RST_N")
	)
	(segment
		(start 10.352024 -136.715246)
		(end 10.352024 -136.197594)
		(width 0.127)
		(layer "F.Cu")
		(net "DDR4_RST_N")
	)
	(segment
		(start 15.07363 -135.62711)
		(end 15.222474 -135.478266)
		(width 0.127)
		(layer "F.Cu")
		(net "DDR4_RST_N")
	)
	(segment
		(start 16.747998 -138.248136)
		(end 16.834612 -138.161522)
		(width 0.127)
		(layer "F.Cu")
		(net "DDR4_RST_N")
	)
	(segment
		(start 15.923768 -137.116312)
		(end 15.923768 -137.994136)
		(width 0.127)
		(layer "F.Cu")
		(net "DDR4_RST_N")
	)
	(segment
		(start 39.299896 -140.599922)
		(end 37.044122 -140.599922)
		(width 0.127)
		(layer "F.Cu")
		(net "DDR4_RST_N")
	)
	(segment
		(start 9.323832 -136.716516)
		(end 10.350754 -136.716516)
		(width 0.127)
		(layer "F.Cu")
		(net "DDR4_RST_N")
	)
	(segment
		(start 17.234662 -137.761472)
		(end 16.834612 -138.161522)
		(width 0.127)
		(layer "F.Cu")
		(net "DDR4_RST_N")
	)
	(segment
		(start 10.350754 -136.716516)
		(end 10.352024 -136.715246)
		(width 0.127)
		(layer "F.Cu")
		(net "DDR4_RST_N")
	)
	(segment
		(start 15.58163 -136.774174)
		(end 15.923768 -137.116312)
		(width 0.127)
		(layer "F.Cu")
		(net "DDR4_RST_N")
	)
	(segment
		(start 14.714474 -136.72058)
		(end 14.924786 -136.72058)
		(width 0.127)
		(layer "F.Cu")
		(net "DDR4_RST_N")
	)
	(segment
		(start 16.177768 -138.248136)
		(end 16.747998 -138.248136)
		(width 0.127)
		(layer "F.Cu")
		(net "DDR4_RST_N")
	)
	(segment
		(start 15.07363 -136.571736)
		(end 15.07363 -135.62711)
		(width 0.127)
		(layer "F.Cu")
		(net "DDR4_RST_N")
	)
	(segment
		(start 10.352024 -136.197594)
		(end 10.532872 -136.016746)
		(width 0.127)
		(layer "F.Cu")
		(net "DDR4_RST_N")
	)
	(segment
		(start 10.532872 -136.016746)
		(end 14.27734 -136.016746)
		(width 0.127)
		(layer "F.Cu")
		(net "DDR4_RST_N")
	)
	(segment
		(start 37.044122 -140.599922)
		(end 35.153854 -138.709654)
		(width 0.127)
		(layer "F.Cu")
		(net "DDR4_RST_N")
	)
	(segment
		(start 14.27734 -136.016746)
		(end 14.56563 -136.305036)
		(width 0.127)
		(layer "F.Cu")
		(net "DDR4_RST_N")
	)
	(segment
		(start 15.58163 -135.62711)
		(end 15.58163 -136.774174)
		(width 0.127)
		(layer "F.Cu")
		(net "DDR4_RST_N")
	)
	(segment
		(start 15.923768 -137.994136)
		(end 16.177768 -138.248136)
		(width 0.127)
		(layer "F.Cu")
		(net "DDR4_RST_N")
	)
	(segment
		(start 33.922716 -136.744202)
		(end 33.922716 -136.492996)
		(width 0.127)
		(layer "F.Cu")
		(net "DDR4_RST_N")
	)
	(segment
		(start 35.153854 -138.709654)
		(end 35.153854 -137.97534)
		(width 0.127)
		(layer "F.Cu")
		(net "DDR4_RST_N")
	)
	(segment
		(start 14.924786 -136.72058)
		(end 15.07363 -136.571736)
		(width 0.127)
		(layer "F.Cu")
		(net "DDR4_RST_N")
	)
	(segment
		(start 14.56563 -136.305036)
		(end 14.56563 -136.571736)
		(width 0.127)
		(layer "F.Cu")
		(net "DDR4_RST_N")
	)
	(segment
		(start 14.56563 -136.571736)
		(end 14.714474 -136.72058)
		(width 0.127)
		(layer "F.Cu")
		(net "DDR4_RST_N")
	)
	(via
		(at 33.922716 -136.492996)
		(size 0.508)
		(drill 0.254)
		(layers "F.Cu" "B.Cu")
		(net "DDR4_RST_N")
	)
	(via
		(at 17.234662 -137.761472)
		(size 0.508)
		(drill 0.254)
		(layers "F.Cu" "B.Cu")
		(net "DDR4_RST_N")
	)
	(segment
		(start 32.544258 -135.763)
		(end 31.8897 -135.763)
		(width 0.127)
		(layer "In5.Cu")
		(net "DDR4_RST_N")
	)
	(segment
		(start 31.7627 -135.89)
		(end 31.7627 -136.357106)
		(width 0.127)
		(layer "In5.Cu")
		(net "DDR4_RST_N")
	)
	(segment
		(start 28.190698 -134.232396)
		(end 21.311108 -134.232396)
		(width 0.127)
		(layer "In5.Cu")
		(net "DDR4_RST_N")
	)
	(segment
		(start 18.98904 -136.554464)
		(end 18.292572 -136.554464)
		(width 0.127)
		(layer "In5.Cu")
		(net "DDR4_RST_N")
	)
	(segment
		(start 32.671258 -135.89)
		(end 32.544258 -135.763)
		(width 0.127)
		(layer "In5.Cu")
		(net "DDR4_RST_N")
	)
	(segment
		(start 34.31286 -136.283446)
		(end 34.31286 -135.89762)
		(width 0.127)
		(layer "In5.Cu")
		(net "DDR4_RST_N")
	)
	(segment
		(start 34.10331 -136.492996)
		(end 34.31286 -136.283446)
		(width 0.127)
		(layer "In5.Cu")
		(net "DDR4_RST_N")
	)
	(segment
		(start 29.721302 -135.763)
		(end 28.190698 -134.232396)
		(width 0.127)
		(layer "In5.Cu")
		(net "DDR4_RST_N")
	)
	(segment
		(start 17.714722 -136.615678)
		(end 17.634458 -136.695942)
		(width 0.0889)
		(layer "In5.Cu")
		(net "DDR4_RST_N")
	)
	(segment
		(start 18.280634 -136.542526)
		(end 17.787874 -136.542526)
		(width 0.127)
		(layer "In5.Cu")
		(net "DDR4_RST_N")
	)
	(segment
		(start 33.179258 -135.89)
		(end 33.179258 -136.44626)
		(width 0.127)
		(layer "In5.Cu")
		(net "DDR4_RST_N")
	)
	(segment
		(start 32.671258 -136.44626)
		(end 32.671258 -135.89)
		(width 0.127)
		(layer "In5.Cu")
		(net "DDR4_RST_N")
	)
	(segment
		(start 31.8897 -135.763)
		(end 31.7627 -135.89)
		(width 0.127)
		(layer "In5.Cu")
		(net "DDR4_RST_N")
	)
	(segment
		(start 34.31286 -135.89762)
		(end 34.17824 -135.763)
		(width 0.127)
		(layer "In5.Cu")
		(net "DDR4_RST_N")
	)
	(segment
		(start 17.634458 -136.695942)
		(end 17.634458 -137.361676)
		(width 0.0889)
		(layer "In5.Cu")
		(net "DDR4_RST_N")
	)
	(segment
		(start 21.311108 -134.232396)
		(end 18.98904 -136.554464)
		(width 0.127)
		(layer "In5.Cu")
		(net "DDR4_RST_N")
	)
	(segment
		(start 17.634458 -137.361676)
		(end 17.234662 -137.761472)
		(width 0.0889)
		(layer "In5.Cu")
		(net "DDR4_RST_N")
	)
	(segment
		(start 30.5816 -135.763)
		(end 29.721302 -135.763)
		(width 0.127)
		(layer "In5.Cu")
		(net "DDR4_RST_N")
	)
	(segment
		(start 34.17824 -135.763)
		(end 33.306258 -135.763)
		(width 0.127)
		(layer "In5.Cu")
		(net "DDR4_RST_N")
	)
	(segment
		(start 33.052258 -136.57326)
		(end 32.798258 -136.57326)
		(width 0.127)
		(layer "In5.Cu")
		(net "DDR4_RST_N")
	)
	(segment
		(start 32.798258 -136.57326)
		(end 32.671258 -136.44626)
		(width 0.127)
		(layer "In5.Cu")
		(net "DDR4_RST_N")
	)
	(segment
		(start 31.7627 -136.357106)
		(end 31.62681 -136.492996)
		(width 0.127)
		(layer "In5.Cu")
		(net "DDR4_RST_N")
	)
	(segment
		(start 31.311596 -136.492996)
		(end 30.5816 -135.763)
		(width 0.127)
		(layer "In5.Cu")
		(net "DDR4_RST_N")
	)
	(segment
		(start 33.922716 -136.492996)
		(end 34.10331 -136.492996)
		(width 0.127)
		(layer "In5.Cu")
		(net "DDR4_RST_N")
	)
	(segment
		(start 33.179258 -136.44626)
		(end 33.052258 -136.57326)
		(width 0.127)
		(layer "In5.Cu")
		(net "DDR4_RST_N")
	)
	(segment
		(start 31.62681 -136.492996)
		(end 31.311596 -136.492996)
		(width 0.127)
		(layer "In5.Cu")
		(net "DDR4_RST_N")
	)
	(segment
		(start 18.292572 -136.554464)
		(end 18.280634 -136.542526)
		(width 0.127)
		(layer "In5.Cu")
		(net "DDR4_RST_N")
	)
	(segment
		(start 33.306258 -135.763)
		(end 33.179258 -135.89)
		(width 0.127)
		(layer "In5.Cu")
		(net "DDR4_RST_N")
	)
	(segment
		(start 17.787874 -136.542526)
		(end 17.714722 -136.615678)
		(width 0.127)
		(layer "In5.Cu")
		(net "DDR4_RST_N")
	)
	(segment
		(start 22.011386 -130.562858)
		(end 22.011386 -129.556256)
		(width 0.127)
		(layer "F.Cu")
		(net "DDR4_ALERT")
	)
	(segment
		(start 23.234396 -138.161522)
		(end 23.32228 -138.161522)
		(width 0.127)
		(layer "F.Cu")
		(net "DDR4_ALERT")
	)
	(segment
		(start 25.174194 -134.796022)
		(end 24.139144 -133.760972)
		(width 0.127)
		(layer "F.Cu")
		(net "DDR4_ALERT")
	)
	(segment
		(start 22.030944 -130.5433)
		(end 22.011386 -130.562858)
		(width 0.127)
		(layer "F.Cu")
		(net "DDR4_ALERT")
	)
	(segment
		(start 42.900092 -141.000226)
		(end 43.299888 -141.399768)
		(width 0.127)
		(layer "F.Cu")
		(net "DDR4_ALERT")
	)
	(segment
		(start 43.299888 -141.399768)
		(end 43.299888 -141.400022)
		(width 0.127)
		(layer "F.Cu")
		(net "DDR4_ALERT")
	)
	(segment
		(start 24.139144 -130.859784)
		(end 23.82266 -130.5433)
		(width 0.127)
		(layer "F.Cu")
		(net "DDR4_ALERT")
	)
	(segment
		(start 23.368 -130.5433)
		(end 22.030944 -130.5433)
		(width 0.127)
		(layer "F.Cu")
		(net "DDR4_ALERT")
	)
	(segment
		(start 23.32228 -138.161522)
		(end 23.810976 -137.672826)
		(width 0.127)
		(layer "F.Cu")
		(net "DDR4_ALERT")
	)
	(segment
		(start 24.139144 -133.760972)
		(end 24.139144 -130.859784)
		(width 0.127)
		(layer "F.Cu")
		(net "DDR4_ALERT")
	)
	(segment
		(start 25.174194 -136.957054)
		(end 25.174194 -134.796022)
		(width 0.127)
		(layer "F.Cu")
		(net "DDR4_ALERT")
	)
	(segment
		(start 24.458422 -137.672826)
		(end 25.174194 -136.957054)
		(width 0.127)
		(layer "F.Cu")
		(net "DDR4_ALERT")
	)
	(segment
		(start 23.810976 -137.672826)
		(end 24.458422 -137.672826)
		(width 0.127)
		(layer "F.Cu")
		(net "DDR4_ALERT")
	)
	(segment
		(start 23.82266 -130.5433)
		(end 23.368 -130.5433)
		(width 0.127)
		(layer "F.Cu")
		(net "DDR4_ALERT")
	)
	(segment
		(start 22.011386 -129.556256)
		(end 22.014942 -129.5527)
		(width 0.127)
		(layer "F.Cu")
		(net "DDR4_ALERT")
	)
	(via
		(at 42.900092 -141.000226)
		(size 0.4572)
		(drill 0.2032)
		(layers "F.Cu" "B.Cu")
		(net "DDR4_ALERT")
	)
	(via
		(at 23.810976 -137.672826)
		(size 0.508)
		(drill 0.254)
		(layers "F.Cu" "B.Cu")
		(net "DDR4_ALERT")
	)
	(segment
		(start 40.257984 -141.393672)
		(end 42.506646 -141.393672)
		(width 0.127)
		(layer "In2.Cu")
		(net "DDR4_ALERT")
	)
	(segment
		(start 31.0896 -137.99312)
		(end 31.27502 -137.8077)
		(width 0.127)
		(layer "In2.Cu")
		(net "DDR4_ALERT")
	)
	(segment
		(start 35.790124 -138.80084)
		(end 35.917124 -138.67384)
		(width 0.127)
		(layer "In2.Cu")
		(net "DDR4_ALERT")
	)
	(segment
		(start 36.044124 -137.7315)
		(end 36.595812 -137.7315)
		(width 0.127)
		(layer "In2.Cu")
		(net "DDR4_ALERT")
	)
	(segment
		(start 35.536124 -138.80084)
		(end 35.790124 -138.80084)
		(width 0.127)
		(layer "In2.Cu")
		(net "DDR4_ALERT")
	)
	(segment
		(start 33.504124 -138.52652)
		(end 33.758124 -138.52652)
		(width 0.127)
		(layer "In2.Cu")
		(net "DDR4_ALERT")
	)
	(segment
		(start 33.885124 -137.8585)
		(end 34.012124 -137.7315)
		(width 0.127)
		(layer "In2.Cu")
		(net "DDR4_ALERT")
	)
	(segment
		(start 31.0896 -139.91844)
		(end 31.0896 -137.99312)
		(width 0.127)
		(layer "In2.Cu")
		(net "DDR4_ALERT")
	)
	(segment
		(start 34.901124 -137.8585)
		(end 35.028124 -137.7315)
		(width 0.127)
		(layer "In2.Cu")
		(net "DDR4_ALERT")
	)
	(segment
		(start 34.266124 -137.7315)
		(end 34.393124 -137.8585)
		(width 0.127)
		(layer "In2.Cu")
		(net "DDR4_ALERT")
	)
	(segment
		(start 32.129222 -137.39114)
		(end 32.604456 -137.39114)
		(width 0.127)
		(layer "In2.Cu")
		(net "DDR4_ALERT")
	)
	(segment
		(start 35.409124 -138.67384)
		(end 35.536124 -138.80084)
		(width 0.127)
		(layer "In2.Cu")
		(net "DDR4_ALERT")
	)
	(segment
		(start 42.506646 -141.393672)
		(end 42.900092 -141.000226)
		(width 0.127)
		(layer "In2.Cu")
		(net "DDR4_ALERT")
	)
	(segment
		(start 35.917124 -137.8585)
		(end 36.044124 -137.7315)
		(width 0.127)
		(layer "In2.Cu")
		(net "DDR4_ALERT")
	)
	(segment
		(start 31.27502 -137.8077)
		(end 31.712662 -137.8077)
		(width 0.127)
		(layer "In2.Cu")
		(net "DDR4_ALERT")
	)
	(segment
		(start 34.393124 -138.64082)
		(end 34.520124 -138.76782)
		(width 0.127)
		(layer "In2.Cu")
		(net "DDR4_ALERT")
	)
	(segment
		(start 24.426164 -137.926318)
		(end 27.281124 -137.926318)
		(width 0.127)
		(layer "In2.Cu")
		(net "DDR4_ALERT")
	)
	(segment
		(start 29.400246 -140.04544)
		(end 30.9626 -140.04544)
		(width 0.127)
		(layer "In2.Cu")
		(net "DDR4_ALERT")
	)
	(segment
		(start 24.172672 -137.672826)
		(end 24.426164 -137.926318)
		(width 0.127)
		(layer "In2.Cu")
		(net "DDR4_ALERT")
	)
	(segment
		(start 33.885124 -138.39952)
		(end 33.885124 -137.8585)
		(width 0.127)
		(layer "In2.Cu")
		(net "DDR4_ALERT")
	)
	(segment
		(start 35.028124 -137.7315)
		(end 35.282124 -137.7315)
		(width 0.127)
		(layer "In2.Cu")
		(net "DDR4_ALERT")
	)
	(segment
		(start 32.604456 -137.39114)
		(end 32.944816 -137.7315)
		(width 0.127)
		(layer "In2.Cu")
		(net "DDR4_ALERT")
	)
	(segment
		(start 34.393124 -137.8585)
		(end 34.393124 -138.64082)
		(width 0.127)
		(layer "In2.Cu")
		(net "DDR4_ALERT")
	)
	(segment
		(start 23.810976 -137.672826)
		(end 24.172672 -137.672826)
		(width 0.127)
		(layer "In2.Cu")
		(net "DDR4_ALERT")
	)
	(segment
		(start 30.9626 -140.04544)
		(end 31.0896 -139.91844)
		(width 0.127)
		(layer "In2.Cu")
		(net "DDR4_ALERT")
	)
	(segment
		(start 35.282124 -137.7315)
		(end 35.409124 -137.8585)
		(width 0.127)
		(layer "In2.Cu")
		(net "DDR4_ALERT")
	)
	(segment
		(start 33.758124 -138.52652)
		(end 33.885124 -138.39952)
		(width 0.127)
		(layer "In2.Cu")
		(net "DDR4_ALERT")
	)
	(segment
		(start 34.012124 -137.7315)
		(end 34.266124 -137.7315)
		(width 0.127)
		(layer "In2.Cu")
		(net "DDR4_ALERT")
	)
	(segment
		(start 36.595812 -137.7315)
		(end 40.257984 -141.393672)
		(width 0.127)
		(layer "In2.Cu")
		(net "DDR4_ALERT")
	)
	(segment
		(start 31.712662 -137.8077)
		(end 32.129222 -137.39114)
		(width 0.127)
		(layer "In2.Cu")
		(net "DDR4_ALERT")
	)
	(segment
		(start 33.377124 -138.39952)
		(end 33.504124 -138.52652)
		(width 0.127)
		(layer "In2.Cu")
		(net "DDR4_ALERT")
	)
	(segment
		(start 27.281124 -137.926318)
		(end 29.400246 -140.04544)
		(width 0.127)
		(layer "In2.Cu")
		(net "DDR4_ALERT")
	)
	(segment
		(start 35.917124 -138.67384)
		(end 35.917124 -137.8585)
		(width 0.127)
		(layer "In2.Cu")
		(net "DDR4_ALERT")
	)
	(segment
		(start 33.250124 -137.7315)
		(end 33.377124 -137.8585)
		(width 0.127)
		(layer "In2.Cu")
		(net "DDR4_ALERT")
	)
	(segment
		(start 34.520124 -138.76782)
		(end 34.774124 -138.76782)
		(width 0.127)
		(layer "In2.Cu")
		(net "DDR4_ALERT")
	)
	(segment
		(start 35.409124 -137.8585)
		(end 35.409124 -138.67384)
		(width 0.127)
		(layer "In2.Cu")
		(net "DDR4_ALERT")
	)
	(segment
		(start 33.377124 -137.8585)
		(end 33.377124 -138.39952)
		(width 0.127)
		(layer "In2.Cu")
		(net "DDR4_ALERT")
	)
	(segment
		(start 32.944816 -137.7315)
		(end 33.250124 -137.7315)
		(width 0.127)
		(layer "In2.Cu")
		(net "DDR4_ALERT")
	)
	(segment
		(start 34.774124 -138.76782)
		(end 34.901124 -138.64082)
		(width 0.127)
		(layer "In2.Cu")
		(net "DDR4_ALERT")
	)
	(segment
		(start 34.901124 -138.64082)
		(end 34.901124 -137.8585)
		(width 0.127)
		(layer "In2.Cu")
		(net "DDR4_ALERT")
	)
	(segment
		(start 19.59356 -134.663688)
		(end 19.383248 -134.663688)
		(width 0.127)
		(layer "F.Cu")
		(net "DDR4_ACT")
	)
	(segment
		(start 17.723612 -130.562858)
		(end 17.723612 -129.583688)
		(width 0.127)
		(layer "F.Cu")
		(net "DDR4_ACT")
	)
	(segment
		(start 40.899842 -142.199868)
		(end 41.299892 -142.599918)
		(width 0.127)
		(layer "F.Cu")
		(net "DDR4_ACT")
	)
	(segment
		(start 18.434558 -140.561568)
		(end 18.761456 -140.888466)
		(width 0.127)
		(layer "F.Cu")
		(net "DDR4_ACT")
	)
	(segment
		(start 17.723612 -130.562858)
		(end 18.422112 -131.261358)
		(width 0.127)
		(layer "F.Cu")
		(net "DDR4_ACT")
	)
	(segment
		(start 19.742912 -134.51459)
		(end 19.59356 -134.663688)
		(width 0.127)
		(layer "F.Cu")
		(net "DDR4_ACT")
	)
	(segment
		(start 18.598388 -134.38759)
		(end 18.598388 -134.597648)
		(width 0.127)
		(layer "F.Cu")
		(net "DDR4_ACT")
	)
	(segment
		(start 19.454876 -140.888466)
		(end 19.882104 -140.461238)
		(width 0.127)
		(layer "F.Cu")
		(net "DDR4_ACT")
	)
	(segment
		(start 19.742912 -134.304532)
		(end 19.742912 -134.51459)
		(width 0.127)
		(layer "F.Cu")
		(net "DDR4_ACT")
	)
	(segment
		(start 18.958052 -134.238492)
		(end 18.74774 -134.238492)
		(width 0.127)
		(layer "F.Cu")
		(net "DDR4_ACT")
	)
	(segment
		(start 19.383248 -134.663688)
		(end 18.958052 -134.238492)
		(width 0.127)
		(layer "F.Cu")
		(net "DDR4_ACT")
	)
	(segment
		(start 18.761456 -140.888466)
		(end 19.454876 -140.888466)
		(width 0.127)
		(layer "F.Cu")
		(net "DDR4_ACT")
	)
	(segment
		(start 18.422112 -131.261358)
		(end 18.422112 -132.983732)
		(width 0.127)
		(layer "F.Cu")
		(net "DDR4_ACT")
	)
	(segment
		(start 18.598388 -134.597648)
		(end 19.882104 -135.881364)
		(width 0.127)
		(layer "F.Cu")
		(net "DDR4_ACT")
	)
	(segment
		(start 19.882104 -140.461238)
		(end 19.882104 -138.573764)
		(width 0.127)
		(layer "F.Cu")
		(net "DDR4_ACT")
	)
	(segment
		(start 18.422112 -132.983732)
		(end 19.742912 -134.304532)
		(width 0.127)
		(layer "F.Cu")
		(net "DDR4_ACT")
	)
	(segment
		(start 19.882104 -135.881364)
		(end 19.882104 -138.573764)
		(width 0.127)
		(layer "F.Cu")
		(net "DDR4_ACT")
	)
	(segment
		(start 17.723612 -129.583688)
		(end 17.7546 -129.5527)
		(width 0.127)
		(layer "F.Cu")
		(net "DDR4_ACT")
	)
	(segment
		(start 18.74774 -134.238492)
		(end 18.598388 -134.38759)
		(width 0.127)
		(layer "F.Cu")
		(net "DDR4_ACT")
	)
	(via
		(at 19.882104 -138.573764)
		(size 0.508)
		(drill 0.254)
		(layers "F.Cu" "B.Cu")
		(net "DDR4_ACT")
	)
	(via
		(at 41.299892 -142.599918)
		(size 0.4572)
		(drill 0.2032)
		(layers "F.Cu" "B.Cu")
		(net "DDR4_ACT")
	)
	(segment
		(start 21.048472 -137.756392)
		(end 20.724876 -137.432796)
		(width 0.0889)
		(layer "In5.Cu")
		(net "DDR4_ACT")
	)
	(segment
		(start 24.088344 -137.253726)
		(end 23.494492 -137.253726)
		(width 0.127)
		(layer "In5.Cu")
		(net "DDR4_ACT")
	)
	(segment
		(start 23.387304 -137.360914)
		(end 23.386796 -137.361422)
		(width 0.0889)
		(layer "In5.Cu")
		(net "DDR4_ACT")
	)
	(segment
		(start 20.588224 -138.301984)
		(end 20.203922 -137.917682)
		(width 0.0889)
		(layer "In5.Cu")
		(net "DDR4_ACT")
	)
	(segment
		(start 21.299932 -137.756392)
		(end 21.048472 -137.756392)
		(width 0.0889)
		(layer "In5.Cu")
		(net "DDR4_ACT")
	)
	(segment
		(start 20.473416 -137.536936)
		(end 20.473416 -137.684256)
		(width 0.0889)
		(layer "In5.Cu")
		(net "DDR4_ACT")
	)
	(segment
		(start 29.991558 -139.9286)
		(end 27.609038 -137.54608)
		(width 0.127)
		(layer "In5.Cu")
		(net "DDR4_ACT")
	)
	(segment
		(start 23.494492 -137.253726)
		(end 23.387304 -137.360914)
		(width 0.127)
		(layer "In5.Cu")
		(net "DDR4_ACT")
	)
	(segment
		(start 40.972486 -142.51432)
		(end 40.74033 -142.282164)
		(width 0.127)
		(layer "In5.Cu")
		(net "DDR4_ACT")
	)
	(segment
		(start 37.878258 -140.537692)
		(end 32.608266 -140.537692)
		(width 0.127)
		(layer "In5.Cu")
		(net "DDR4_ACT")
	)
	(segment
		(start 20.839684 -138.050524)
		(end 20.839684 -138.197844)
		(width 0.0889)
		(layer "In5.Cu")
		(net "DDR4_ACT")
	)
	(segment
		(start 20.203922 -137.917682)
		(end 20.056602 -137.917682)
		(width 0.0889)
		(layer "In5.Cu")
		(net "DDR4_ACT")
	)
	(segment
		(start 20.056602 -137.917682)
		(end 19.882104 -138.09218)
		(width 0.0889)
		(layer "In5.Cu")
		(net "DDR4_ACT")
	)
	(segment
		(start 19.882104 -138.09218)
		(end 19.882104 -138.573764)
		(width 0.0889)
		(layer "In5.Cu")
		(net "DDR4_ACT")
	)
	(segment
		(start 21.694902 -137.361422)
		(end 21.299932 -137.756392)
		(width 0.0889)
		(layer "In5.Cu")
		(net "DDR4_ACT")
	)
	(segment
		(start 39.397686 -142.05712)
		(end 37.878258 -140.537692)
		(width 0.127)
		(layer "In5.Cu")
		(net "DDR4_ACT")
	)
	(segment
		(start 20.839684 -138.197844)
		(end 20.735544 -138.301984)
		(width 0.0889)
		(layer "In5.Cu")
		(net "DDR4_ACT")
	)
	(segment
		(start 23.386796 -137.361422)
		(end 21.694902 -137.361422)
		(width 0.0889)
		(layer "In5.Cu")
		(net "DDR4_ACT")
	)
	(segment
		(start 31.999174 -139.9286)
		(end 29.991558 -139.9286)
		(width 0.127)
		(layer "In5.Cu")
		(net "DDR4_ACT")
	)
	(segment
		(start 32.608266 -140.537692)
		(end 31.999174 -139.9286)
		(width 0.127)
		(layer "In5.Cu")
		(net "DDR4_ACT")
	)
	(segment
		(start 20.735544 -138.301984)
		(end 20.588224 -138.301984)
		(width 0.0889)
		(layer "In5.Cu")
		(net "DDR4_ACT")
	)
	(segment
		(start 20.724876 -137.432796)
		(end 20.577556 -137.432796)
		(width 0.0889)
		(layer "In5.Cu")
		(net "DDR4_ACT")
	)
	(segment
		(start 20.577556 -137.432796)
		(end 20.473416 -137.536936)
		(width 0.0889)
		(layer "In5.Cu")
		(net "DDR4_ACT")
	)
	(segment
		(start 41.299892 -142.599918)
		(end 41.179242 -142.599918)
		(width 0.127)
		(layer "In5.Cu")
		(net "DDR4_ACT")
	)
	(segment
		(start 27.609038 -137.54608)
		(end 24.380698 -137.54608)
		(width 0.127)
		(layer "In5.Cu")
		(net "DDR4_ACT")
	)
	(segment
		(start 24.380698 -137.54608)
		(end 24.088344 -137.253726)
		(width 0.127)
		(layer "In5.Cu")
		(net "DDR4_ACT")
	)
	(segment
		(start 20.473416 -137.684256)
		(end 20.839684 -138.050524)
		(width 0.0889)
		(layer "In5.Cu")
		(net "DDR4_ACT")
	)
	(arc
		(start 40.15613 -142.231364)
		(mid 39.739214 -142.308444)
		(end 39.397686 -142.05712)
		(width 0.127)
		(layer "In5.Cu")
		(net "DDR4_ACT")
	)
	(arc
		(start 40.628316 -142.201392)
		(mid 40.388187 -142.152585)
		(end 40.15613 -142.231364)
		(width 0.127)
		(layer "In5.Cu")
		(net "DDR4_ACT")
	)
	(arc
		(start 40.74033 -142.282164)
		(mid 40.687556 -142.237296)
		(end 40.628316 -142.201392)
		(width 0.127)
		(layer "In5.Cu")
		(net "DDR4_ACT")
	)
	(arc
		(start 41.179242 -142.599918)
		(mid 41.067363 -142.577664)
		(end 40.972486 -142.51432)
		(width 0.127)
		(layer "In5.Cu")
		(net "DDR4_ACT")
	)
	(segment
		(start 48.899826 -150.200106)
		(end 48.899826 -150.199852)
		(width 0.127)
		(layer "F.Cu")
		(net "DACAV33")
	)
	(segment
		(start 49.299622 -149.800056)
		(end 49.299622 -149.799802)
		(width 0.127)
		(layer "F.Cu")
		(net "DACAV33")
	)
	(segment
		(start 49.299622 -149.799802)
		(end 48.899826 -149.400006)
		(width 0.127)
		(layer "F.Cu")
		(net "DACAV33")
	)
	(segment
		(start 49.299622 -150.599902)
		(end 48.899826 -150.200106)
		(width 0.127)
		(layer "F.Cu")
		(net "DACAV33")
	)
	(via
		(at 35.29838 -160.598358)
		(size 0.508)
		(drill 0.254)
		(layers "F.Cu" "B.Cu")
		(net "DACAV33")
	)
	(via
		(at 49.299622 -149.800056)
		(size 0.4572)
		(drill 0.2032)
		(layers "F.Cu" "B.Cu")
		(net "DACAV33")
	)
	(via
		(at 49.299622 -150.599902)
		(size 0.4572)
		(drill 0.2032)
		(layers "F.Cu" "B.Cu")
		(net "DACAV33")
	)
	(segment
		(start 49.299622 -150.599902)
		(end 49.299622 -149.800056)
		(width 0.127)
		(layer "B.Cu")
		(net "DACAV33")
	)
	(segment
		(start 35.489134 -160.789112)
		(end 39.439088 -160.789112)
		(width 0.127)
		(layer "In2.Cu")
		(net "DACAV33")
	)
	(segment
		(start 47.761398 -150.206456)
		(end 47.761652 -150.206202)
		(width 0.127)
		(layer "In2.Cu")
		(net "DACAV33")
	)
	(segment
		(start 47.30623 -150.436834)
		(end 47.536608 -150.206456)
		(width 0.127)
		(layer "In2.Cu")
		(net "DACAV33")
	)
	(segment
		(start 45.693838 -152.045416)
		(end 45.986954 -151.7523)
		(width 0.127)
		(layer "In2.Cu")
		(net "DACAV33")
	)
	(segment
		(start 46.317154 -151.7523)
		(end 47.30623 -150.763224)
		(width 0.127)
		(layer "In2.Cu")
		(net "DACAV33")
	)
	(segment
		(start 47.30623 -150.763224)
		(end 47.30623 -150.436834)
		(width 0.127)
		(layer "In2.Cu")
		(net "DACAV33")
	)
	(segment
		(start 35.29838 -160.598358)
		(end 35.489134 -160.789112)
		(width 0.127)
		(layer "In2.Cu")
		(net "DACAV33")
	)
	(segment
		(start 47.761652 -150.206202)
		(end 48.663098 -150.206202)
		(width 0.127)
		(layer "In2.Cu")
		(net "DACAV33")
	)
	(segment
		(start 39.439088 -160.789112)
		(end 45.693838 -154.534362)
		(width 0.127)
		(layer "In2.Cu")
		(net "DACAV33")
	)
	(segment
		(start 48.663098 -150.206202)
		(end 49.056798 -150.599902)
		(width 0.127)
		(layer "In2.Cu")
		(net "DACAV33")
	)
	(segment
		(start 47.536608 -150.206456)
		(end 47.761398 -150.206456)
		(width 0.127)
		(layer "In2.Cu")
		(net "DACAV33")
	)
	(segment
		(start 45.986954 -151.7523)
		(end 46.317154 -151.7523)
		(width 0.127)
		(layer "In2.Cu")
		(net "DACAV33")
	)
	(segment
		(start 45.693838 -154.534362)
		(end 45.693838 -152.045416)
		(width 0.127)
		(layer "In2.Cu")
		(net "DACAV33")
	)
	(segment
		(start 49.056798 -150.599902)
		(end 49.299622 -150.599902)
		(width 0.127)
		(layer "In2.Cu")
		(net "DACAV33")
	)
	(segment
		(start 66.40322 -136.53008)
		(end 66.9544 -135.9789)
		(width 0.127)
		(layer "F.Cu")
		(net "COMP_SPARE_1")
	)
	(segment
		(start 65.778126 -136.53008)
		(end 65.778126 -137.533634)
		(width 0.127)
		(layer "F.Cu")
		(net "COMP_SPARE_1")
	)
	(segment
		(start 65.778126 -136.53008)
		(end 66.40322 -136.53008)
		(width 0.127)
		(layer "F.Cu")
		(net "COMP_SPARE_1")
	)
	(via
		(at 66.9544 -135.9789)
		(size 0.508)
		(drill 0.254)
		(layers "F.Cu" "B.Cu")
		(net "COMP_SPARE_1")
	)
	(via
		(at 65.778126 -136.53008)
		(size 0.6604)
		(drill 0.3302)
		(layers "F.Cu" "B.Cu")
		(net "COMP_SPARE_1")
	)
	(via
		(at 101.0031 -136.314434)
		(size 0.508)
		(drill 0.254)
		(layers "F.Cu" "B.Cu")
		(net "COMP_SPARE_1")
	)
	(segment
		(start 102.108 -47.136304)
		(end 103.844344 -45.39996)
		(width 0.127)
		(layer "In2.Cu")
		(net "COMP_SPARE_1")
	)
	(segment
		(start 101.0031 -136.314434)
		(end 102.108 -135.209534)
		(width 0.127)
		(layer "In2.Cu")
		(net "COMP_SPARE_1")
	)
	(segment
		(start 103.844344 -45.39996)
		(end 107.099862 -45.39996)
		(width 0.127)
		(layer "In2.Cu")
		(net "COMP_SPARE_1")
	)
	(segment
		(start 102.108 -135.209534)
		(end 102.108 -47.136304)
		(width 0.127)
		(layer "In2.Cu")
		(net "COMP_SPARE_1")
	)
	(segment
		(start 86.900766 -138.371072)
		(end 85.011006 -136.481312)
		(width 0.127)
		(layer "In5.Cu")
		(net "COMP_SPARE_1")
	)
	(segment
		(start 78.248256 -136.0678)
		(end 70.454012 -136.0678)
		(width 0.127)
		(layer "In5.Cu")
		(net "COMP_SPARE_1")
	)
	(segment
		(start 66.9925 -135.9408)
		(end 66.9544 -135.9789)
		(width 0.127)
		(layer "In5.Cu")
		(net "COMP_SPARE_1")
	)
	(segment
		(start 97.0534 -136.314434)
		(end 94.996762 -138.371072)
		(width 0.127)
		(layer "In5.Cu")
		(net "COMP_SPARE_1")
	)
	(segment
		(start 83.716876 -136.481312)
		(end 83.570064 -136.3345)
		(width 0.127)
		(layer "In5.Cu")
		(net "COMP_SPARE_1")
	)
	(segment
		(start 101.0031 -136.314434)
		(end 97.0534 -136.314434)
		(width 0.127)
		(layer "In5.Cu")
		(net "COMP_SPARE_1")
	)
	(segment
		(start 94.996762 -138.371072)
		(end 86.900766 -138.371072)
		(width 0.127)
		(layer "In5.Cu")
		(net "COMP_SPARE_1")
	)
	(segment
		(start 78.629256 -136.4488)
		(end 78.248256 -136.0678)
		(width 0.127)
		(layer "In5.Cu")
		(net "COMP_SPARE_1")
	)
	(segment
		(start 82.781394 -136.3345)
		(end 82.667094 -136.4488)
		(width 0.127)
		(layer "In5.Cu")
		(net "COMP_SPARE_1")
	)
	(segment
		(start 83.570064 -136.3345)
		(end 82.781394 -136.3345)
		(width 0.127)
		(layer "In5.Cu")
		(net "COMP_SPARE_1")
	)
	(segment
		(start 82.667094 -136.4488)
		(end 78.629256 -136.4488)
		(width 0.127)
		(layer "In5.Cu")
		(net "COMP_SPARE_1")
	)
	(segment
		(start 85.011006 -136.481312)
		(end 83.716876 -136.481312)
		(width 0.127)
		(layer "In5.Cu")
		(net "COMP_SPARE_1")
	)
	(segment
		(start 70.454012 -136.0678)
		(end 70.327012 -135.9408)
		(width 0.127)
		(layer "In5.Cu")
		(net "COMP_SPARE_1")
	)
	(segment
		(start 70.327012 -135.9408)
		(end 66.9925 -135.9408)
		(width 0.127)
		(layer "In5.Cu")
		(net "COMP_SPARE_1")
	)
	(segment
		(start 62.658752 -134.239254)
		(end 63.320422 -134.900924)
		(width 0.127)
		(layer "F.Cu")
		(net "COMP_SPARE_0")
	)
	(segment
		(start 63.728854 -134.900924)
		(end 65.034668 -134.900924)
		(width 0.127)
		(layer "F.Cu")
		(net "COMP_SPARE_0")
	)
	(segment
		(start 65.034668 -134.900924)
		(end 65.505076 -134.430516)
		(width 0.127)
		(layer "F.Cu")
		(net "COMP_SPARE_0")
	)
	(segment
		(start 63.320422 -134.900924)
		(end 63.728854 -134.900924)
		(width 0.127)
		(layer "F.Cu")
		(net "COMP_SPARE_0")
	)
	(via
		(at 63.728854 -134.900924)
		(size 0.6604)
		(drill 0.3302)
		(layers "F.Cu" "B.Cu")
		(net "COMP_SPARE_0")
	)
	(via
		(at 101.0031 -129.0955)
		(size 0.508)
		(drill 0.254)
		(layers "F.Cu" "B.Cu")
		(net "COMP_SPARE_0")
	)
	(via
		(at 65.505076 -134.430516)
		(size 0.508)
		(drill 0.254)
		(layers "F.Cu" "B.Cu")
		(net "COMP_SPARE_0")
	)
	(segment
		(start 101.0031 -129.0955)
		(end 101.727 -128.3716)
		(width 0.127)
		(layer "In2.Cu")
		(net "COMP_SPARE_0")
	)
	(segment
		(start 101.727 -46.978316)
		(end 104.70515 -44.000166)
		(width 0.127)
		(layer "In2.Cu")
		(net "COMP_SPARE_0")
	)
	(segment
		(start 101.727 -128.3716)
		(end 101.727 -46.978316)
		(width 0.127)
		(layer "In2.Cu")
		(net "COMP_SPARE_0")
	)
	(segment
		(start 104.70515 -44.000166)
		(end 107.099862 -44.000166)
		(width 0.127)
		(layer "In2.Cu")
		(net "COMP_SPARE_0")
	)
	(segment
		(start 83.246976 -134.213346)
		(end 83.602322 -133.858)
		(width 0.127)
		(layer "In5.Cu")
		(net "COMP_SPARE_0")
	)
	(segment
		(start 81.3816 -134.6454)
		(end 81.813654 -134.213346)
		(width 0.127)
		(layer "In5.Cu")
		(net "COMP_SPARE_0")
	)
	(segment
		(start 72.3138 -134.6454)
		(end 81.3816 -134.6454)
		(width 0.127)
		(layer "In5.Cu")
		(net "COMP_SPARE_0")
	)
	(segment
		(start 98.032062 -130.838956)
		(end 99.259644 -130.838956)
		(width 0.127)
		(layer "In5.Cu")
		(net "COMP_SPARE_0")
	)
	(segment
		(start 96.752918 -132.1181)
		(end 98.032062 -130.838956)
		(width 0.127)
		(layer "In5.Cu")
		(net "COMP_SPARE_0")
	)
	(segment
		(start 87.4522 -133.858)
		(end 88.1507 -133.1595)
		(width 0.127)
		(layer "In5.Cu")
		(net "COMP_SPARE_0")
	)
	(segment
		(start 90.851228 -133.1595)
		(end 91.892628 -132.1181)
		(width 0.127)
		(layer "In5.Cu")
		(net "COMP_SPARE_0")
	)
	(segment
		(start 99.259644 -130.838956)
		(end 101.0031 -129.0955)
		(width 0.127)
		(layer "In5.Cu")
		(net "COMP_SPARE_0")
	)
	(segment
		(start 66.356992 -133.5786)
		(end 71.247 -133.5786)
		(width 0.127)
		(layer "In5.Cu")
		(net "COMP_SPARE_0")
	)
	(segment
		(start 65.505076 -134.430516)
		(end 66.356992 -133.5786)
		(width 0.127)
		(layer "In5.Cu")
		(net "COMP_SPARE_0")
	)
	(segment
		(start 91.892628 -132.1181)
		(end 96.752918 -132.1181)
		(width 0.127)
		(layer "In5.Cu")
		(net "COMP_SPARE_0")
	)
	(segment
		(start 81.813654 -134.213346)
		(end 83.246976 -134.213346)
		(width 0.127)
		(layer "In5.Cu")
		(net "COMP_SPARE_0")
	)
	(segment
		(start 83.602322 -133.858)
		(end 87.4522 -133.858)
		(width 0.127)
		(layer "In5.Cu")
		(net "COMP_SPARE_0")
	)
	(segment
		(start 71.247 -133.5786)
		(end 72.3138 -134.6454)
		(width 0.127)
		(layer "In5.Cu")
		(net "COMP_SPARE_0")
	)
	(segment
		(start 88.1507 -133.1595)
		(end 90.851228 -133.1595)
		(width 0.127)
		(layer "In5.Cu")
		(net "COMP_SPARE_0")
	)
	(segment
		(start 41.699942 -150.999952)
		(end 41.299892 -151.400002)
		(width 0.127)
		(layer "F.Cu")
		(net "COMP_PWR_EN_R")
	)
	(via
		(at 41.299892 -151.400002)
		(size 0.4572)
		(drill 0.2032)
		(layers "F.Cu" "B.Cu")
		(net "COMP_PWR_EN_R")
	)
	(via
		(at 38.862 -151.111458)
		(size 0.6096)
		(drill 0.3048)
		(layers "F.Cu" "B.Cu")
		(net "COMP_PWR_EN_R")
	)
	(segment
		(start 40.33647 -150.993602)
		(end 40.893492 -150.993602)
		(width 0.127)
		(layer "B.Cu")
		(net "COMP_PWR_EN_R")
	)
	(segment
		(start 39.064184 -150.909274)
		(end 40.252142 -150.909274)
		(width 0.127)
		(layer "B.Cu")
		(net "COMP_PWR_EN_R")
	)
	(segment
		(start 40.252142 -150.909274)
		(end 40.33647 -150.993602)
		(width 0.127)
		(layer "B.Cu")
		(net "COMP_PWR_EN_R")
	)
	(segment
		(start 38.411658 -151.5618)
		(end 37.9095 -151.5618)
		(width 0.127)
		(layer "B.Cu")
		(net "COMP_PWR_EN_R")
	)
	(segment
		(start 38.862 -151.111458)
		(end 38.411658 -151.5618)
		(width 0.127)
		(layer "B.Cu")
		(net "COMP_PWR_EN_R")
	)
	(segment
		(start 38.862 -151.111458)
		(end 39.064184 -150.909274)
		(width 0.127)
		(layer "B.Cu")
		(net "COMP_PWR_EN_R")
	)
	(segment
		(start 40.893492 -150.993602)
		(end 41.299892 -151.400002)
		(width 0.127)
		(layer "B.Cu")
		(net "COMP_PWR_EN_R")
	)
	(segment
		(start 83.042252 -153.032714)
		(end 84.1375 -151.937466)
		(width 0.127)
		(layer "F.Cu")
		(net "COMP_PWR_EN")
	)
	(segment
		(start 82.146902 -153.032714)
		(end 83.042252 -153.032714)
		(width 0.127)
		(layer "F.Cu")
		(net "COMP_PWR_EN")
	)
	(segment
		(start 84.1375 -151.937466)
		(end 84.1375 -151.52624)
		(width 0.127)
		(layer "F.Cu")
		(net "COMP_PWR_EN")
	)
	(via
		(at 82.146902 -153.032714)
		(size 0.508)
		(drill 0.254)
		(layers "F.Cu" "B.Cu")
		(net "COMP_PWR_EN")
	)
	(via
		(at 37.846 -124.1044)
		(size 0.508)
		(drill 0.254)
		(layers "F.Cu" "B.Cu")
		(net "COMP_PWR_EN")
	)
	(via
		(at 95.4278 -147.345908)
		(size 0.508)
		(drill 0.254)
		(layers "F.Cu" "B.Cu")
		(net "COMP_PWR_EN")
	)
	(via
		(at 73.33488 -162.92957)
		(size 0.508)
		(drill 0.254)
		(layers "F.Cu" "B.Cu")
		(net "COMP_PWR_EN")
	)
	(via
		(at 37.846 -125.603)
		(size 0.6096)
		(drill 0.3048)
		(layers "F.Cu" "B.Cu")
		(net "COMP_PWR_EN")
	)
	(via
		(at 76.962 -149.0472)
		(size 0.508)
		(drill 0.254)
		(layers "F.Cu" "B.Cu")
		(net "COMP_PWR_EN")
	)
	(via
		(at 98.826574 -120.706896)
		(size 0.508)
		(drill 0.254)
		(layers "F.Cu" "B.Cu")
		(net "COMP_PWR_EN")
	)
	(via
		(at 35.433 -155.2448)
		(size 0.508)
		(drill 0.254)
		(layers "F.Cu" "B.Cu")
		(net "COMP_PWR_EN")
	)
	(segment
		(start 82.548476 -150.141686)
		(end 82.045048 -150.645114)
		(width 0.127)
		(layer "B.Cu")
		(net "COMP_PWR_EN")
	)
	(segment
		(start 75.3745 -150.819866)
		(end 75.3745 -151.29256)
		(width 0.127)
		(layer "B.Cu")
		(net "COMP_PWR_EN")
	)
	(segment
		(start 76.962 -149.0472)
		(end 76.9366 -149.0726)
		(width 0.127)
		(layer "B.Cu")
		(net "COMP_PWR_EN")
	)
	(segment
		(start 76.9366 -149.0726)
		(end 75.511914 -149.0726)
		(width 0.127)
		(layer "B.Cu")
		(net "COMP_PWR_EN")
	)
	(segment
		(start 37.0205 -153.721308)
		(end 37.0205 -151.5618)
		(width 0.127)
		(layer "B.Cu")
		(net "COMP_PWR_EN")
	)
	(segment
		(start 76.962 -149.0472)
		(end 76.962 -149.4536)
		(width 0.127)
		(layer "B.Cu")
		(net "COMP_PWR_EN")
	)
	(segment
		(start 76.962 -149.4536)
		(end 78.377288 -150.868888)
		(width 0.127)
		(layer "B.Cu")
		(net "COMP_PWR_EN")
	)
	(segment
		(start 35.433 -155.2448)
		(end 35.56 -155.1178)
		(width 0.127)
		(layer "B.Cu")
		(net "COMP_PWR_EN")
	)
	(segment
		(start 82.977228 -150.141686)
		(end 82.548476 -150.141686)
		(width 0.127)
		(layer "B.Cu")
		(net "COMP_PWR_EN")
	)
	(segment
		(start 35.56 -155.1178)
		(end 35.624008 -155.1178)
		(width 0.127)
		(layer "B.Cu")
		(net "COMP_PWR_EN")
	)
	(segment
		(start 37.846 -125.603)
		(end 37.846 -124.1044)
		(width 0.127)
		(layer "B.Cu")
		(net "COMP_PWR_EN")
	)
	(segment
		(start 78.377288 -150.868888)
		(end 79.684372 -150.868888)
		(width 0.127)
		(layer "B.Cu")
		(net "COMP_PWR_EN")
	)
	(segment
		(start 84.074508 -149.756622)
		(end 83.362292 -149.756622)
		(width 0.127)
		(layer "B.Cu")
		(net "COMP_PWR_EN")
	)
	(segment
		(start 82.146902 -152.409906)
		(end 82.146902 -153.032714)
		(width 0.127)
		(layer "B.Cu")
		(net "COMP_PWR_EN")
	)
	(segment
		(start 83.362292 -149.756622)
		(end 82.977228 -150.141686)
		(width 0.127)
		(layer "B.Cu")
		(net "COMP_PWR_EN")
	)
	(segment
		(start 35.624008 -155.1178)
		(end 37.0205 -153.721308)
		(width 0.127)
		(layer "B.Cu")
		(net "COMP_PWR_EN")
	)
	(segment
		(start 38.443154 -127.443738)
		(end 37.846 -126.846584)
		(width 0.127)
		(layer "B.Cu")
		(net "COMP_PWR_EN")
	)
	(segment
		(start 75.26274 -150.708106)
		(end 75.3745 -150.819866)
		(width 0.127)
		(layer "B.Cu")
		(net "COMP_PWR_EN")
	)
	(segment
		(start 75.511914 -149.0726)
		(end 75.26274 -149.321774)
		(width 0.127)
		(layer "B.Cu")
		(net "COMP_PWR_EN")
	)
	(segment
		(start 79.684372 -150.868888)
		(end 81.848198 -153.032714)
		(width 0.127)
		(layer "B.Cu")
		(net "COMP_PWR_EN")
	)
	(segment
		(start 75.26274 -149.321774)
		(end 75.26274 -150.708106)
		(width 0.127)
		(layer "B.Cu")
		(net "COMP_PWR_EN")
	)
	(segment
		(start 81.848198 -153.032714)
		(end 82.146902 -153.032714)
		(width 0.127)
		(layer "B.Cu")
		(net "COMP_PWR_EN")
	)
	(segment
		(start 82.045048 -152.308052)
		(end 82.146902 -152.409906)
		(width 0.127)
		(layer "B.Cu")
		(net "COMP_PWR_EN")
	)
	(segment
		(start 37.846 -126.846584)
		(end 37.846 -125.603)
		(width 0.127)
		(layer "B.Cu")
		(net "COMP_PWR_EN")
	)
	(segment
		(start 82.045048 -150.645114)
		(end 82.045048 -152.308052)
		(width 0.127)
		(layer "B.Cu")
		(net "COMP_PWR_EN")
	)
	(segment
		(start 104.661462 -40.809926)
		(end 104.661462 -31.574232)
		(width 0.127)
		(layer "In2.Cu")
		(net "COMP_PWR_EN")
	)
	(segment
		(start 104.661462 -31.574232)
		(end 106.669078 -29.566616)
		(width 0.127)
		(layer "In2.Cu")
		(net "COMP_PWR_EN")
	)
	(segment
		(start 98.6282 -120.90527)
		(end 98.6282 -123.91898)
		(width 0.127)
		(layer "In2.Cu")
		(net "COMP_PWR_EN")
	)
	(segment
		(start 99.410266 -142.2019)
		(end 98.0186 -143.593566)
		(width 0.127)
		(layer "In2.Cu")
		(net "COMP_PWR_EN")
	)
	(segment
		(start 98.7044 -135.1788)
		(end 98.7044 -137.513568)
		(width 0.127)
		(layer "In2.Cu")
		(net "COMP_PWR_EN")
	)
	(segment
		(start 98.746818 -130.6068)
		(end 99.0346 -130.894582)
		(width 0.127)
		(layer "In2.Cu")
		(net "COMP_PWR_EN")
	)
	(segment
		(start 73.33488 -162.92957)
		(end 73.3806 -162.88385)
		(width 0.127)
		(layer "In2.Cu")
		(net "COMP_PWR_EN")
	)
	(segment
		(start 98.826574 -120.706896)
		(end 98.6282 -120.90527)
		(width 0.127)
		(layer "In2.Cu")
		(net "COMP_PWR_EN")
	)
	(segment
		(start 98.826574 -120.706896)
		(end 99.441 -120.09247)
		(width 0.127)
		(layer "In2.Cu")
		(net "COMP_PWR_EN")
	)
	(segment
		(start 77.098144 -149.183344)
		(end 76.962 -149.0472)
		(width 0.127)
		(layer "In2.Cu")
		(net "COMP_PWR_EN")
	)
	(segment
		(start 98.6282 -123.91898)
		(end 99.725988 -125.016768)
		(width 0.127)
		(layer "In2.Cu")
		(net "COMP_PWR_EN")
	)
	(segment
		(start 98.0186 -144.755108)
		(end 95.4278 -147.345908)
		(width 0.127)
		(layer "In2.Cu")
		(net "COMP_PWR_EN")
	)
	(segment
		(start 99.725988 -127.070612)
		(end 98.746818 -128.049782)
		(width 0.127)
		(layer "In2.Cu")
		(net "COMP_PWR_EN")
	)
	(segment
		(start 99.0346 -134.8486)
		(end 98.7044 -135.1788)
		(width 0.127)
		(layer "In2.Cu")
		(net "COMP_PWR_EN")
	)
	(segment
		(start 73.3806 -162.022282)
		(end 76.894944 -158.507938)
		(width 0.127)
		(layer "In2.Cu")
		(net "COMP_PWR_EN")
	)
	(segment
		(start 99.441 -120.09247)
		(end 99.441 -46.030388)
		(width 0.127)
		(layer "In2.Cu")
		(net "COMP_PWR_EN")
	)
	(segment
		(start 98.7044 -137.513568)
		(end 99.410266 -138.219434)
		(width 0.127)
		(layer "In2.Cu")
		(net "COMP_PWR_EN")
	)
	(segment
		(start 76.894944 -157.1625)
		(end 77.55128 -156.506164)
		(width 0.127)
		(layer "In2.Cu")
		(net "COMP_PWR_EN")
	)
	(segment
		(start 99.410266 -138.219434)
		(end 99.410266 -142.2019)
		(width 0.127)
		(layer "In2.Cu")
		(net "COMP_PWR_EN")
	)
	(segment
		(start 76.894944 -158.507938)
		(end 76.894944 -157.1625)
		(width 0.127)
		(layer "In2.Cu")
		(net "COMP_PWR_EN")
	)
	(segment
		(start 99.0346 -130.894582)
		(end 99.0346 -134.8486)
		(width 0.127)
		(layer "In2.Cu")
		(net "COMP_PWR_EN")
	)
	(segment
		(start 77.55128 -156.506164)
		(end 77.55128 -152.94229)
		(width 0.127)
		(layer "In2.Cu")
		(net "COMP_PWR_EN")
	)
	(segment
		(start 112.513618 -29.566616)
		(end 113.4872 -30.540198)
		(width 0.127)
		(layer "In2.Cu")
		(net "COMP_PWR_EN")
	)
	(segment
		(start 73.3806 -162.88385)
		(end 73.3806 -162.022282)
		(width 0.127)
		(layer "In2.Cu")
		(net "COMP_PWR_EN")
	)
	(segment
		(start 113.4872 -40.987218)
		(end 114.3 -41.800018)
		(width 0.127)
		(layer "In2.Cu")
		(net "COMP_PWR_EN")
	)
	(segment
		(start 113.4872 -30.540198)
		(end 113.4872 -40.987218)
		(width 0.127)
		(layer "In2.Cu")
		(net "COMP_PWR_EN")
	)
	(segment
		(start 106.669078 -29.566616)
		(end 112.513618 -29.566616)
		(width 0.127)
		(layer "In2.Cu")
		(net "COMP_PWR_EN")
	)
	(segment
		(start 98.0186 -143.593566)
		(end 98.0186 -144.755108)
		(width 0.127)
		(layer "In2.Cu")
		(net "COMP_PWR_EN")
	)
	(segment
		(start 99.441 -46.030388)
		(end 104.661462 -40.809926)
		(width 0.127)
		(layer "In2.Cu")
		(net "COMP_PWR_EN")
	)
	(segment
		(start 98.746818 -128.049782)
		(end 98.746818 -130.6068)
		(width 0.127)
		(layer "In2.Cu")
		(net "COMP_PWR_EN")
	)
	(segment
		(start 77.55128 -152.94229)
		(end 77.098144 -152.489154)
		(width 0.127)
		(layer "In2.Cu")
		(net "COMP_PWR_EN")
	)
	(segment
		(start 99.725988 -125.016768)
		(end 99.725988 -127.070612)
		(width 0.127)
		(layer "In2.Cu")
		(net "COMP_PWR_EN")
	)
	(segment
		(start 77.098144 -152.489154)
		(end 77.098144 -149.183344)
		(width 0.127)
		(layer "In2.Cu")
		(net "COMP_PWR_EN")
	)
	(segment
		(start 97.829878 -119.7102)
		(end 96.5454 -119.7102)
		(width 0.127)
		(layer "In5.Cu")
		(net "COMP_PWR_EN")
	)
	(segment
		(start 56.151272 -162.4584)
		(end 56.595772 -162.9029)
		(width 0.127)
		(layer "In5.Cu")
		(net "COMP_PWR_EN")
	)
	(segment
		(start 51.0286 -125.013466)
		(end 44.088812 -125.013466)
		(width 0.127)
		(layer "In5.Cu")
		(net "COMP_PWR_EN")
	)
	(segment
		(start 44.088812 -125.013466)
		(end 43.595798 -125.50648)
		(width 0.127)
		(layer "In5.Cu")
		(net "COMP_PWR_EN")
	)
	(segment
		(start 73.00087 -163.26358)
		(end 73.33488 -162.92957)
		(width 0.127)
		(layer "In5.Cu")
		(net "COMP_PWR_EN")
	)
	(segment
		(start 66.859912 -122.7963)
		(end 60.2361 -122.7963)
		(width 0.127)
		(layer "In5.Cu")
		(net "COMP_PWR_EN")
	)
	(segment
		(start 71.987918 -163.26358)
		(end 73.00087 -163.26358)
		(width 0.127)
		(layer "In5.Cu")
		(net "COMP_PWR_EN")
	)
	(segment
		(start 76.962 -149.0472)
		(end 77.092048 -148.917152)
		(width 0.127)
		(layer "In5.Cu")
		(net "COMP_PWR_EN")
	)
	(segment
		(start 81.838292 -148.186902)
		(end 81.838292 -147.74799)
		(width 0.127)
		(layer "In5.Cu")
		(net "COMP_PWR_EN")
	)
	(segment
		(start 59.616086 -122.176286)
		(end 58.178192 -122.176286)
		(width 0.127)
		(layer "In5.Cu")
		(net "COMP_PWR_EN")
	)
	(segment
		(start 41.6814 -124.4854)
		(end 38.227 -124.4854)
		(width 0.127)
		(layer "In5.Cu")
		(net "COMP_PWR_EN")
	)
	(segment
		(start 50.948844 -158.203138)
		(end 55.204106 -162.4584)
		(width 0.127)
		(layer "In5.Cu")
		(net "COMP_PWR_EN")
	)
	(segment
		(start 74.021188 -121.9708)
		(end 67.685412 -121.9708)
		(width 0.127)
		(layer "In5.Cu")
		(net "COMP_PWR_EN")
	)
	(segment
		(start 94.11335 -118.9228)
		(end 88.996012 -118.9228)
		(width 0.127)
		(layer "In5.Cu")
		(net "COMP_PWR_EN")
	)
	(segment
		(start 78.801468 -148.917152)
		(end 79.109316 -149.225)
		(width 0.127)
		(layer "In5.Cu")
		(net "COMP_PWR_EN")
	)
	(segment
		(start 98.826574 -120.706896)
		(end 97.829878 -119.7102)
		(width 0.127)
		(layer "In5.Cu")
		(net "COMP_PWR_EN")
	)
	(segment
		(start 81.838292 -147.74799)
		(end 82.749136 -146.837146)
		(width 0.127)
		(layer "In5.Cu")
		(net "COMP_PWR_EN")
	)
	(segment
		(start 35.433 -155.532836)
		(end 37.405564 -157.5054)
		(width 0.127)
		(layer "In5.Cu")
		(net "COMP_PWR_EN")
	)
	(segment
		(start 53.401722 -122.640344)
		(end 51.0286 -125.013466)
		(width 0.127)
		(layer "In5.Cu")
		(net "COMP_PWR_EN")
	)
	(segment
		(start 37.405564 -157.5054)
		(end 41.508934 -157.5054)
		(width 0.127)
		(layer "In5.Cu")
		(net "COMP_PWR_EN")
	)
	(segment
		(start 38.227 -124.4854)
		(end 37.846 -124.1044)
		(width 0.127)
		(layer "In5.Cu")
		(net "COMP_PWR_EN")
	)
	(segment
		(start 80.800194 -149.225)
		(end 81.838292 -148.186902)
		(width 0.127)
		(layer "In5.Cu")
		(net "COMP_PWR_EN")
	)
	(segment
		(start 71.583042 -163.26358)
		(end 71.590662 -163.2712)
		(width 0.127)
		(layer "In5.Cu")
		(net "COMP_PWR_EN")
	)
	(segment
		(start 60.2361 -122.7963)
		(end 59.616086 -122.176286)
		(width 0.127)
		(layer "In5.Cu")
		(net "COMP_PWR_EN")
	)
	(segment
		(start 67.685412 -121.9708)
		(end 66.859912 -122.7963)
		(width 0.127)
		(layer "In5.Cu")
		(net "COMP_PWR_EN")
	)
	(segment
		(start 93.595952 -146.48815)
		(end 94.45371 -147.345908)
		(width 0.127)
		(layer "In5.Cu")
		(net "COMP_PWR_EN")
	)
	(segment
		(start 58.178192 -122.176286)
		(end 57.714134 -122.640344)
		(width 0.127)
		(layer "In5.Cu")
		(net "COMP_PWR_EN")
	)
	(segment
		(start 43.595798 -125.50648)
		(end 42.70248 -125.50648)
		(width 0.127)
		(layer "In5.Cu")
		(net "COMP_PWR_EN")
	)
	(segment
		(start 77.092048 -148.917152)
		(end 78.801468 -148.917152)
		(width 0.127)
		(layer "In5.Cu")
		(net "COMP_PWR_EN")
	)
	(segment
		(start 57.714134 -122.640344)
		(end 53.401722 -122.640344)
		(width 0.127)
		(layer "In5.Cu")
		(net "COMP_PWR_EN")
	)
	(segment
		(start 71.341742 -163.26358)
		(end 71.583042 -163.26358)
		(width 0.127)
		(layer "In5.Cu")
		(net "COMP_PWR_EN")
	)
	(segment
		(start 42.206672 -158.203138)
		(end 50.948844 -158.203138)
		(width 0.127)
		(layer "In5.Cu")
		(net "COMP_PWR_EN")
	)
	(segment
		(start 88.317832 -146.48815)
		(end 93.595952 -146.48815)
		(width 0.127)
		(layer "In5.Cu")
		(net "COMP_PWR_EN")
	)
	(segment
		(start 55.204106 -162.4584)
		(end 56.151272 -162.4584)
		(width 0.127)
		(layer "In5.Cu")
		(net "COMP_PWR_EN")
	)
	(segment
		(start 35.433 -155.2448)
		(end 35.433 -155.532836)
		(width 0.127)
		(layer "In5.Cu")
		(net "COMP_PWR_EN")
	)
	(segment
		(start 82.290412 -125.6284)
		(end 77.678788 -125.6284)
		(width 0.127)
		(layer "In5.Cu")
		(net "COMP_PWR_EN")
	)
	(segment
		(start 56.595772 -162.9029)
		(end 70.981062 -162.9029)
		(width 0.127)
		(layer "In5.Cu")
		(net "COMP_PWR_EN")
	)
	(segment
		(start 96.1644 -119.3292)
		(end 94.51975 -119.3292)
		(width 0.127)
		(layer "In5.Cu")
		(net "COMP_PWR_EN")
	)
	(segment
		(start 77.678788 -125.6284)
		(end 74.021188 -121.9708)
		(width 0.127)
		(layer "In5.Cu")
		(net "COMP_PWR_EN")
	)
	(segment
		(start 41.508934 -157.5054)
		(end 42.206672 -158.203138)
		(width 0.127)
		(layer "In5.Cu")
		(net "COMP_PWR_EN")
	)
	(segment
		(start 86.188296 -147.087336)
		(end 87.718646 -147.087336)
		(width 0.127)
		(layer "In5.Cu")
		(net "COMP_PWR_EN")
	)
	(segment
		(start 94.51975 -119.3292)
		(end 94.11335 -118.9228)
		(width 0.127)
		(layer "In5.Cu")
		(net "COMP_PWR_EN")
	)
	(segment
		(start 79.109316 -149.225)
		(end 80.800194 -149.225)
		(width 0.127)
		(layer "In5.Cu")
		(net "COMP_PWR_EN")
	)
	(segment
		(start 96.5454 -119.7102)
		(end 96.1644 -119.3292)
		(width 0.127)
		(layer "In5.Cu")
		(net "COMP_PWR_EN")
	)
	(segment
		(start 70.981062 -162.9029)
		(end 71.341742 -163.26358)
		(width 0.127)
		(layer "In5.Cu")
		(net "COMP_PWR_EN")
	)
	(segment
		(start 87.718646 -147.087336)
		(end 88.317832 -146.48815)
		(width 0.127)
		(layer "In5.Cu")
		(net "COMP_PWR_EN")
	)
	(segment
		(start 71.980298 -163.2712)
		(end 71.987918 -163.26358)
		(width 0.127)
		(layer "In5.Cu")
		(net "COMP_PWR_EN")
	)
	(segment
		(start 94.45371 -147.345908)
		(end 95.4278 -147.345908)
		(width 0.127)
		(layer "In5.Cu")
		(net "COMP_PWR_EN")
	)
	(segment
		(start 71.590662 -163.2712)
		(end 71.980298 -163.2712)
		(width 0.127)
		(layer "In5.Cu")
		(net "COMP_PWR_EN")
	)
	(segment
		(start 42.70248 -125.50648)
		(end 41.6814 -124.4854)
		(width 0.127)
		(layer "In5.Cu")
		(net "COMP_PWR_EN")
	)
	(segment
		(start 85.938106 -146.837146)
		(end 86.188296 -147.087336)
		(width 0.127)
		(layer "In5.Cu")
		(net "COMP_PWR_EN")
	)
	(segment
		(start 82.749136 -146.837146)
		(end 85.938106 -146.837146)
		(width 0.127)
		(layer "In5.Cu")
		(net "COMP_PWR_EN")
	)
	(segment
		(start 88.996012 -118.9228)
		(end 82.290412 -125.6284)
		(width 0.127)
		(layer "In5.Cu")
		(net "COMP_PWR_EN")
	)
	(segment
		(start 41.300146 -139.400534)
		(end 41.3004 -139.400534)
		(width 0.127)
		(layer "F.Cu")
		(net "CLKIN_24M_BMC")
	)
	(segment
		(start 36.046156 -132.915152)
		(end 36.046156 -133.15696)
		(width 0.127)
		(layer "F.Cu")
		(net "CLKIN_24M_BMC")
	)
	(segment
		(start 36.046156 -133.15696)
		(end 36.598098 -133.708902)
		(width 0.127)
		(layer "F.Cu")
		(net "CLKIN_24M_BMC")
	)
	(segment
		(start 41.3004 -139.400534)
		(end 41.699942 -139.800076)
		(width 0.127)
		(layer "F.Cu")
		(net "CLKIN_24M_BMC")
	)
	(via
		(at 36.598098 -133.708902)
		(size 0.508)
		(drill 0.254)
		(layers "F.Cu" "B.Cu")
		(net "CLKIN_24M_BMC")
	)
	(via
		(at 41.300146 -139.400534)
		(size 0.4572)
		(drill 0.2032)
		(layers "F.Cu" "B.Cu")
		(net "CLKIN_24M_BMC")
	)
	(segment
		(start 39.398194 -138.994134)
		(end 40.797734 -138.994134)
		(width 0.127)
		(layer "In2.Cu")
		(net "CLKIN_24M_BMC")
	)
	(segment
		(start 36.957 -136.55294)
		(end 39.398194 -138.994134)
		(width 0.127)
		(layer "In2.Cu")
		(net "CLKIN_24M_BMC")
	)
	(segment
		(start 40.797734 -138.994134)
		(end 41.204134 -139.400534)
		(width 0.127)
		(layer "In2.Cu")
		(net "CLKIN_24M_BMC")
	)
	(segment
		(start 41.204134 -139.400534)
		(end 41.300146 -139.400534)
		(width 0.127)
		(layer "In2.Cu")
		(net "CLKIN_24M_BMC")
	)
	(segment
		(start 36.598098 -133.708902)
		(end 36.957 -134.067804)
		(width 0.127)
		(layer "In2.Cu")
		(net "CLKIN_24M_BMC")
	)
	(segment
		(start 36.957 -134.067804)
		(end 36.957 -136.55294)
		(width 0.127)
		(layer "In2.Cu")
		(net "CLKIN_24M_BMC")
	)
	(segment
		(start 70.7136 -173.355)
		(end 70.0278 -173.355)
		(width 0.127)
		(layer "F.Cu")
		(net "BMC_TPM_RST_N")
	)
	(segment
		(start 69.5452 -173.8376)
		(end 69.5452 -174.3329)
		(width 0.127)
		(layer "F.Cu")
		(net "BMC_TPM_RST_N")
	)
	(segment
		(start 71.526908 -167.021002)
		(end 70.974458 -166.468552)
		(width 0.127)
		(layer "F.Cu")
		(net "BMC_TPM_RST_N")
	)
	(segment
		(start 69.7611 -163.721288)
		(end 69.7611 -165.716458)
		(width 0.127)
		(layer "F.Cu")
		(net "BMC_TPM_RST_N")
	)
	(segment
		(start 70.513194 -166.468552)
		(end 70.092824 -166.048182)
		(width 0.127)
		(layer "F.Cu")
		(net "BMC_TPM_RST_N")
	)
	(segment
		(start 71.9582 -171.7548)
		(end 71.0692 -172.6438)
		(width 0.127)
		(layer "F.Cu")
		(net "BMC_TPM_RST_N")
	)
	(segment
		(start 70.974458 -166.468552)
		(end 70.513194 -166.468552)
		(width 0.127)
		(layer "F.Cu")
		(net "BMC_TPM_RST_N")
	)
	(segment
		(start 71.9582 -167.452294)
		(end 71.9582 -171.7548)
		(width 0.127)
		(layer "F.Cu")
		(net "BMC_TPM_RST_N")
	)
	(segment
		(start 71.0692 -172.9994)
		(end 70.7136 -173.355)
		(width 0.127)
		(layer "F.Cu")
		(net "BMC_TPM_RST_N")
	)
	(segment
		(start 71.0692 -172.6438)
		(end 71.0692 -172.9994)
		(width 0.127)
		(layer "F.Cu")
		(net "BMC_TPM_RST_N")
	)
	(segment
		(start 70.0278 -173.355)
		(end 69.5452 -173.8376)
		(width 0.127)
		(layer "F.Cu")
		(net "BMC_TPM_RST_N")
	)
	(segment
		(start 69.7611 -165.716458)
		(end 70.092824 -166.048182)
		(width 0.127)
		(layer "F.Cu")
		(net "BMC_TPM_RST_N")
	)
	(segment
		(start 71.526908 -167.021002)
		(end 71.9582 -167.452294)
		(width 0.127)
		(layer "F.Cu")
		(net "BMC_TPM_RST_N")
	)
	(segment
		(start 69.7611 -162.756088)
		(end 69.7611 -163.721288)
		(width 0.127)
		(layer "F.Cu")
		(net "BMC_TPM_RST_N")
	)
	(via
		(at 71.526908 -167.021002)
		(size 0.6604)
		(drill 0.3302)
		(layers "F.Cu" "B.Cu")
		(net "BMC_TPM_RST_N")
	)
	(segment
		(start 39.200836 -118.1354)
		(end 39.150036 -118.1862)
		(width 0.127)
		(layer "F.Cu")
		(net "BMC_SPI_MOSI_R")
	)
	(segment
		(start 54.561232 -117.6782)
		(end 55.069232 -118.1862)
		(width 0.127)
		(layer "F.Cu")
		(net "BMC_SPI_MOSI_R")
	)
	(segment
		(start 39.150036 -118.1862)
		(end 31.56966 -118.1862)
		(width 0.127)
		(layer "F.Cu")
		(net "BMC_SPI_MOSI_R")
	)
	(segment
		(start 55.069232 -118.1862)
		(end 56.012334 -118.1862)
		(width 0.127)
		(layer "F.Cu")
		(net "BMC_SPI_MOSI_R")
	)
	(segment
		(start 56.19115 -118.1862)
		(end 56.012334 -118.1862)
		(width 0.127)
		(layer "F.Cu")
		(net "BMC_SPI_MOSI_R")
	)
	(via
		(at 39.200836 -118.1354)
		(size 0.508)
		(drill 0.254)
		(layers "F.Cu" "B.Cu")
		(net "BMC_SPI_MOSI_R")
	)
	(via
		(at 54.561232 -117.6782)
		(size 0.508)
		(drill 0.254)
		(layers "F.Cu" "B.Cu")
		(net "BMC_SPI_MOSI_R")
	)
	(segment
		(start 50.79746 -116.91874)
		(end 49.41316 -118.30304)
		(width 0.127)
		(layer "B.Cu")
		(net "BMC_SPI_MOSI_R")
	)
	(segment
		(start 53.29174 -116.91874)
		(end 50.79746 -116.91874)
		(width 0.127)
		(layer "B.Cu")
		(net "BMC_SPI_MOSI_R")
	)
	(segment
		(start 42.499534 -117.3099)
		(end 41.674034 -118.1354)
		(width 0.127)
		(layer "B.Cu")
		(net "BMC_SPI_MOSI_R")
	)
	(segment
		(start 49.41316 -118.30304)
		(end 46.7233 -118.30304)
		(width 0.127)
		(layer "B.Cu")
		(net "BMC_SPI_MOSI_R")
	)
	(segment
		(start 39.0144 -125.349)
		(end 39.0144 -126.365)
		(width 0.127)
		(layer "B.Cu")
		(net "BMC_SPI_MOSI_R")
	)
	(segment
		(start 40.3479 -123.4186)
		(end 39.5986 -124.1679)
		(width 0.127)
		(layer "B.Cu")
		(net "BMC_SPI_MOSI_R")
	)
	(segment
		(start 39.497 -128.651)
		(end 41.402 -130.556)
		(width 0.127)
		(layer "B.Cu")
		(net "BMC_SPI_MOSI_R")
	)
	(segment
		(start 39.497 -126.8476)
		(end 39.497 -128.651)
		(width 0.127)
		(layer "B.Cu")
		(net "BMC_SPI_MOSI_R")
	)
	(segment
		(start 41.6433 -130.556)
		(end 42.418 -131.3307)
		(width 0.127)
		(layer "B.Cu")
		(net "BMC_SPI_MOSI_R")
	)
	(segment
		(start 46.7233 -118.30304)
		(end 45.73016 -117.3099)
		(width 0.127)
		(layer "B.Cu")
		(net "BMC_SPI_MOSI_R")
	)
	(segment
		(start 39.200836 -120.137936)
		(end 40.3479 -121.285)
		(width 0.127)
		(layer "B.Cu")
		(net "BMC_SPI_MOSI_R")
	)
	(segment
		(start 41.674034 -118.1354)
		(end 39.200836 -118.1354)
		(width 0.127)
		(layer "B.Cu")
		(net "BMC_SPI_MOSI_R")
	)
	(segment
		(start 39.5986 -124.7648)
		(end 39.0144 -125.349)
		(width 0.127)
		(layer "B.Cu")
		(net "BMC_SPI_MOSI_R")
	)
	(segment
		(start 39.5986 -124.1679)
		(end 39.5986 -124.7648)
		(width 0.127)
		(layer "B.Cu")
		(net "BMC_SPI_MOSI_R")
	)
	(segment
		(start 39.200836 -118.1354)
		(end 39.200836 -120.137936)
		(width 0.127)
		(layer "B.Cu")
		(net "BMC_SPI_MOSI_R")
	)
	(segment
		(start 54.561232 -117.6782)
		(end 54.0512 -117.6782)
		(width 0.127)
		(layer "B.Cu")
		(net "BMC_SPI_MOSI_R")
	)
	(segment
		(start 45.73016 -117.3099)
		(end 42.499534 -117.3099)
		(width 0.127)
		(layer "B.Cu")
		(net "BMC_SPI_MOSI_R")
	)
	(segment
		(start 54.0512 -117.6782)
		(end 53.29174 -116.91874)
		(width 0.127)
		(layer "B.Cu")
		(net "BMC_SPI_MOSI_R")
	)
	(segment
		(start 39.0144 -126.365)
		(end 39.497 -126.8476)
		(width 0.127)
		(layer "B.Cu")
		(net "BMC_SPI_MOSI_R")
	)
	(segment
		(start 41.402 -130.556)
		(end 41.6433 -130.556)
		(width 0.127)
		(layer "B.Cu")
		(net "BMC_SPI_MOSI_R")
	)
	(segment
		(start 40.3479 -121.285)
		(end 40.3479 -123.4186)
		(width 0.127)
		(layer "B.Cu")
		(net "BMC_SPI_MOSI_R")
	)
	(segment
		(start 42.900092 -140.200126)
		(end 43.299888 -140.599922)
		(width 0.127)
		(layer "F.Cu")
		(net "BMC_SPI_MOSI")
	)
	(via
		(at 42.3164 -133.1214)
		(size 0.508)
		(drill 0.254)
		(layers "F.Cu" "B.Cu")
		(net "BMC_SPI_MOSI")
	)
	(via
		(at 42.900092 -140.200126)
		(size 0.4572)
		(drill 0.2032)
		(layers "F.Cu" "B.Cu")
		(net "BMC_SPI_MOSI")
	)
	(segment
		(start 42.418 -132.2197)
		(end 41.722548 -132.2197)
		(width 0.127)
		(layer "B.Cu")
		(net "BMC_SPI_MOSI")
	)
	(segment
		(start 41.722548 -132.2197)
		(end 41.656 -132.286248)
		(width 0.127)
		(layer "B.Cu")
		(net "BMC_SPI_MOSI")
	)
	(segment
		(start 42.418 -132.2197)
		(end 42.418 -132.6896)
		(width 0.127)
		(layer "B.Cu")
		(net "BMC_SPI_MOSI")
	)
	(segment
		(start 42.3164 -132.7912)
		(end 42.3164 -133.1214)
		(width 0.127)
		(layer "B.Cu")
		(net "BMC_SPI_MOSI")
	)
	(segment
		(start 42.418 -132.6896)
		(end 42.3164 -132.7912)
		(width 0.127)
		(layer "B.Cu")
		(net "BMC_SPI_MOSI")
	)
	(segment
		(start 41.656 -132.286248)
		(end 40.726106 -132.286248)
		(width 0.127)
		(layer "B.Cu")
		(net "BMC_SPI_MOSI")
	)
	(segment
		(start 42.900092 -139.953492)
		(end 42.740326 -139.793726)
		(width 0.127)
		(layer "In2.Cu")
		(net "BMC_SPI_MOSI")
	)
	(segment
		(start 42.506392 -138.44905)
		(end 42.260012 -138.20267)
		(width 0.127)
		(layer "In2.Cu")
		(net "BMC_SPI_MOSI")
	)
	(segment
		(start 42.260012 -138.20267)
		(end 41.944036 -138.20267)
		(width 0.127)
		(layer "In2.Cu")
		(net "BMC_SPI_MOSI")
	)
	(segment
		(start 42.506392 -139.563348)
		(end 42.506392 -138.44905)
		(width 0.127)
		(layer "In2.Cu")
		(net "BMC_SPI_MOSI")
	)
	(segment
		(start 41.713658 -137.972292)
		(end 41.713658 -137.97026)
		(width 0.127)
		(layer "In2.Cu")
		(net "BMC_SPI_MOSI")
	)
	(segment
		(start 41.944036 -138.20267)
		(end 41.713658 -137.972292)
		(width 0.127)
		(layer "In2.Cu")
		(net "BMC_SPI_MOSI")
	)
	(segment
		(start 42.900092 -140.200126)
		(end 42.900092 -139.953492)
		(width 0.127)
		(layer "In2.Cu")
		(net "BMC_SPI_MOSI")
	)
	(segment
		(start 41.706546 -133.731254)
		(end 42.3164 -133.1214)
		(width 0.127)
		(layer "In2.Cu")
		(net "BMC_SPI_MOSI")
	)
	(segment
		(start 41.706546 -137.963148)
		(end 41.706546 -133.731254)
		(width 0.127)
		(layer "In2.Cu")
		(net "BMC_SPI_MOSI")
	)
	(segment
		(start 42.73677 -139.793726)
		(end 42.506392 -139.563348)
		(width 0.127)
		(layer "In2.Cu")
		(net "BMC_SPI_MOSI")
	)
	(segment
		(start 42.740326 -139.793726)
		(end 42.73677 -139.793726)
		(width 0.127)
		(layer "In2.Cu")
		(net "BMC_SPI_MOSI")
	)
	(segment
		(start 41.713658 -137.97026)
		(end 41.706546 -137.963148)
		(width 0.127)
		(layer "In2.Cu")
		(net "BMC_SPI_MOSI")
	)
	(segment
		(start 43.196764 -124.374402)
		(end 44.345352 -124.374402)
		(width 0.127)
		(layer "F.Cu")
		(net "BMC_SPI_MISO_TPM")
	)
	(segment
		(start 41.764966 -125.8062)
		(end 43.196764 -124.374402)
		(width 0.127)
		(layer "F.Cu")
		(net "BMC_SPI_MISO_TPM")
	)
	(segment
		(start 41.184576 -125.8062)
		(end 41.764966 -125.8062)
		(width 0.127)
		(layer "F.Cu")
		(net "BMC_SPI_MISO_TPM")
	)
	(segment
		(start 67.148456 -125.8062)
		(end 65.806066 -125.8062)
		(width 0.127)
		(layer "F.Cu")
		(net "BMC_SPI_MISO_R")
	)
	(segment
		(start 65.62725 -125.8062)
		(end 65.806066 -125.8062)
		(width 0.127)
		(layer "F.Cu")
		(net "BMC_SPI_MISO_R")
	)
	(segment
		(start 67.732656 -125.222)
		(end 67.148456 -125.8062)
		(width 0.127)
		(layer "F.Cu")
		(net "BMC_SPI_MISO_R")
	)
	(via
		(at 67.732656 -125.222)
		(size 0.508)
		(drill 0.254)
		(layers "F.Cu" "B.Cu")
		(net "BMC_SPI_MISO_R")
	)
	(via
		(at 43.3832 -126.9492)
		(size 0.508)
		(drill 0.254)
		(layers "F.Cu" "B.Cu")
		(net "BMC_SPI_MISO_R")
	)
	(segment
		(start 43.3832 -127.7747)
		(end 43.3832 -126.9492)
		(width 0.127)
		(layer "B.Cu")
		(net "BMC_SPI_MISO_R")
	)
	(segment
		(start 51.349402 -126.926848)
		(end 47.519844 -126.926848)
		(width 0.127)
		(layer "In5.Cu")
		(net "BMC_SPI_MISO_R")
	)
	(segment
		(start 67.732656 -125.222)
		(end 66.7512 -125.222)
		(width 0.127)
		(layer "In5.Cu")
		(net "BMC_SPI_MISO_R")
	)
	(segment
		(start 55.009796 -125.0442)
		(end 54.043072 -126.010924)
		(width 0.127)
		(layer "In5.Cu")
		(net "BMC_SPI_MISO_R")
	)
	(segment
		(start 44.229782 -127.4191)
		(end 43.759882 -126.9492)
		(width 0.127)
		(layer "In5.Cu")
		(net "BMC_SPI_MISO_R")
	)
	(segment
		(start 47.519844 -126.926848)
		(end 47.027592 -127.4191)
		(width 0.127)
		(layer "In5.Cu")
		(net "BMC_SPI_MISO_R")
	)
	(segment
		(start 43.759882 -126.9492)
		(end 43.3832 -126.9492)
		(width 0.127)
		(layer "In5.Cu")
		(net "BMC_SPI_MISO_R")
	)
	(segment
		(start 66.7512 -125.222)
		(end 66.5734 -125.0442)
		(width 0.127)
		(layer "In5.Cu")
		(net "BMC_SPI_MISO_R")
	)
	(segment
		(start 54.043072 -126.010924)
		(end 52.265326 -126.010924)
		(width 0.127)
		(layer "In5.Cu")
		(net "BMC_SPI_MISO_R")
	)
	(segment
		(start 66.5734 -125.0442)
		(end 55.009796 -125.0442)
		(width 0.127)
		(layer "In5.Cu")
		(net "BMC_SPI_MISO_R")
	)
	(segment
		(start 52.265326 -126.010924)
		(end 51.349402 -126.926848)
		(width 0.127)
		(layer "In5.Cu")
		(net "BMC_SPI_MISO_R")
	)
	(segment
		(start 47.027592 -127.4191)
		(end 44.229782 -127.4191)
		(width 0.127)
		(layer "In5.Cu")
		(net "BMC_SPI_MISO_R")
	)
	(segment
		(start 43.4848 -129.49936)
		(end 43.891962 -129.092198)
		(width 0.127)
		(layer "F.Cu")
		(net "BMC_SPI_MISO")
	)
	(segment
		(start 44.099988 -139.800076)
		(end 43.699938 -139.400026)
		(width 0.127)
		(layer "F.Cu")
		(net "BMC_SPI_MISO")
	)
	(segment
		(start 43.891962 -129.092198)
		(end 43.891962 -126.160784)
		(width 0.127)
		(layer "F.Cu")
		(net "BMC_SPI_MISO")
	)
	(segment
		(start 43.891962 -126.160784)
		(end 44.345352 -125.707394)
		(width 0.127)
		(layer "F.Cu")
		(net "BMC_SPI_MISO")
	)
	(segment
		(start 44.345352 -125.707394)
		(end 44.345352 -125.263402)
		(width 0.127)
		(layer "F.Cu")
		(net "BMC_SPI_MISO")
	)
	(via
		(at 43.699938 -139.400026)
		(size 0.4572)
		(drill 0.2032)
		(layers "F.Cu" "B.Cu")
		(net "BMC_SPI_MISO")
	)
	(via
		(at 43.4848 -129.49936)
		(size 0.508)
		(drill 0.254)
		(layers "F.Cu" "B.Cu")
		(net "BMC_SPI_MISO")
	)
	(segment
		(start 43.3832 -129.39776)
		(end 43.4848 -129.49936)
		(width 0.127)
		(layer "B.Cu")
		(net "BMC_SPI_MISO")
	)
	(segment
		(start 44.4246 -128.6637)
		(end 43.3832 -128.6637)
		(width 0.127)
		(layer "B.Cu")
		(net "BMC_SPI_MISO")
	)
	(segment
		(start 43.3832 -128.6637)
		(end 43.3832 -129.39776)
		(width 0.127)
		(layer "B.Cu")
		(net "BMC_SPI_MISO")
	)
	(segment
		(start 44.093638 -134.395718)
		(end 44.093638 -139.006326)
		(width 0.127)
		(layer "In2.Cu")
		(net "BMC_SPI_MISO")
	)
	(segment
		(start 43.4848 -129.49936)
		(end 43.8658 -129.88036)
		(width 0.127)
		(layer "In2.Cu")
		(net "BMC_SPI_MISO")
	)
	(segment
		(start 43.31081 -133.61289)
		(end 44.093638 -134.395718)
		(width 0.127)
		(layer "In2.Cu")
		(net "BMC_SPI_MISO")
	)
	(segment
		(start 44.093638 -139.006326)
		(end 43.699938 -139.400026)
		(width 0.127)
		(layer "In2.Cu")
		(net "BMC_SPI_MISO")
	)
	(segment
		(start 43.31081 -131.61899)
		(end 43.31081 -133.61289)
		(width 0.127)
		(layer "In2.Cu")
		(net "BMC_SPI_MISO")
	)
	(segment
		(start 43.8658 -131.064)
		(end 43.31081 -131.61899)
		(width 0.127)
		(layer "In2.Cu")
		(net "BMC_SPI_MISO")
	)
	(segment
		(start 43.8658 -129.88036)
		(end 43.8658 -131.064)
		(width 0.127)
		(layer "In2.Cu")
		(net "BMC_SPI_MISO")
	)
	(segment
		(start 33.085786 -116.9162)
		(end 33.679892 -117.510306)
		(width 0.127)
		(layer "F.Cu")
		(net "BMC_SPI_CLK_R")
	)
	(segment
		(start 56.012334 -116.9162)
		(end 54.14899 -116.9162)
		(width 0.127)
		(layer "F.Cu")
		(net "BMC_SPI_CLK_R")
	)
	(segment
		(start 31.56966 -116.9162)
		(end 33.085786 -116.9162)
		(width 0.127)
		(layer "F.Cu")
		(net "BMC_SPI_CLK_R")
	)
	(segment
		(start 54.14899 -116.9162)
		(end 54.142386 -116.922804)
		(width 0.127)
		(layer "F.Cu")
		(net "BMC_SPI_CLK_R")
	)
	(segment
		(start 32.2453 -135.7884)
		(end 31.2928 -135.7884)
		(width 0.127)
		(layer "F.Cu")
		(net "BMC_SPI_CLK_R")
	)
	(segment
		(start 56.19115 -116.9162)
		(end 56.012334 -116.9162)
		(width 0.127)
		(layer "F.Cu")
		(net "BMC_SPI_CLK_R")
	)
	(segment
		(start 33.679892 -117.510306)
		(end 33.725358 -117.510306)
		(width 0.127)
		(layer "F.Cu")
		(net "BMC_SPI_CLK_R")
	)
	(via
		(at 31.2928 -135.7884)
		(size 0.508)
		(drill 0.254)
		(layers "F.Cu" "B.Cu")
		(net "BMC_SPI_CLK_R")
	)
	(via
		(at 33.725358 -117.510306)
		(size 0.508)
		(drill 0.254)
		(layers "F.Cu" "B.Cu")
		(net "BMC_SPI_CLK_R")
	)
	(via
		(at 54.142386 -116.922804)
		(size 0.508)
		(drill 0.254)
		(layers "F.Cu" "B.Cu")
		(net "BMC_SPI_CLK_R")
	)
	(segment
		(start 48.552862 -116.8019)
		(end 49.005744 -116.349018)
		(width 0.127)
		(layer "B.Cu")
		(net "BMC_SPI_CLK_R")
	)
	(segment
		(start 41.265348 -117.510814)
		(end 41.974262 -116.8019)
		(width 0.127)
		(layer "B.Cu")
		(net "BMC_SPI_CLK_R")
	)
	(segment
		(start 41.974262 -116.8019)
		(end 48.552862 -116.8019)
		(width 0.127)
		(layer "B.Cu")
		(net "BMC_SPI_CLK_R")
	)
	(segment
		(start 33.725358 -117.510306)
		(end 33.725866 -117.510814)
		(width 0.127)
		(layer "B.Cu")
		(net "BMC_SPI_CLK_R")
	)
	(segment
		(start 49.005744 -116.349018)
		(end 53.560218 -116.349018)
		(width 0.127)
		(layer "B.Cu")
		(net "BMC_SPI_CLK_R")
	)
	(segment
		(start 53.560218 -116.349018)
		(end 54.134004 -116.922804)
		(width 0.127)
		(layer "B.Cu")
		(net "BMC_SPI_CLK_R")
	)
	(segment
		(start 33.725866 -117.510814)
		(end 41.265348 -117.510814)
		(width 0.127)
		(layer "B.Cu")
		(net "BMC_SPI_CLK_R")
	)
	(segment
		(start 54.134004 -116.922804)
		(end 54.142386 -116.922804)
		(width 0.127)
		(layer "B.Cu")
		(net "BMC_SPI_CLK_R")
	)
	(segment
		(start 36.178998 -132.722874)
		(end 36.178998 -134.102602)
		(width 0.127)
		(layer "In2.Cu")
		(net "BMC_SPI_CLK_R")
	)
	(segment
		(start 36.178998 -134.102602)
		(end 35.343592 -134.938008)
		(width 0.127)
		(layer "In2.Cu")
		(net "BMC_SPI_CLK_R")
	)
	(segment
		(start 33.49117 -118.918736)
		(end 37.3888 -122.816366)
		(width 0.127)
		(layer "In2.Cu")
		(net "BMC_SPI_CLK_R")
	)
	(segment
		(start 37.3761 -123.909582)
		(end 37.3761 -124.299218)
		(width 0.127)
		(layer "In2.Cu")
		(net "BMC_SPI_CLK_R")
	)
	(segment
		(start 37.3888 -125.557788)
		(end 37.78885 -125.957838)
		(width 0.127)
		(layer "In2.Cu")
		(net "BMC_SPI_CLK_R")
	)
	(segment
		(start 35.343592 -134.938008)
		(end 34.547048 -134.938008)
		(width 0.127)
		(layer "In2.Cu")
		(net "BMC_SPI_CLK_R")
	)
	(segment
		(start 36.53282 -132.369052)
		(end 36.178998 -132.722874)
		(width 0.127)
		(layer "In2.Cu")
		(net "BMC_SPI_CLK_R")
	)
	(segment
		(start 37.78885 -128.65735)
		(end 36.53282 -129.91338)
		(width 0.127)
		(layer "In2.Cu")
		(net "BMC_SPI_CLK_R")
	)
	(segment
		(start 34.547048 -134.938008)
		(end 33.747456 -135.7376)
		(width 0.127)
		(layer "In2.Cu")
		(net "BMC_SPI_CLK_R")
	)
	(segment
		(start 33.49117 -117.744494)
		(end 33.49117 -118.918736)
		(width 0.127)
		(layer "In2.Cu")
		(net "BMC_SPI_CLK_R")
	)
	(segment
		(start 33.747456 -135.7376)
		(end 31.3436 -135.7376)
		(width 0.127)
		(layer "In2.Cu")
		(net "BMC_SPI_CLK_R")
	)
	(segment
		(start 37.3761 -124.299218)
		(end 37.3888 -124.311918)
		(width 0.127)
		(layer "In2.Cu")
		(net "BMC_SPI_CLK_R")
	)
	(segment
		(start 31.3436 -135.7376)
		(end 31.2928 -135.7884)
		(width 0.127)
		(layer "In2.Cu")
		(net "BMC_SPI_CLK_R")
	)
	(segment
		(start 37.3888 -124.311918)
		(end 37.3888 -125.557788)
		(width 0.127)
		(layer "In2.Cu")
		(net "BMC_SPI_CLK_R")
	)
	(segment
		(start 33.725358 -117.510306)
		(end 33.49117 -117.744494)
		(width 0.127)
		(layer "In2.Cu")
		(net "BMC_SPI_CLK_R")
	)
	(segment
		(start 37.78885 -125.957838)
		(end 37.78885 -128.65735)
		(width 0.127)
		(layer "In2.Cu")
		(net "BMC_SPI_CLK_R")
	)
	(segment
		(start 37.3888 -122.816366)
		(end 37.3888 -123.896882)
		(width 0.127)
		(layer "In2.Cu")
		(net "BMC_SPI_CLK_R")
	)
	(segment
		(start 36.53282 -129.91338)
		(end 36.53282 -132.369052)
		(width 0.127)
		(layer "In2.Cu")
		(net "BMC_SPI_CLK_R")
	)
	(segment
		(start 37.3888 -123.896882)
		(end 37.3761 -123.909582)
		(width 0.127)
		(layer "In2.Cu")
		(net "BMC_SPI_CLK_R")
	)
	(segment
		(start 37.823648 -139.342876)
		(end 39.642796 -139.342876)
		(width 0.127)
		(layer "F.Cu")
		(net "BMC_SPI_CLK")
	)
	(segment
		(start 34.181034 -135.1534)
		(end 35.306 -135.1534)
		(width 0.127)
		(layer "F.Cu")
		(net "BMC_SPI_CLK")
	)
	(segment
		(start 39.642796 -139.342876)
		(end 40.099996 -139.800076)
		(width 0.127)
		(layer "F.Cu")
		(net "BMC_SPI_CLK")
	)
	(segment
		(start 33.1343 -134.6962)
		(end 33.723834 -134.6962)
		(width 0.127)
		(layer "F.Cu")
		(net "BMC_SPI_CLK")
	)
	(segment
		(start 36.210494 -136.057894)
		(end 36.210494 -137.729722)
		(width 0.127)
		(layer "F.Cu")
		(net "BMC_SPI_CLK")
	)
	(segment
		(start 36.210494 -137.729722)
		(end 37.823648 -139.342876)
		(width 0.127)
		(layer "F.Cu")
		(net "BMC_SPI_CLK")
	)
	(segment
		(start 33.723834 -134.6962)
		(end 34.181034 -135.1534)
		(width 0.127)
		(layer "F.Cu")
		(net "BMC_SPI_CLK")
	)
	(segment
		(start 35.306 -135.1534)
		(end 36.210494 -136.057894)
		(width 0.127)
		(layer "F.Cu")
		(net "BMC_SPI_CLK")
	)
	(segment
		(start 33.1343 -135.7884)
		(end 33.1343 -134.6962)
		(width 0.127)
		(layer "F.Cu")
		(net "BMC_SPI_CLK")
	)
	(segment
		(start 45.331126 -131.557522)
		(end 45.331126 -130.487674)
		(width 0.127)
		(layer "F.Cu")
		(net "BMC_SMB2_DAT_TP")
	)
	(segment
		(start 45.331126 -130.487674)
		(end 45.4152 -130.4036)
		(width 0.127)
		(layer "F.Cu")
		(net "BMC_SMB2_DAT_TP")
	)
	(segment
		(start 47.8155 -124.206)
		(end 47.8155 -123.953524)
		(width 0.127)
		(layer "B.Cu")
		(net "BMC_SMB2_CLK_TP")
	)
	(segment
		(start 47.8155 -123.953524)
		(end 46.9392 -123.077224)
		(width 0.127)
		(layer "B.Cu")
		(net "BMC_SMB2_CLK_TP")
	)
	(segment
		(start 138.393424 -42.428414)
		(end 138.021822 -42.800016)
		(width 0.127)
		(layer "F.Cu")
		(net "BMC_RMT_HEARTBEAT")
	)
	(segment
		(start 137.3632 -28.321)
		(end 138.393424 -29.351224)
		(width 0.127)
		(layer "F.Cu")
		(net "BMC_RMT_HEARTBEAT")
	)
	(segment
		(start 138.393424 -29.351224)
		(end 138.393424 -42.428414)
		(width 0.127)
		(layer "F.Cu")
		(net "BMC_RMT_HEARTBEAT")
	)
	(segment
		(start 138.021822 -42.800016)
		(end 137.700004 -42.800016)
		(width 0.127)
		(layer "F.Cu")
		(net "BMC_RMT_HEARTBEAT")
	)
	(via
		(at 41.7576 -154.7368)
		(size 0.508)
		(drill 0.254)
		(layers "F.Cu" "B.Cu")
		(net "BMC_RMT_HEARTBEAT")
	)
	(via
		(at 137.3632 -28.321)
		(size 0.508)
		(drill 0.254)
		(layers "F.Cu" "B.Cu")
		(net "BMC_RMT_HEARTBEAT")
	)
	(via
		(at 81.640934 -153.73731)
		(size 0.508)
		(drill 0.254)
		(layers "F.Cu" "B.Cu")
		(net "BMC_RMT_HEARTBEAT")
	)
	(via
		(at 40.513 -155.5242)
		(size 0.6096)
		(drill 0.3048)
		(layers "F.Cu" "B.Cu")
		(net "BMC_RMT_HEARTBEAT")
	)
	(segment
		(start 40.513 -155.565602)
		(end 39.456614 -156.621988)
		(width 0.127)
		(layer "B.Cu")
		(net "BMC_RMT_HEARTBEAT")
	)
	(segment
		(start 40.513 -155.5242)
		(end 40.513 -155.565602)
		(width 0.127)
		(layer "B.Cu")
		(net "BMC_RMT_HEARTBEAT")
	)
	(segment
		(start 41.3004 -154.7368)
		(end 41.7576 -154.7368)
		(width 0.127)
		(layer "B.Cu")
		(net "BMC_RMT_HEARTBEAT")
	)
	(segment
		(start 40.513 -155.5242)
		(end 41.3004 -154.7368)
		(width 0.127)
		(layer "B.Cu")
		(net "BMC_RMT_HEARTBEAT")
	)
	(segment
		(start 137.3632 -28.321)
		(end 133.1214 -24.0792)
		(width 0.127)
		(layer "In2.Cu")
		(net "BMC_RMT_HEARTBEAT")
	)
	(segment
		(start 81.3816 -130.6576)
		(end 81.3816 -133.7564)
		(width 0.127)
		(layer "In2.Cu")
		(net "BMC_RMT_HEARTBEAT")
	)
	(segment
		(start 85.6361 -93.2561)
		(end 84.285582 -94.606618)
		(width 0.127)
		(layer "In2.Cu")
		(net "BMC_RMT_HEARTBEAT")
	)
	(segment
		(start 81.292446 -146.16049)
		(end 81.292446 -146.475958)
		(width 0.127)
		(layer "In2.Cu")
		(net "BMC_RMT_HEARTBEAT")
	)
	(segment
		(start 97.669604 -11.8872)
		(end 97.078038 -11.295634)
		(width 0.127)
		(layer "In2.Cu")
		(net "BMC_RMT_HEARTBEAT")
	)
	(segment
		(start 133.1214 -24.0792)
		(end 126.472696 -24.0792)
		(width 0.127)
		(layer "In2.Cu")
		(net "BMC_RMT_HEARTBEAT")
	)
	(segment
		(start 81.8007 -10.302748)
		(end 81.800954 -10.303002)
		(width 0.127)
		(layer "In2.Cu")
		(net "BMC_RMT_HEARTBEAT")
	)
	(segment
		(start 83.557364 -34.482786)
		(end 83.557364 -64.405764)
		(width 0.127)
		(layer "In2.Cu")
		(net "BMC_RMT_HEARTBEAT")
	)
	(segment
		(start 84.285328 -99.050856)
		(end 84.285328 -99.366324)
		(width 0.127)
		(layer "In2.Cu")
		(net "BMC_RMT_HEARTBEAT")
	)
	(segment
		(start 74.828654 -117.857778)
		(end 74.828654 -123.0122)
		(width 0.127)
		(layer "In2.Cu")
		(net "BMC_RMT_HEARTBEAT")
	)
	(segment
		(start 84.004404 -7.783576)
		(end 81.8007 -9.98728)
		(width 0.127)
		(layer "In2.Cu")
		(net "BMC_RMT_HEARTBEAT")
	)
	(segment
		(start 81.1276 -136.842246)
		(end 81.775554 -137.4902)
		(width 0.127)
		(layer "In2.Cu")
		(net "BMC_RMT_HEARTBEAT")
	)
	(segment
		(start 81.292446 -146.475958)
		(end 81.2927 -146.476212)
		(width 0.127)
		(layer "In2.Cu")
		(net "BMC_RMT_HEARTBEAT")
	)
	(segment
		(start 97.078038 -11.295634)
		(end 97.078038 -10.693908)
		(width 0.127)
		(layer "In2.Cu")
		(net "BMC_RMT_HEARTBEAT")
	)
	(segment
		(start 97.669604 -13.061188)
		(end 97.669604 -11.8872)
		(width 0.127)
		(layer "In2.Cu")
		(net "BMC_RMT_HEARTBEAT")
	)
	(segment
		(start 81.3816 -133.7564)
		(end 81.1276 -134.0104)
		(width 0.127)
		(layer "In2.Cu")
		(net "BMC_RMT_HEARTBEAT")
	)
	(segment
		(start 118.619524 -18.0848)
		(end 116.098828 -15.564104)
		(width 0.127)
		(layer "In2.Cu")
		(net "BMC_RMT_HEARTBEAT")
	)
	(segment
		(start 81.8007 -9.98728)
		(end 81.8007 -10.302748)
		(width 0.127)
		(layer "In2.Cu")
		(net "BMC_RMT_HEARTBEAT")
	)
	(segment
		(start 97.078292 -10.378186)
		(end 94.483682 -7.783576)
		(width 0.127)
		(layer "In2.Cu")
		(net "BMC_RMT_HEARTBEAT")
	)
	(segment
		(start 80.1624 -128.345946)
		(end 80.1624 -129.4384)
		(width 0.127)
		(layer "In2.Cu")
		(net "BMC_RMT_HEARTBEAT")
	)
	(segment
		(start 86.9823 -102.063296)
		(end 86.9823 -107.931204)
		(width 0.127)
		(layer "In2.Cu")
		(net "BMC_RMT_HEARTBEAT")
	)
	(segment
		(start 81.143602 -114.741198)
		(end 77.945234 -114.741198)
		(width 0.127)
		(layer "In2.Cu")
		(net "BMC_RMT_HEARTBEAT")
	)
	(segment
		(start 84.7217 -111.1631)
		(end 81.143602 -114.741198)
		(width 0.127)
		(layer "In2.Cu")
		(net "BMC_RMT_HEARTBEAT")
	)
	(segment
		(start 81.2927 -146.476212)
		(end 81.2927 -151.906732)
		(width 0.127)
		(layer "In2.Cu")
		(net "BMC_RMT_HEARTBEAT")
	)
	(segment
		(start 81.775554 -145.677382)
		(end 81.292446 -146.16049)
		(width 0.127)
		(layer "In2.Cu")
		(net "BMC_RMT_HEARTBEAT")
	)
	(segment
		(start 86.9823 -107.931204)
		(end 84.7217 -110.191804)
		(width 0.127)
		(layer "In2.Cu")
		(net "BMC_RMT_HEARTBEAT")
	)
	(segment
		(start 97.078292 -10.693654)
		(end 97.078292 -10.378186)
		(width 0.127)
		(layer "In2.Cu")
		(net "BMC_RMT_HEARTBEAT")
	)
	(segment
		(start 116.098828 -15.564104)
		(end 100.17252 -15.564104)
		(width 0.127)
		(layer "In2.Cu")
		(net "BMC_RMT_HEARTBEAT")
	)
	(segment
		(start 126.472696 -24.0792)
		(end 120.478296 -18.0848)
		(width 0.127)
		(layer "In2.Cu")
		(net "BMC_RMT_HEARTBEAT")
	)
	(segment
		(start 81.800954 -32.726376)
		(end 83.557364 -34.482786)
		(width 0.127)
		(layer "In2.Cu")
		(net "BMC_RMT_HEARTBEAT")
	)
	(segment
		(start 85.6361 -66.4845)
		(end 85.6361 -93.2561)
		(width 0.127)
		(layer "In2.Cu")
		(net "BMC_RMT_HEARTBEAT")
	)
	(segment
		(start 84.7217 -110.191804)
		(end 84.7217 -111.1631)
		(width 0.127)
		(layer "In2.Cu")
		(net "BMC_RMT_HEARTBEAT")
	)
	(segment
		(start 80.1624 -129.4384)
		(end 81.3816 -130.6576)
		(width 0.127)
		(layer "In2.Cu")
		(net "BMC_RMT_HEARTBEAT")
	)
	(segment
		(start 84.285582 -94.606618)
		(end 84.285582 -99.050602)
		(width 0.127)
		(layer "In2.Cu")
		(net "BMC_RMT_HEARTBEAT")
	)
	(segment
		(start 81.545176 -152.159208)
		(end 81.545176 -153.641552)
		(width 0.127)
		(layer "In2.Cu")
		(net "BMC_RMT_HEARTBEAT")
	)
	(segment
		(start 120.478296 -18.0848)
		(end 118.619524 -18.0848)
		(width 0.127)
		(layer "In2.Cu")
		(net "BMC_RMT_HEARTBEAT")
	)
	(segment
		(start 81.1276 -134.0104)
		(end 81.1276 -136.842246)
		(width 0.127)
		(layer "In2.Cu")
		(net "BMC_RMT_HEARTBEAT")
	)
	(segment
		(start 81.545176 -153.641552)
		(end 81.640934 -153.73731)
		(width 0.127)
		(layer "In2.Cu")
		(net "BMC_RMT_HEARTBEAT")
	)
	(segment
		(start 81.800954 -10.303002)
		(end 81.800954 -32.726376)
		(width 0.127)
		(layer "In2.Cu")
		(net "BMC_RMT_HEARTBEAT")
	)
	(segment
		(start 84.285582 -99.050602)
		(end 84.285328 -99.050856)
		(width 0.127)
		(layer "In2.Cu")
		(net "BMC_RMT_HEARTBEAT")
	)
	(segment
		(start 81.2927 -151.906732)
		(end 81.545176 -152.159208)
		(width 0.127)
		(layer "In2.Cu")
		(net "BMC_RMT_HEARTBEAT")
	)
	(segment
		(start 83.557364 -64.405764)
		(end 85.6361 -66.4845)
		(width 0.127)
		(layer "In2.Cu")
		(net "BMC_RMT_HEARTBEAT")
	)
	(segment
		(start 94.483682 -7.783576)
		(end 84.004404 -7.783576)
		(width 0.127)
		(layer "In2.Cu")
		(net "BMC_RMT_HEARTBEAT")
	)
	(segment
		(start 84.285328 -99.366324)
		(end 86.9823 -102.063296)
		(width 0.127)
		(layer "In2.Cu")
		(net "BMC_RMT_HEARTBEAT")
	)
	(segment
		(start 74.828654 -123.0122)
		(end 80.1624 -128.345946)
		(width 0.127)
		(layer "In2.Cu")
		(net "BMC_RMT_HEARTBEAT")
	)
	(segment
		(start 81.775554 -137.4902)
		(end 81.775554 -145.677382)
		(width 0.127)
		(layer "In2.Cu")
		(net "BMC_RMT_HEARTBEAT")
	)
	(segment
		(start 97.078038 -10.693908)
		(end 97.078292 -10.693654)
		(width 0.127)
		(layer "In2.Cu")
		(net "BMC_RMT_HEARTBEAT")
	)
	(segment
		(start 77.945234 -114.741198)
		(end 74.828654 -117.857778)
		(width 0.127)
		(layer "In2.Cu")
		(net "BMC_RMT_HEARTBEAT")
	)
	(segment
		(start 100.17252 -15.564104)
		(end 97.669604 -13.061188)
		(width 0.127)
		(layer "In2.Cu")
		(net "BMC_RMT_HEARTBEAT")
	)
	(segment
		(start 54.222142 -155.3972)
		(end 61.3918 -155.3972)
		(width 0.127)
		(layer "In5.Cu")
		(net "BMC_RMT_HEARTBEAT")
	)
	(segment
		(start 71.802752 -151.513286)
		(end 72.122792 -151.833326)
		(width 0.127)
		(layer "In5.Cu")
		(net "BMC_RMT_HEARTBEAT")
	)
	(segment
		(start 61.3918 -155.3972)
		(end 63.643002 -153.145998)
		(width 0.127)
		(layer "In5.Cu")
		(net "BMC_RMT_HEARTBEAT")
	)
	(segment
		(start 75.820778 -152.7175)
		(end 80.837024 -152.7175)
		(width 0.127)
		(layer "In5.Cu")
		(net "BMC_RMT_HEARTBEAT")
	)
	(segment
		(start 81.640934 -153.52141)
		(end 81.640934 -153.73731)
		(width 0.127)
		(layer "In5.Cu")
		(net "BMC_RMT_HEARTBEAT")
	)
	(segment
		(start 63.643002 -152.202388)
		(end 64.332104 -151.513286)
		(width 0.127)
		(layer "In5.Cu")
		(net "BMC_RMT_HEARTBEAT")
	)
	(segment
		(start 80.837024 -152.7175)
		(end 81.640934 -153.52141)
		(width 0.127)
		(layer "In5.Cu")
		(net "BMC_RMT_HEARTBEAT")
	)
	(segment
		(start 64.332104 -151.513286)
		(end 71.802752 -151.513286)
		(width 0.127)
		(layer "In5.Cu")
		(net "BMC_RMT_HEARTBEAT")
	)
	(segment
		(start 63.643002 -153.145998)
		(end 63.643002 -152.202388)
		(width 0.127)
		(layer "In5.Cu")
		(net "BMC_RMT_HEARTBEAT")
	)
	(segment
		(start 53.904642 -155.0797)
		(end 54.222142 -155.3972)
		(width 0.127)
		(layer "In5.Cu")
		(net "BMC_RMT_HEARTBEAT")
	)
	(segment
		(start 41.7576 -154.7368)
		(end 42.1005 -155.0797)
		(width 0.127)
		(layer "In5.Cu")
		(net "BMC_RMT_HEARTBEAT")
	)
	(segment
		(start 42.1005 -155.0797)
		(end 53.904642 -155.0797)
		(width 0.127)
		(layer "In5.Cu")
		(net "BMC_RMT_HEARTBEAT")
	)
	(segment
		(start 74.936604 -151.833326)
		(end 75.820778 -152.7175)
		(width 0.127)
		(layer "In5.Cu")
		(net "BMC_RMT_HEARTBEAT")
	)
	(segment
		(start 72.122792 -151.833326)
		(end 74.936604 -151.833326)
		(width 0.127)
		(layer "In5.Cu")
		(net "BMC_RMT_HEARTBEAT")
	)
	(segment
		(start 42.900092 -150.599902)
		(end 42.900092 -150.599648)
		(width 0.127)
		(layer "F.Cu")
		(net "BMC_RMT_HB")
	)
	(segment
		(start 42.900092 -150.599648)
		(end 43.299888 -150.199852)
		(width 0.127)
		(layer "F.Cu")
		(net "BMC_RMT_HB")
	)
	(via
		(at 40.662352 -154.4574)
		(size 0.6096)
		(drill 0.3048)
		(layers "F.Cu" "B.Cu")
		(net "BMC_RMT_HB")
	)
	(via
		(at 42.900092 -150.599902)
		(size 0.4572)
		(drill 0.2032)
		(layers "F.Cu" "B.Cu")
		(net "BMC_RMT_HB")
	)
	(segment
		(start 42.900092 -150.599902)
		(end 42.900092 -150.84298)
		(width 0.127)
		(layer "B.Cu")
		(net "BMC_RMT_HB")
	)
	(segment
		(start 42.506392 -151.550624)
		(end 42.263314 -151.793702)
		(width 0.127)
		(layer "B.Cu")
		(net "BMC_RMT_HB")
	)
	(segment
		(start 41.706292 -152.03678)
		(end 41.706292 -152.848564)
		(width 0.127)
		(layer "B.Cu")
		(net "BMC_RMT_HB")
	)
	(segment
		(start 40.662352 -154.4574)
		(end 40.662352 -154.638248)
		(width 0.127)
		(layer "B.Cu")
		(net "BMC_RMT_HB")
	)
	(segment
		(start 41.706292 -152.848564)
		(end 40.662352 -153.892504)
		(width 0.127)
		(layer "B.Cu")
		(net "BMC_RMT_HB")
	)
	(segment
		(start 42.506392 -151.23668)
		(end 42.506392 -151.550624)
		(width 0.127)
		(layer "B.Cu")
		(net "BMC_RMT_HB")
	)
	(segment
		(start 42.900092 -150.84298)
		(end 42.506392 -151.23668)
		(width 0.127)
		(layer "B.Cu")
		(net "BMC_RMT_HB")
	)
	(segment
		(start 40.662352 -154.638248)
		(end 39.567612 -155.732988)
		(width 0.127)
		(layer "B.Cu")
		(net "BMC_RMT_HB")
	)
	(segment
		(start 41.94937 -151.793702)
		(end 41.706292 -152.03678)
		(width 0.127)
		(layer "B.Cu")
		(net "BMC_RMT_HB")
	)
	(segment
		(start 39.567612 -155.732988)
		(end 39.456614 -155.732988)
		(width 0.127)
		(layer "B.Cu")
		(net "BMC_RMT_HB")
	)
	(segment
		(start 40.662352 -153.892504)
		(end 40.662352 -154.4574)
		(width 0.127)
		(layer "B.Cu")
		(net "BMC_RMT_HB")
	)
	(segment
		(start 42.263314 -151.793702)
		(end 41.94937 -151.793702)
		(width 0.127)
		(layer "B.Cu")
		(net "BMC_RMT_HB")
	)
	(segment
		(start 54.899814 -152.199848)
		(end 54.500018 -152.599644)
		(width 0.127)
		(layer "F.Cu")
		(net "BMC_RGMII_C2_C3_D1_D2_E6")
	)
	(segment
		(start 53.699918 -152.599898)
		(end 54.500018 -152.599898)
		(width 0.127)
		(layer "F.Cu")
		(net "BMC_RGMII_C2_C3_D1_D2_E6")
	)
	(segment
		(start 53.699918 -153.399998)
		(end 53.699918 -152.599898)
		(width 0.127)
		(layer "F.Cu")
		(net "BMC_RGMII_C2_C3_D1_D2_E6")
	)
	(segment
		(start 52.499768 -149.799802)
		(end 52.500022 -149.799802)
		(width 0.127)
		(layer "F.Cu")
		(net "BMC_RGMII_C2_C3_D1_D2_E6")
	)
	(segment
		(start 54.500018 -151.800052)
		(end 54.899814 -152.199848)
		(width 0.127)
		(layer "F.Cu")
		(net "BMC_RGMII_C2_C3_D1_D2_E6")
	)
	(segment
		(start 54.500018 -152.599644)
		(end 54.500018 -152.599898)
		(width 0.127)
		(layer "F.Cu")
		(net "BMC_RGMII_C2_C3_D1_D2_E6")
	)
	(segment
		(start 52.500022 -149.799802)
		(end 52.899818 -149.400006)
		(width 0.127)
		(layer "F.Cu")
		(net "BMC_RGMII_C2_C3_D1_D2_E6")
	)
	(via
		(at 52.499768 -149.799802)
		(size 0.4572)
		(drill 0.2032)
		(layers "F.Cu" "B.Cu")
		(net "BMC_RGMII_C2_C3_D1_D2_E6")
	)
	(via
		(at 56.134 -152.8826)
		(size 0.6096)
		(drill 0.3048)
		(layers "F.Cu" "B.Cu")
		(net "BMC_RGMII_C2_C3_D1_D2_E6")
	)
	(via
		(at 54.899814 -152.199848)
		(size 0.4572)
		(drill 0.2032)
		(layers "F.Cu" "B.Cu")
		(net "BMC_RGMII_C2_C3_D1_D2_E6")
	)
	(segment
		(start 57.3786 -154.4701)
		(end 57.3786 -153.89987)
		(width 0.127)
		(layer "B.Cu")
		(net "BMC_RGMII_C2_C3_D1_D2_E6")
	)
	(segment
		(start 56.36133 -152.8826)
		(end 56.134 -152.8826)
		(width 0.127)
		(layer "B.Cu")
		(net "BMC_RGMII_C2_C3_D1_D2_E6")
	)
	(segment
		(start 52.905914 -150.763224)
		(end 52.905914 -150.314914)
		(width 0.127)
		(layer "B.Cu")
		(net "BMC_RGMII_C2_C3_D1_D2_E6")
	)
	(segment
		(start 54.899814 -152.199848)
		(end 54.663848 -152.199848)
		(width 0.127)
		(layer "B.Cu")
		(net "BMC_RGMII_C2_C3_D1_D2_E6")
	)
	(segment
		(start 52.499768 -149.908768)
		(end 52.499768 -149.799802)
		(width 0.127)
		(layer "B.Cu")
		(net "BMC_RGMII_C2_C3_D1_D2_E6")
	)
	(segment
		(start 57.3786 -153.89987)
		(end 56.36133 -152.8826)
		(width 0.127)
		(layer "B.Cu")
		(net "BMC_RGMII_C2_C3_D1_D2_E6")
	)
	(segment
		(start 55.582566 -152.8826)
		(end 54.899814 -152.199848)
		(width 0.127)
		(layer "B.Cu")
		(net "BMC_RGMII_C2_C3_D1_D2_E6")
	)
	(segment
		(start 53.457602 -150.993602)
		(end 53.136292 -150.993602)
		(width 0.127)
		(layer "B.Cu")
		(net "BMC_RGMII_C2_C3_D1_D2_E6")
	)
	(segment
		(start 53.136292 -150.993602)
		(end 52.905914 -150.763224)
		(width 0.127)
		(layer "B.Cu")
		(net "BMC_RGMII_C2_C3_D1_D2_E6")
	)
	(segment
		(start 56.134 -152.8826)
		(end 55.582566 -152.8826)
		(width 0.127)
		(layer "B.Cu")
		(net "BMC_RGMII_C2_C3_D1_D2_E6")
	)
	(segment
		(start 52.905914 -150.314914)
		(end 52.499768 -149.908768)
		(width 0.127)
		(layer "B.Cu")
		(net "BMC_RGMII_C2_C3_D1_D2_E6")
	)
	(segment
		(start 54.663848 -152.199848)
		(end 53.457602 -150.993602)
		(width 0.127)
		(layer "B.Cu")
		(net "BMC_RGMII_C2_C3_D1_D2_E6")
	)
	(segment
		(start 55.442104 -150.657052)
		(end 55.785004 -150.999952)
		(width 0.127)
		(layer "F.Cu")
		(net "BMC_RGMII_A4_D3")
	)
	(segment
		(start 54.499764 -153.399998)
		(end 54.099968 -153.000202)
		(width 0.127)
		(layer "F.Cu")
		(net "BMC_RGMII_A4_D3")
	)
	(segment
		(start 54.657752 -151.422354)
		(end 54.956964 -151.123142)
		(width 0.127)
		(layer "F.Cu")
		(net "BMC_RGMII_A4_D3")
	)
	(segment
		(start 54.956964 -151.123142)
		(end 54.956964 -150.857712)
		(width 0.127)
		(layer "F.Cu")
		(net "BMC_RGMII_A4_D3")
	)
	(segment
		(start 55.785004 -150.999952)
		(end 56.099964 -150.999952)
		(width 0.127)
		(layer "F.Cu")
		(net "BMC_RGMII_A4_D3")
	)
	(segment
		(start 53.699918 -151.800052)
		(end 54.099714 -152.199848)
		(width 0.127)
		(layer "F.Cu")
		(net "BMC_RGMII_A4_D3")
	)
	(segment
		(start 53.699918 -151.800052)
		(end 54.077616 -151.422354)
		(width 0.127)
		(layer "F.Cu")
		(net "BMC_RGMII_A4_D3")
	)
	(segment
		(start 54.500018 -153.399998)
		(end 54.499764 -153.399998)
		(width 0.127)
		(layer "F.Cu")
		(net "BMC_RGMII_A4_D3")
	)
	(segment
		(start 55.157624 -150.657052)
		(end 55.442104 -150.657052)
		(width 0.127)
		(layer "F.Cu")
		(net "BMC_RGMII_A4_D3")
	)
	(segment
		(start 54.956964 -150.857712)
		(end 55.157624 -150.657052)
		(width 0.127)
		(layer "F.Cu")
		(net "BMC_RGMII_A4_D3")
	)
	(segment
		(start 54.077616 -151.422354)
		(end 54.657752 -151.422354)
		(width 0.127)
		(layer "F.Cu")
		(net "BMC_RGMII_A4_D3")
	)
	(via
		(at 54.099968 -153.000202)
		(size 0.4572)
		(drill 0.2032)
		(layers "F.Cu" "B.Cu")
		(net "BMC_RGMII_A4_D3")
	)
	(via
		(at 55.4482 -153.67)
		(size 0.6096)
		(drill 0.3048)
		(layers "F.Cu" "B.Cu")
		(net "BMC_RGMII_A4_D3")
	)
	(via
		(at 54.099714 -152.199848)
		(size 0.4572)
		(drill 0.2032)
		(layers "F.Cu" "B.Cu")
		(net "BMC_RGMII_A4_D3")
	)
	(segment
		(start 56.2737 -154.4955)
		(end 55.4482 -153.67)
		(width 0.127)
		(layer "B.Cu")
		(net "BMC_RGMII_A4_D3")
	)
	(segment
		(start 54.212744 -153.112978)
		(end 54.099968 -153.000202)
		(width 0.127)
		(layer "B.Cu")
		(net "BMC_RGMII_A4_D3")
	)
	(segment
		(start 55.4482 -153.67)
		(end 54.891178 -153.112978)
		(width 0.127)
		(layer "B.Cu")
		(net "BMC_RGMII_A4_D3")
	)
	(segment
		(start 54.099714 -152.199848)
		(end 54.099968 -152.200102)
		(width 0.127)
		(layer "B.Cu")
		(net "BMC_RGMII_A4_D3")
	)
	(segment
		(start 56.3372 -154.4955)
		(end 56.2737 -154.4955)
		(width 0.127)
		(layer "B.Cu")
		(net "BMC_RGMII_A4_D3")
	)
	(segment
		(start 54.891178 -153.112978)
		(end 54.212744 -153.112978)
		(width 0.127)
		(layer "B.Cu")
		(net "BMC_RGMII_A4_D3")
	)
	(segment
		(start 54.099968 -152.200102)
		(end 54.099968 -153.000202)
		(width 0.127)
		(layer "B.Cu")
		(net "BMC_RGMII_A4_D3")
	)
	(segment
		(start 48.899826 -138.199876)
		(end 49.299876 -137.799826)
		(width 0.127)
		(layer "F.Cu")
		(net "BMC_PEREXT")
	)
	(via
		(at 48.497744 -137.395712)
		(size 0.6096)
		(drill 0.3048)
		(layers "F.Cu" "B.Cu")
		(net "BMC_PEREXT")
	)
	(via
		(at 49.299876 -137.799826)
		(size 0.4572)
		(drill 0.2032)
		(layers "F.Cu" "B.Cu")
		(net "BMC_PEREXT")
	)
	(segment
		(start 48.497744 -136.871456)
		(end 48.690276 -136.678924)
		(width 0.127)
		(layer "B.Cu")
		(net "BMC_PEREXT")
	)
	(segment
		(start 48.901858 -137.799826)
		(end 48.497744 -137.395712)
		(width 0.127)
		(layer "B.Cu")
		(net "BMC_PEREXT")
	)
	(segment
		(start 48.690276 -136.678924)
		(end 48.690276 -136.163812)
		(width 0.127)
		(layer "B.Cu")
		(net "BMC_PEREXT")
	)
	(segment
		(start 48.497744 -137.395712)
		(end 48.497744 -136.871456)
		(width 0.127)
		(layer "B.Cu")
		(net "BMC_PEREXT")
	)
	(segment
		(start 49.299876 -137.799826)
		(end 48.901858 -137.799826)
		(width 0.127)
		(layer "B.Cu")
		(net "BMC_PEREXT")
	)
	(segment
		(start 138.774424 -43.125644)
		(end 137.700004 -44.200064)
		(width 0.127)
		(layer "F.Cu")
		(net "BMC_LOC_HEARTBEAT")
	)
	(segment
		(start 138.774424 -28.51277)
		(end 138.774424 -43.125644)
		(width 0.127)
		(layer "F.Cu")
		(net "BMC_LOC_HEARTBEAT")
	)
	(segment
		(start 137.936986 -27.675332)
		(end 138.774424 -28.51277)
		(width 0.127)
		(layer "F.Cu")
		(net "BMC_LOC_HEARTBEAT")
	)
	(via
		(at 137.936986 -27.675332)
		(size 0.508)
		(drill 0.254)
		(layers "F.Cu" "B.Cu")
		(net "BMC_LOC_HEARTBEAT")
	)
	(via
		(at 84.3788 -163.5252)
		(size 0.508)
		(drill 0.254)
		(layers "F.Cu" "B.Cu")
		(net "BMC_LOC_HEARTBEAT")
	)
	(via
		(at 40.905938 -156.461206)
		(size 0.6096)
		(drill 0.3048)
		(layers "F.Cu" "B.Cu")
		(net "BMC_LOC_HEARTBEAT")
	)
	(via
		(at 41.3385 -155.503118)
		(size 0.508)
		(drill 0.254)
		(layers "F.Cu" "B.Cu")
		(net "BMC_LOC_HEARTBEAT")
	)
	(segment
		(start 40.5511 -157.4546)
		(end 40.5511 -156.816044)
		(width 0.127)
		(layer "B.Cu")
		(net "BMC_LOC_HEARTBEAT")
	)
	(segment
		(start 40.5511 -156.816044)
		(end 40.905938 -156.461206)
		(width 0.127)
		(layer "B.Cu")
		(net "BMC_LOC_HEARTBEAT")
	)
	(segment
		(start 41.3385 -155.503118)
		(end 41.3385 -156.028644)
		(width 0.127)
		(layer "B.Cu")
		(net "BMC_LOC_HEARTBEAT")
	)
	(segment
		(start 41.3385 -156.028644)
		(end 40.905938 -156.461206)
		(width 0.127)
		(layer "B.Cu")
		(net "BMC_LOC_HEARTBEAT")
	)
	(segment
		(start 83.904582 -99.524566)
		(end 83.904328 -99.524312)
		(width 0.127)
		(layer "In2.Cu")
		(net "BMC_LOC_HEARTBEAT")
	)
	(segment
		(start 97.459292 -10.851642)
		(end 97.459038 -10.851896)
		(width 0.127)
		(layer "In2.Cu")
		(net "BMC_LOC_HEARTBEAT")
	)
	(segment
		(start 94.64167 -7.402576)
		(end 97.459292 -10.220198)
		(width 0.127)
		(layer "In2.Cu")
		(net "BMC_LOC_HEARTBEAT")
	)
	(segment
		(start 81.394554 -137.648188)
		(end 80.645 -136.898634)
		(width 0.127)
		(layer "In2.Cu")
		(net "BMC_LOC_HEARTBEAT")
	)
	(segment
		(start 80.254602 -146.659346)
		(end 81.394554 -145.519394)
		(width 0.127)
		(layer "In2.Cu")
		(net "BMC_LOC_HEARTBEAT")
	)
	(segment
		(start 100.330508 -15.183104)
		(end 115.94084 -15.183104)
		(width 0.127)
		(layer "In2.Cu")
		(net "BMC_LOC_HEARTBEAT")
	)
	(segment
		(start 80.470756 -151.71674)
		(end 80.470756 -150.711916)
		(width 0.127)
		(layer "In2.Cu")
		(net "BMC_LOC_HEARTBEAT")
	)
	(segment
		(start 80.254602 -150.495762)
		(end 80.254602 -146.659346)
		(width 0.127)
		(layer "In2.Cu")
		(net "BMC_LOC_HEARTBEAT")
	)
	(segment
		(start 118.726712 -17.653)
		(end 120.637554 -17.653)
		(width 0.127)
		(layer "In2.Cu")
		(net "BMC_LOC_HEARTBEAT")
	)
	(segment
		(start 80.645 -133.811772)
		(end 80.2386 -133.405372)
		(width 0.127)
		(layer "In2.Cu")
		(net "BMC_LOC_HEARTBEAT")
	)
	(segment
		(start 80.2386 -133.405372)
		(end 80.2386 -130.0988)
		(width 0.127)
		(layer "In2.Cu")
		(net "BMC_LOC_HEARTBEAT")
	)
	(segment
		(start 116.256562 -15.18285)
		(end 118.726712 -17.653)
		(width 0.127)
		(layer "In2.Cu")
		(net "BMC_LOC_HEARTBEAT")
	)
	(segment
		(start 83.788504 -71.235316)
		(end 83.788504 -69.076316)
		(width 0.127)
		(layer "In2.Cu")
		(net "BMC_LOC_HEARTBEAT")
	)
	(segment
		(start 97.459292 -10.220198)
		(end 97.459292 -10.851642)
		(width 0.127)
		(layer "In2.Cu")
		(net "BMC_LOC_HEARTBEAT")
	)
	(segment
		(start 83.904328 -99.524312)
		(end 83.904328 -98.892868)
		(width 0.127)
		(layer "In2.Cu")
		(net "BMC_LOC_HEARTBEAT")
	)
	(segment
		(start 74.447654 -117.69979)
		(end 77.787246 -114.360198)
		(width 0.127)
		(layer "In2.Cu")
		(net "BMC_LOC_HEARTBEAT")
	)
	(segment
		(start 79.7814 -128.503934)
		(end 74.447654 -123.170188)
		(width 0.127)
		(layer "In2.Cu")
		(net "BMC_LOC_HEARTBEAT")
	)
	(segment
		(start 126.682754 -23.6982)
		(end 133.959854 -23.6982)
		(width 0.127)
		(layer "In2.Cu")
		(net "BMC_LOC_HEARTBEAT")
	)
	(segment
		(start 115.941094 -15.18285)
		(end 116.256562 -15.18285)
		(width 0.127)
		(layer "In2.Cu")
		(net "BMC_LOC_HEARTBEAT")
	)
	(segment
		(start 84.3407 -111.005112)
		(end 84.3407 -110.033816)
		(width 0.127)
		(layer "In2.Cu")
		(net "BMC_LOC_HEARTBEAT")
	)
	(segment
		(start 83.904328 -98.892868)
		(end 83.904582 -98.892614)
		(width 0.127)
		(layer "In2.Cu")
		(net "BMC_LOC_HEARTBEAT")
	)
	(segment
		(start 81.394554 -145.519394)
		(end 81.394554 -137.648188)
		(width 0.127)
		(layer "In2.Cu")
		(net "BMC_LOC_HEARTBEAT")
	)
	(segment
		(start 81.399634 -32.864044)
		(end 81.399634 -9.849358)
		(width 0.127)
		(layer "In2.Cu")
		(net "BMC_LOC_HEARTBEAT")
	)
	(segment
		(start 77.787246 -114.360198)
		(end 80.985614 -114.360198)
		(width 0.127)
		(layer "In2.Cu")
		(net "BMC_LOC_HEARTBEAT")
	)
	(segment
		(start 80.470756 -150.711916)
		(end 80.254602 -150.495762)
		(width 0.127)
		(layer "In2.Cu")
		(net "BMC_LOC_HEARTBEAT")
	)
	(segment
		(start 84.3788 -163.5252)
		(end 84.053172 -163.5252)
		(width 0.127)
		(layer "In2.Cu")
		(net "BMC_LOC_HEARTBEAT")
	)
	(segment
		(start 98.050604 -12.9032)
		(end 100.330508 -15.183104)
		(width 0.127)
		(layer "In2.Cu")
		(net "BMC_LOC_HEARTBEAT")
	)
	(segment
		(start 120.637554 -17.653)
		(end 126.682754 -23.6982)
		(width 0.127)
		(layer "In2.Cu")
		(net "BMC_LOC_HEARTBEAT")
	)
	(segment
		(start 83.176364 -34.640774)
		(end 81.399634 -32.864044)
		(width 0.127)
		(layer "In2.Cu")
		(net "BMC_LOC_HEARTBEAT")
	)
	(segment
		(start 83.2866 -160.19272)
		(end 81.164176 -158.070296)
		(width 0.127)
		(layer "In2.Cu")
		(net "BMC_LOC_HEARTBEAT")
	)
	(segment
		(start 84.194396 -71.641208)
		(end 83.788504 -71.235316)
		(width 0.127)
		(layer "In2.Cu")
		(net "BMC_LOC_HEARTBEAT")
	)
	(segment
		(start 86.6013 -102.500684)
		(end 83.904582 -99.803966)
		(width 0.127)
		(layer "In2.Cu")
		(net "BMC_LOC_HEARTBEAT")
	)
	(segment
		(start 133.959854 -23.6982)
		(end 137.936986 -27.675332)
		(width 0.127)
		(layer "In2.Cu")
		(net "BMC_LOC_HEARTBEAT")
	)
	(segment
		(start 84.3407 -110.033816)
		(end 86.6013 -107.773216)
		(width 0.127)
		(layer "In2.Cu")
		(net "BMC_LOC_HEARTBEAT")
	)
	(segment
		(start 83.904582 -90.643456)
		(end 84.194396 -90.353642)
		(width 0.127)
		(layer "In2.Cu")
		(net "BMC_LOC_HEARTBEAT")
	)
	(segment
		(start 83.788504 -69.076316)
		(end 83.176364 -68.464176)
		(width 0.127)
		(layer "In2.Cu")
		(net "BMC_LOC_HEARTBEAT")
	)
	(segment
		(start 74.447654 -123.170188)
		(end 74.447654 -117.69979)
		(width 0.127)
		(layer "In2.Cu")
		(net "BMC_LOC_HEARTBEAT")
	)
	(segment
		(start 97.459038 -10.851896)
		(end 97.459038 -11.137646)
		(width 0.127)
		(layer "In2.Cu")
		(net "BMC_LOC_HEARTBEAT")
	)
	(segment
		(start 86.6013 -107.773216)
		(end 86.6013 -102.500684)
		(width 0.127)
		(layer "In2.Cu")
		(net "BMC_LOC_HEARTBEAT")
	)
	(segment
		(start 83.904582 -98.892614)
		(end 83.904582 -90.643456)
		(width 0.127)
		(layer "In2.Cu")
		(net "BMC_LOC_HEARTBEAT")
	)
	(segment
		(start 81.164176 -152.41016)
		(end 80.470756 -151.71674)
		(width 0.127)
		(layer "In2.Cu")
		(net "BMC_LOC_HEARTBEAT")
	)
	(segment
		(start 80.645 -136.898634)
		(end 80.645 -133.811772)
		(width 0.127)
		(layer "In2.Cu")
		(net "BMC_LOC_HEARTBEAT")
	)
	(segment
		(start 98.050604 -11.729212)
		(end 98.050604 -12.9032)
		(width 0.127)
		(layer "In2.Cu")
		(net "BMC_LOC_HEARTBEAT")
	)
	(segment
		(start 81.164176 -158.070296)
		(end 81.164176 -152.41016)
		(width 0.127)
		(layer "In2.Cu")
		(net "BMC_LOC_HEARTBEAT")
	)
	(segment
		(start 97.459038 -11.137646)
		(end 98.050604 -11.729212)
		(width 0.127)
		(layer "In2.Cu")
		(net "BMC_LOC_HEARTBEAT")
	)
	(segment
		(start 83.2866 -162.758628)
		(end 83.2866 -160.19272)
		(width 0.127)
		(layer "In2.Cu")
		(net "BMC_LOC_HEARTBEAT")
	)
	(segment
		(start 115.94084 -15.183104)
		(end 115.941094 -15.18285)
		(width 0.127)
		(layer "In2.Cu")
		(net "BMC_LOC_HEARTBEAT")
	)
	(segment
		(start 80.2386 -130.0988)
		(end 79.7814 -129.6416)
		(width 0.127)
		(layer "In2.Cu")
		(net "BMC_LOC_HEARTBEAT")
	)
	(segment
		(start 80.985614 -114.360198)
		(end 84.3407 -111.005112)
		(width 0.127)
		(layer "In2.Cu")
		(net "BMC_LOC_HEARTBEAT")
	)
	(segment
		(start 79.7814 -129.6416)
		(end 79.7814 -128.503934)
		(width 0.127)
		(layer "In2.Cu")
		(net "BMC_LOC_HEARTBEAT")
	)
	(segment
		(start 83.904582 -99.803966)
		(end 83.904582 -99.524566)
		(width 0.127)
		(layer "In2.Cu")
		(net "BMC_LOC_HEARTBEAT")
	)
	(segment
		(start 84.194396 -90.353642)
		(end 84.194396 -71.641208)
		(width 0.127)
		(layer "In2.Cu")
		(net "BMC_LOC_HEARTBEAT")
	)
	(segment
		(start 83.176364 -68.464176)
		(end 83.176364 -34.640774)
		(width 0.127)
		(layer "In2.Cu")
		(net "BMC_LOC_HEARTBEAT")
	)
	(segment
		(start 81.399634 -9.849358)
		(end 83.846416 -7.402576)
		(width 0.127)
		(layer "In2.Cu")
		(net "BMC_LOC_HEARTBEAT")
	)
	(segment
		(start 84.053172 -163.5252)
		(end 83.2866 -162.758628)
		(width 0.127)
		(layer "In2.Cu")
		(net "BMC_LOC_HEARTBEAT")
	)
	(segment
		(start 83.846416 -7.402576)
		(end 94.64167 -7.402576)
		(width 0.127)
		(layer "In2.Cu")
		(net "BMC_LOC_HEARTBEAT")
	)
	(segment
		(start 53.8099 -155.3083)
		(end 57.2897 -158.7881)
		(width 0.127)
		(layer "In5.Cu")
		(net "BMC_LOC_HEARTBEAT")
	)
	(segment
		(start 84.4931 -162.822382)
		(end 84.3788 -162.936682)
		(width 0.127)
		(layer "In5.Cu")
		(net "BMC_LOC_HEARTBEAT")
	)
	(segment
		(start 84.4931 -162.348672)
		(end 84.4931 -162.822382)
		(width 0.127)
		(layer "In5.Cu")
		(net "BMC_LOC_HEARTBEAT")
	)
	(segment
		(start 57.2897 -158.7881)
		(end 63.8302 -158.7881)
		(width 0.127)
		(layer "In5.Cu")
		(net "BMC_LOC_HEARTBEAT")
	)
	(segment
		(start 63.8937 -158.7246)
		(end 72.8726 -158.7246)
		(width 0.127)
		(layer "In5.Cu")
		(net "BMC_LOC_HEARTBEAT")
	)
	(segment
		(start 63.8302 -158.7881)
		(end 63.8937 -158.7246)
		(width 0.127)
		(layer "In5.Cu")
		(net "BMC_LOC_HEARTBEAT")
	)
	(segment
		(start 41.3385 -155.503118)
		(end 41.533318 -155.3083)
		(width 0.127)
		(layer "In5.Cu")
		(net "BMC_LOC_HEARTBEAT")
	)
	(segment
		(start 73.638664 -157.958536)
		(end 80.102964 -157.958536)
		(width 0.127)
		(layer "In5.Cu")
		(net "BMC_LOC_HEARTBEAT")
	)
	(segment
		(start 80.102964 -157.958536)
		(end 84.4931 -162.348672)
		(width 0.127)
		(layer "In5.Cu")
		(net "BMC_LOC_HEARTBEAT")
	)
	(segment
		(start 72.8726 -158.7246)
		(end 73.638664 -157.958536)
		(width 0.127)
		(layer "In5.Cu")
		(net "BMC_LOC_HEARTBEAT")
	)
	(segment
		(start 41.533318 -155.3083)
		(end 53.8099 -155.3083)
		(width 0.127)
		(layer "In5.Cu")
		(net "BMC_LOC_HEARTBEAT")
	)
	(segment
		(start 84.3788 -162.936682)
		(end 84.3788 -163.5252)
		(width 0.127)
		(layer "In5.Cu")
		(net "BMC_LOC_HEARTBEAT")
	)
	(segment
		(start 42.900092 -151.399748)
		(end 43.299888 -150.999952)
		(width 0.127)
		(layer "F.Cu")
		(net "BMC_LOC_HB")
	)
	(segment
		(start 42.900092 -151.400002)
		(end 42.900092 -151.399748)
		(width 0.127)
		(layer "F.Cu")
		(net "BMC_LOC_HB")
	)
	(via
		(at 41.91 -156.0322)
		(size 0.6096)
		(drill 0.3048)
		(layers "F.Cu" "B.Cu")
		(net "BMC_LOC_HB")
	)
	(via
		(at 42.900092 -151.400002)
		(size 0.4572)
		(drill 0.2032)
		(layers "F.Cu" "B.Cu")
		(net "BMC_LOC_HB")
	)
	(segment
		(start 42.493692 -152.04948)
		(end 42.493692 -152.363424)
		(width 0.127)
		(layer "B.Cu")
		(net "BMC_LOC_HB")
	)
	(segment
		(start 42.900092 -151.64308)
		(end 42.493692 -152.04948)
		(width 0.127)
		(layer "B.Cu")
		(net "BMC_LOC_HB")
	)
	(segment
		(start 42.900092 -151.400002)
		(end 42.900092 -151.64308)
		(width 0.127)
		(layer "B.Cu")
		(net "BMC_LOC_HB")
	)
	(segment
		(start 42.493692 -152.363424)
		(end 42.359834 -152.497282)
		(width 0.127)
		(layer "B.Cu")
		(net "BMC_LOC_HB")
	)
	(segment
		(start 42.359834 -152.497282)
		(end 42.359834 -155.582366)
		(width 0.127)
		(layer "B.Cu")
		(net "BMC_LOC_HB")
	)
	(segment
		(start 41.4401 -157.4546)
		(end 41.4401 -156.5021)
		(width 0.127)
		(layer "B.Cu")
		(net "BMC_LOC_HB")
	)
	(segment
		(start 41.4401 -156.5021)
		(end 41.91 -156.0322)
		(width 0.127)
		(layer "B.Cu")
		(net "BMC_LOC_HB")
	)
	(segment
		(start 42.359834 -155.582366)
		(end 41.91 -156.0322)
		(width 0.127)
		(layer "B.Cu")
		(net "BMC_LOC_HB")
	)
	(segment
		(start 23.777956 -127.343408)
		(end 23.777956 -126.104396)
		(width 0.127)
		(layer "F.Cu")
		(net "BMC_HBLED_R")
	)
	(segment
		(start 23.777956 -126.104396)
		(end 23.756874 -126.083314)
		(width 0.127)
		(layer "F.Cu")
		(net "BMC_HBLED_R")
	)
	(segment
		(start 26.047446 -128.867408)
		(end 26.060654 -128.8542)
		(width 0.127)
		(layer "F.Cu")
		(net "BMC_HBLED")
	)
	(segment
		(start 23.777956 -128.867408)
		(end 26.047446 -128.867408)
		(width 0.127)
		(layer "F.Cu")
		(net "BMC_HBLED")
	)
	(segment
		(start 40.500046 -139.400534)
		(end 40.5003 -139.400534)
		(width 0.127)
		(layer "F.Cu")
		(net "BMC_HBLED")
	)
	(segment
		(start 40.5003 -139.400534)
		(end 40.899842 -139.800076)
		(width 0.127)
		(layer "F.Cu")
		(net "BMC_HBLED")
	)
	(via
		(at 26.060654 -128.8542)
		(size 0.508)
		(drill 0.254)
		(layers "F.Cu" "B.Cu")
		(net "BMC_HBLED")
	)
	(via
		(at 36.42741 -134.656322)
		(size 0.508)
		(drill 0.254)
		(layers "F.Cu" "B.Cu")
		(net "BMC_HBLED")
	)
	(via
		(at 40.500046 -139.400534)
		(size 0.4572)
		(drill 0.2032)
		(layers "F.Cu" "B.Cu")
		(net "BMC_HBLED")
	)
	(segment
		(start 36.42741 -136.402064)
		(end 39.42588 -139.400534)
		(width 0.127)
		(layer "In2.Cu")
		(net "BMC_HBLED")
	)
	(segment
		(start 36.42741 -134.656322)
		(end 36.42741 -136.402064)
		(width 0.127)
		(layer "In2.Cu")
		(net "BMC_HBLED")
	)
	(segment
		(start 39.42588 -139.400534)
		(end 40.500046 -139.400534)
		(width 0.127)
		(layer "In2.Cu")
		(net "BMC_HBLED")
	)
	(segment
		(start 37.108384 -133.975348)
		(end 37.108384 -132.954014)
		(width 0.127)
		(layer "In5.Cu")
		(net "BMC_HBLED")
	)
	(segment
		(start 36.576 -130.801618)
		(end 34.628582 -128.8542)
		(width 0.127)
		(layer "In5.Cu")
		(net "BMC_HBLED")
	)
	(segment
		(start 37.108384 -132.954014)
		(end 36.576 -132.42163)
		(width 0.127)
		(layer "In5.Cu")
		(net "BMC_HBLED")
	)
	(segment
		(start 34.628582 -128.8542)
		(end 26.060654 -128.8542)
		(width 0.127)
		(layer "In5.Cu")
		(net "BMC_HBLED")
	)
	(segment
		(start 36.42741 -134.656322)
		(end 37.108384 -133.975348)
		(width 0.127)
		(layer "In5.Cu")
		(net "BMC_HBLED")
	)
	(segment
		(start 36.576 -132.42163)
		(end 36.576 -130.801618)
		(width 0.127)
		(layer "In5.Cu")
		(net "BMC_HBLED")
	)
	(segment
		(start 39.11219 -133.765036)
		(end 39.11219 -134.051294)
		(width 0.127)
		(layer "F.Cu")
		(net "BMC_GPIOZ7")
	)
	(segment
		(start 38.034468 -132.687314)
		(end 39.11219 -133.765036)
		(width 0.127)
		(layer "F.Cu")
		(net "BMC_GPIOZ7")
	)
	(segment
		(start 41.32453 -135.956294)
		(end 41.32453 -137.024618)
		(width 0.127)
		(layer "F.Cu")
		(net "BMC_GPIOZ7")
	)
	(segment
		(start 39.11219 -134.051294)
		(end 39.41953 -134.051294)
		(width 0.127)
		(layer "F.Cu")
		(net "BMC_GPIOZ7")
	)
	(segment
		(start 39.41953 -134.051294)
		(end 41.32453 -135.956294)
		(width 0.127)
		(layer "F.Cu")
		(net "BMC_GPIOZ7")
	)
	(segment
		(start 38.034468 -132.000244)
		(end 38.034468 -132.687314)
		(width 0.127)
		(layer "F.Cu")
		(net "BMC_GPIOZ7")
	)
	(segment
		(start 41.32453 -137.024618)
		(end 41.699942 -137.40003)
		(width 0.127)
		(layer "F.Cu")
		(net "BMC_GPIOZ7")
	)
	(via
		(at 39.11219 -134.051294)
		(size 0.6604)
		(drill 0.3302)
		(layers "F.Cu" "B.Cu")
		(net "BMC_GPIOZ7")
	)
	(segment
		(start 42.500042 -136.37006)
		(end 42.500042 -136.59993)
		(width 0.127)
		(layer "F.Cu")
		(net "BMC_GPIOZ6")
	)
	(segment
		(start 40.828722 -134.057644)
		(end 42.41165 -135.640572)
		(width 0.127)
		(layer "F.Cu")
		(net "BMC_GPIOZ6")
	)
	(segment
		(start 40.718486 -133.947408)
		(end 40.828722 -134.057644)
		(width 0.127)
		(layer "F.Cu")
		(net "BMC_GPIOZ6")
	)
	(segment
		(start 40.718486 -132.532628)
		(end 40.718486 -133.947408)
		(width 0.127)
		(layer "F.Cu")
		(net "BMC_GPIOZ6")
	)
	(segment
		(start 42.41165 -135.640572)
		(end 42.41165 -136.281668)
		(width 0.127)
		(layer "F.Cu")
		(net "BMC_GPIOZ6")
	)
	(segment
		(start 40.105584 -131.919726)
		(end 40.718486 -132.532628)
		(width 0.127)
		(layer "F.Cu")
		(net "BMC_GPIOZ6")
	)
	(segment
		(start 42.41165 -136.281668)
		(end 42.500042 -136.37006)
		(width 0.127)
		(layer "F.Cu")
		(net "BMC_GPIOZ6")
	)
	(via
		(at 40.828722 -134.057644)
		(size 0.6604)
		(drill 0.3302)
		(layers "F.Cu" "B.Cu")
		(net "BMC_GPIOZ6")
	)
	(segment
		(start 40.079422 -134.368286)
		(end 40.079422 -133.88848)
		(width 0.127)
		(layer "F.Cu")
		(net "BMC_GPIOZ5")
	)
	(segment
		(start 41.699942 -136.59993)
		(end 41.699942 -135.988806)
		(width 0.127)
		(layer "F.Cu")
		(net "BMC_GPIOZ5")
	)
	(segment
		(start 38.820344 -131.77012)
		(end 38.820344 -132.629402)
		(width 0.127)
		(layer "F.Cu")
		(net "BMC_GPIOZ5")
	)
	(segment
		(start 38.820344 -132.629402)
		(end 39.154354 -132.963412)
		(width 0.127)
		(layer "F.Cu")
		(net "BMC_GPIOZ5")
	)
	(segment
		(start 41.699942 -135.988806)
		(end 40.079422 -134.368286)
		(width 0.127)
		(layer "F.Cu")
		(net "BMC_GPIOZ5")
	)
	(segment
		(start 40.079422 -133.88848)
		(end 39.154354 -132.963412)
		(width 0.127)
		(layer "F.Cu")
		(net "BMC_GPIOZ5")
	)
	(segment
		(start 38.034468 -130.984244)
		(end 38.820344 -131.77012)
		(width 0.127)
		(layer "F.Cu")
		(net "BMC_GPIOZ5")
	)
	(via
		(at 39.154354 -132.963412)
		(size 0.6604)
		(drill 0.3302)
		(layers "F.Cu" "B.Cu")
		(net "BMC_GPIOZ5")
	)
	(segment
		(start 42.64025 -134.973314)
		(end 42.64025 -136.185402)
		(width 0.127)
		(layer "F.Cu")
		(net "BMC_GPIOZ4")
	)
	(segment
		(start 41.13276 -131.936998)
		(end 41.13276 -133.465824)
		(width 0.127)
		(layer "F.Cu")
		(net "BMC_GPIOZ4")
	)
	(segment
		(start 42.64025 -136.185402)
		(end 42.8752 -136.420352)
		(width 0.127)
		(layer "F.Cu")
		(net "BMC_GPIOZ4")
	)
	(segment
		(start 42.8752 -136.420352)
		(end 42.8752 -136.975342)
		(width 0.127)
		(layer "F.Cu")
		(net "BMC_GPIOZ4")
	)
	(segment
		(start 41.123108 -131.927346)
		(end 41.13276 -131.936998)
		(width 0.127)
		(layer "F.Cu")
		(net "BMC_GPIOZ4")
	)
	(segment
		(start 41.13276 -133.465824)
		(end 42.055288 -134.388352)
		(width 0.127)
		(layer "F.Cu")
		(net "BMC_GPIOZ4")
	)
	(segment
		(start 42.055288 -134.388352)
		(end 42.64025 -134.973314)
		(width 0.127)
		(layer "F.Cu")
		(net "BMC_GPIOZ4")
	)
	(segment
		(start 42.8752 -136.975342)
		(end 43.299888 -137.40003)
		(width 0.127)
		(layer "F.Cu")
		(net "BMC_GPIOZ4")
	)
	(via
		(at 42.055288 -134.388352)
		(size 0.6604)
		(drill 0.3302)
		(layers "F.Cu" "B.Cu")
		(net "BMC_GPIOZ4")
	)
	(segment
		(start 47.380398 -131.935474)
		(end 47.380398 -132.438902)
		(width 0.127)
		(layer "F.Cu")
		(net "BMC_GPIOY3")
	)
	(segment
		(start 47.380398 -132.438902)
		(end 46.6725 -133.1468)
		(width 0.127)
		(layer "F.Cu")
		(net "BMC_GPIOY3")
	)
	(segment
		(start 46.099984 -137.80008)
		(end 45.699934 -137.40003)
		(width 0.127)
		(layer "F.Cu")
		(net "BMC_GPIOY3")
	)
	(via
		(at 46.6725 -133.1468)
		(size 0.508)
		(drill 0.254)
		(layers "F.Cu" "B.Cu")
		(net "BMC_GPIOY3")
	)
	(via
		(at 46.099984 -137.80008)
		(size 0.4572)
		(drill 0.2032)
		(layers "F.Cu" "B.Cu")
		(net "BMC_GPIOY3")
	)
	(segment
		(start 46.151546 -134.442454)
		(end 46.151546 -134.749794)
		(width 0.127)
		(layer "In2.Cu")
		(net "BMC_GPIOY3")
	)
	(segment
		(start 46.482 -133.3373)
		(end 46.482 -134.112)
		(width 0.127)
		(layer "In2.Cu")
		(net "BMC_GPIOY3")
	)
	(segment
		(start 45.8978 -137.597896)
		(end 46.099984 -137.80008)
		(width 0.127)
		(layer "In2.Cu")
		(net "BMC_GPIOY3")
	)
	(segment
		(start 46.6725 -133.1468)
		(end 46.482 -133.3373)
		(width 0.127)
		(layer "In2.Cu")
		(net "BMC_GPIOY3")
	)
	(segment
		(start 45.8978 -135.00354)
		(end 45.8978 -137.597896)
		(width 0.127)
		(layer "In2.Cu")
		(net "BMC_GPIOY3")
	)
	(segment
		(start 46.151546 -134.749794)
		(end 45.8978 -135.00354)
		(width 0.127)
		(layer "In2.Cu")
		(net "BMC_GPIOY3")
	)
	(segment
		(start 46.482 -134.112)
		(end 46.151546 -134.442454)
		(width 0.127)
		(layer "In2.Cu")
		(net "BMC_GPIOY3")
	)
	(segment
		(start 46.5709 -134.0866)
		(end 46.5709 -135.0391)
		(width 0.127)
		(layer "F.Cu")
		(net "BMC_GPIOY2")
	)
	(segment
		(start 46.5709 -135.0391)
		(end 45.699934 -135.910066)
		(width 0.127)
		(layer "F.Cu")
		(net "BMC_GPIOY2")
	)
	(segment
		(start 46.2026 -133.7183)
		(end 46.5709 -134.0866)
		(width 0.127)
		(layer "F.Cu")
		(net "BMC_GPIOY2")
	)
	(segment
		(start 45.699934 -135.910066)
		(end 45.699934 -136.59993)
		(width 0.127)
		(layer "F.Cu")
		(net "BMC_GPIOY2")
	)
	(segment
		(start 46.348396 -132.268214)
		(end 46.2026 -132.41401)
		(width 0.127)
		(layer "F.Cu")
		(net "BMC_GPIOY2")
	)
	(segment
		(start 46.2026 -132.41401)
		(end 46.2026 -133.7183)
		(width 0.127)
		(layer "F.Cu")
		(net "BMC_GPIOY2")
	)
	(via
		(at 46.5709 -134.0866)
		(size 0.6604)
		(drill 0.3302)
		(layers "F.Cu" "B.Cu")
		(net "BMC_GPIOY2")
	)
	(segment
		(start 44.44873 -136.948926)
		(end 44.899834 -137.40003)
		(width 0.127)
		(layer "F.Cu")
		(net "BMC_GPIOY1")
	)
	(segment
		(start 42.23512 -132.1943)
		(end 43.03268 -132.99186)
		(width 0.127)
		(layer "F.Cu")
		(net "BMC_GPIOY1")
	)
	(segment
		(start 43.03268 -134.142226)
		(end 44.44873 -135.558276)
		(width 0.127)
		(layer "F.Cu")
		(net "BMC_GPIOY1")
	)
	(segment
		(start 44.44873 -135.558276)
		(end 44.44873 -136.948926)
		(width 0.127)
		(layer "F.Cu")
		(net "BMC_GPIOY1")
	)
	(segment
		(start 43.03268 -133.730746)
		(end 43.03268 -134.142226)
		(width 0.127)
		(layer "F.Cu")
		(net "BMC_GPIOY1")
	)
	(segment
		(start 43.03268 -132.99186)
		(end 43.03268 -133.730746)
		(width 0.127)
		(layer "F.Cu")
		(net "BMC_GPIOY1")
	)
	(via
		(at 43.03268 -133.730746)
		(size 0.6604)
		(drill 0.3302)
		(layers "F.Cu" "B.Cu")
		(net "BMC_GPIOY1")
	)
	(segment
		(start 43.751754 -133.99008)
		(end 43.98645 -134.224776)
		(width 0.127)
		(layer "F.Cu")
		(net "BMC_GPIOY0")
	)
	(segment
		(start 43.751754 -132.669534)
		(end 43.751754 -133.99008)
		(width 0.127)
		(layer "F.Cu")
		(net "BMC_GPIOY0")
	)
	(segment
		(start 44.899834 -135.13816)
		(end 44.899834 -136.59993)
		(width 0.127)
		(layer "F.Cu")
		(net "BMC_GPIOY0")
	)
	(segment
		(start 43.98645 -134.224776)
		(end 44.899834 -135.13816)
		(width 0.127)
		(layer "F.Cu")
		(net "BMC_GPIOY0")
	)
	(segment
		(start 43.27652 -132.1943)
		(end 43.751754 -132.669534)
		(width 0.127)
		(layer "F.Cu")
		(net "BMC_GPIOY0")
	)
	(via
		(at 43.98645 -134.224776)
		(size 0.6604)
		(drill 0.3302)
		(layers "F.Cu" "B.Cu")
		(net "BMC_GPIOY0")
	)
	(segment
		(start 39.699946 -137.800334)
		(end 39.700454 -137.800334)
		(width 0.127)
		(layer "F.Cu")
		(net "BMC_GPIOS7")
	)
	(segment
		(start 39.700454 -137.800334)
		(end 40.099996 -138.199876)
		(width 0.127)
		(layer "F.Cu")
		(net "BMC_GPIOS7")
	)
	(via
		(at 39.699946 -137.800334)
		(size 0.4572)
		(drill 0.2032)
		(layers "F.Cu" "B.Cu")
		(net "BMC_GPIOS7")
	)
	(via
		(at 40.1828 -135.3566)
		(size 0.6096)
		(drill 0.3048)
		(layers "F.Cu" "B.Cu")
		(net "BMC_GPIOS7")
	)
	(segment
		(start 40.132 -137.36828)
		(end 39.699946 -137.800334)
		(width 0.127)
		(layer "B.Cu")
		(net "BMC_GPIOS7")
	)
	(segment
		(start 40.1828 -135.3566)
		(end 40.1828 -134.874)
		(width 0.127)
		(layer "B.Cu")
		(net "BMC_GPIOS7")
	)
	(segment
		(start 40.132 -136.0678)
		(end 40.132 -137.36828)
		(width 0.127)
		(layer "B.Cu")
		(net "BMC_GPIOS7")
	)
	(segment
		(start 40.1828 -134.874)
		(end 40.2844 -134.7724)
		(width 0.127)
		(layer "B.Cu")
		(net "BMC_GPIOS7")
	)
	(segment
		(start 40.1828 -136.017)
		(end 40.132 -136.0678)
		(width 0.127)
		(layer "B.Cu")
		(net "BMC_GPIOS7")
	)
	(segment
		(start 40.2844 -134.7724)
		(end 40.2844 -134.2263)
		(width 0.127)
		(layer "B.Cu")
		(net "BMC_GPIOS7")
	)
	(segment
		(start 40.1828 -135.3566)
		(end 40.1828 -136.017)
		(width 0.127)
		(layer "B.Cu")
		(net "BMC_GPIOS7")
	)
	(segment
		(start 43.299888 -138.199622)
		(end 43.299888 -138.199876)
		(width 0.127)
		(layer "F.Cu")
		(net "BMC_GPIOS6")
	)
	(segment
		(start 42.900092 -137.799826)
		(end 43.299888 -138.199622)
		(width 0.127)
		(layer "F.Cu")
		(net "BMC_GPIOS6")
	)
	(via
		(at 42.900092 -137.799826)
		(size 0.4572)
		(drill 0.2032)
		(layers "F.Cu" "B.Cu")
		(net "BMC_GPIOS6")
	)
	(via
		(at 42.418 -136.017)
		(size 0.6096)
		(drill 0.3048)
		(layers "F.Cu" "B.Cu")
		(net "BMC_GPIOS6")
	)
	(segment
		(start 42.418 -137.317734)
		(end 42.900092 -137.799826)
		(width 0.127)
		(layer "B.Cu")
		(net "BMC_GPIOS6")
	)
	(segment
		(start 42.418 -134.970774)
		(end 42.418 -136.017)
		(width 0.127)
		(layer "B.Cu")
		(net "BMC_GPIOS6")
	)
	(segment
		(start 42.418 -136.017)
		(end 42.418 -137.317734)
		(width 0.127)
		(layer "B.Cu")
		(net "BMC_GPIOS6")
	)
	(segment
		(start 42.533316 -134.855458)
		(end 42.418 -134.970774)
		(width 0.127)
		(layer "B.Cu")
		(net "BMC_GPIOS6")
	)
	(segment
		(start 41.699942 -138.199622)
		(end 41.699942 -138.199876)
		(width 0.127)
		(layer "F.Cu")
		(net "BMC_GPIOS5")
	)
	(segment
		(start 41.300146 -137.799826)
		(end 41.699942 -138.199622)
		(width 0.127)
		(layer "F.Cu")
		(net "BMC_GPIOS5")
	)
	(via
		(at 41.300146 -137.799826)
		(size 0.4572)
		(drill 0.2032)
		(layers "F.Cu" "B.Cu")
		(net "BMC_GPIOS5")
	)
	(via
		(at 41.855136 -137.009378)
		(size 0.6096)
		(drill 0.3048)
		(layers "F.Cu" "B.Cu")
		(net "BMC_GPIOS5")
	)
	(segment
		(start 41.4782 -134.7851)
		(end 41.855136 -135.162036)
		(width 0.127)
		(layer "B.Cu")
		(net "BMC_GPIOS5")
	)
	(segment
		(start 41.855136 -137.244836)
		(end 41.300146 -137.799826)
		(width 0.127)
		(layer "B.Cu")
		(net "BMC_GPIOS5")
	)
	(segment
		(start 41.855136 -137.009378)
		(end 41.855136 -137.244836)
		(width 0.127)
		(layer "B.Cu")
		(net "BMC_GPIOS5")
	)
	(segment
		(start 41.855136 -135.162036)
		(end 41.855136 -137.009378)
		(width 0.127)
		(layer "B.Cu")
		(net "BMC_GPIOS5")
	)
	(segment
		(start 44.500038 -138.600434)
		(end 44.500292 -138.600434)
		(width 0.127)
		(layer "F.Cu")
		(net "BMC_GPIOS4")
	)
	(segment
		(start 44.500292 -138.600434)
		(end 44.899834 -138.999976)
		(width 0.127)
		(layer "F.Cu")
		(net "BMC_GPIOS4")
	)
	(via
		(at 44.43222 -135.7884)
		(size 0.6096)
		(drill 0.3048)
		(layers "F.Cu" "B.Cu")
		(net "BMC_GPIOS4")
	)
	(via
		(at 44.500038 -138.600434)
		(size 0.4572)
		(drill 0.2032)
		(layers "F.Cu" "B.Cu")
		(net "BMC_GPIOS4")
	)
	(segment
		(start 44.43222 -136.262872)
		(end 44.43222 -135.7884)
		(width 0.127)
		(layer "B.Cu")
		(net "BMC_GPIOS4")
	)
	(segment
		(start 44.106338 -136.588754)
		(end 44.43222 -136.262872)
		(width 0.127)
		(layer "B.Cu")
		(net "BMC_GPIOS4")
	)
	(segment
		(start 44.43222 -134.80288)
		(end 44.4373 -134.7978)
		(width 0.127)
		(layer "B.Cu")
		(net "BMC_GPIOS4")
	)
	(segment
		(start 44.500038 -138.600434)
		(end 44.106338 -138.206734)
		(width 0.127)
		(layer "B.Cu")
		(net "BMC_GPIOS4")
	)
	(segment
		(start 44.43222 -135.7884)
		(end 44.43222 -134.80288)
		(width 0.127)
		(layer "B.Cu")
		(net "BMC_GPIOS4")
	)
	(segment
		(start 44.106338 -138.206734)
		(end 44.106338 -136.588754)
		(width 0.127)
		(layer "B.Cu")
		(net "BMC_GPIOS4")
	)
	(segment
		(start 42.500042 -139.799822)
		(end 42.100246 -139.400026)
		(width 0.127)
		(layer "F.Cu")
		(net "BMC_EXTRST_N")
	)
	(segment
		(start 42.500042 -139.800076)
		(end 42.500042 -139.799822)
		(width 0.127)
		(layer "F.Cu")
		(net "BMC_EXTRST_N")
	)
	(via
		(at 41.4782 -129.6416)
		(size 0.6096)
		(drill 0.3048)
		(layers "F.Cu" "B.Cu")
		(net "BMC_EXTRST_N")
	)
	(via
		(at 42.100246 -139.400026)
		(size 0.4572)
		(drill 0.2032)
		(layers "F.Cu" "B.Cu")
		(net "BMC_EXTRST_N")
	)
	(via
		(at 40.712644 -129.140966)
		(size 0.508)
		(drill 0.254)
		(layers "F.Cu" "B.Cu")
		(net "BMC_EXTRST_N")
	)
	(segment
		(start 40.712644 -129.140966)
		(end 41.213278 -129.6416)
		(width 0.127)
		(layer "B.Cu")
		(net "BMC_EXTRST_N")
	)
	(segment
		(start 41.7576 -129.3622)
		(end 41.7576 -128.896618)
		(width 0.127)
		(layer "B.Cu")
		(net "BMC_EXTRST_N")
	)
	(segment
		(start 41.7576 -128.896618)
		(end 41.284398 -128.423416)
		(width 0.127)
		(layer "B.Cu")
		(net "BMC_EXTRST_N")
	)
	(segment
		(start 40.206676 -128.423416)
		(end 41.284398 -128.423416)
		(width 0.127)
		(layer "B.Cu")
		(net "BMC_EXTRST_N")
	)
	(segment
		(start 41.4782 -129.6416)
		(end 41.7576 -129.3622)
		(width 0.127)
		(layer "B.Cu")
		(net "BMC_EXTRST_N")
	)
	(segment
		(start 41.213278 -129.6416)
		(end 41.4782 -129.6416)
		(width 0.127)
		(layer "B.Cu")
		(net "BMC_EXTRST_N")
	)
	(segment
		(start 40.906446 -137.963148)
		(end 41.136824 -138.193526)
		(width 0.127)
		(layer "In2.Cu")
		(net "BMC_EXTRST_N")
	)
	(segment
		(start 41.337738 -133.062726)
		(end 40.906446 -133.494018)
		(width 0.127)
		(layer "In2.Cu")
		(net "BMC_EXTRST_N")
	)
	(segment
		(start 41.140126 -138.193526)
		(end 41.152826 -138.206226)
		(width 0.127)
		(layer "In2.Cu")
		(net "BMC_EXTRST_N")
	)
	(segment
		(start 41.706546 -138.449304)
		(end 41.706546 -138.763248)
		(width 0.127)
		(layer "In2.Cu")
		(net "BMC_EXTRST_N")
	)
	(segment
		(start 42.100246 -139.156948)
		(end 42.100246 -139.400026)
		(width 0.127)
		(layer "In2.Cu")
		(net "BMC_EXTRST_N")
	)
	(segment
		(start 40.8178 -129.5146)
		(end 41.337738 -130.034538)
		(width 0.127)
		(layer "In2.Cu")
		(net "BMC_EXTRST_N")
	)
	(segment
		(start 40.906446 -133.494018)
		(end 40.906446 -137.963148)
		(width 0.127)
		(layer "In2.Cu")
		(net "BMC_EXTRST_N")
	)
	(segment
		(start 40.8178 -129.246122)
		(end 40.8178 -129.5146)
		(width 0.127)
		(layer "In2.Cu")
		(net "BMC_EXTRST_N")
	)
	(segment
		(start 41.337738 -130.034538)
		(end 41.337738 -133.062726)
		(width 0.127)
		(layer "In2.Cu")
		(net "BMC_EXTRST_N")
	)
	(segment
		(start 40.712644 -129.140966)
		(end 40.8178 -129.246122)
		(width 0.127)
		(layer "In2.Cu")
		(net "BMC_EXTRST_N")
	)
	(segment
		(start 41.152826 -138.206226)
		(end 41.463468 -138.206226)
		(width 0.127)
		(layer "In2.Cu")
		(net "BMC_EXTRST_N")
	)
	(segment
		(start 41.463468 -138.206226)
		(end 41.706546 -138.449304)
		(width 0.127)
		(layer "In2.Cu")
		(net "BMC_EXTRST_N")
	)
	(segment
		(start 41.706546 -138.763248)
		(end 42.100246 -139.156948)
		(width 0.127)
		(layer "In2.Cu")
		(net "BMC_EXTRST_N")
	)
	(segment
		(start 41.136824 -138.193526)
		(end 41.140126 -138.193526)
		(width 0.127)
		(layer "In2.Cu")
		(net "BMC_EXTRST_N")
	)
	(segment
		(start 49.299876 -152.200102)
		(end 48.899826 -151.800052)
		(width 0.127)
		(layer "F.Cu")
		(net "BMC_ENTEST")
	)
	(via
		(at 49.299876 -152.200102)
		(size 0.4572)
		(drill 0.2032)
		(layers "F.Cu" "B.Cu")
		(net "BMC_ENTEST")
	)
	(via
		(at 52.939442 -153.746962)
		(size 0.6096)
		(drill 0.3048)
		(layers "F.Cu" "B.Cu")
		(net "BMC_ENTEST")
	)
	(segment
		(start 51.86299 -151.006302)
		(end 49.069498 -151.006302)
		(width 0.127)
		(layer "B.Cu")
		(net "BMC_ENTEST")
	)
	(segment
		(start 53.73878 -154.5463)
		(end 53.975 -154.5463)
		(width 0.127)
		(layer "B.Cu")
		(net "BMC_ENTEST")
	)
	(segment
		(start 52.939442 -153.746962)
		(end 53.73878 -154.5463)
		(width 0.127)
		(layer "B.Cu")
		(net "BMC_ENTEST")
	)
	(segment
		(start 52.939442 -153.746962)
		(end 52.106068 -152.913588)
		(width 0.127)
		(layer "B.Cu")
		(net "BMC_ENTEST")
	)
	(segment
		(start 48.895 -151.1808)
		(end 48.895 -151.795226)
		(width 0.127)
		(layer "B.Cu")
		(net "BMC_ENTEST")
	)
	(segment
		(start 52.106068 -152.913588)
		(end 52.106068 -151.24938)
		(width 0.127)
		(layer "B.Cu")
		(net "BMC_ENTEST")
	)
	(segment
		(start 48.895 -151.795226)
		(end 49.299876 -152.200102)
		(width 0.127)
		(layer "B.Cu")
		(net "BMC_ENTEST")
	)
	(segment
		(start 52.106068 -151.24938)
		(end 51.86299 -151.006302)
		(width 0.127)
		(layer "B.Cu")
		(net "BMC_ENTEST")
	)
	(segment
		(start 49.069498 -151.006302)
		(end 48.895 -151.1808)
		(width 0.127)
		(layer "B.Cu")
		(net "BMC_ENTEST")
	)
	(segment
		(start 219.49283 -93.915738)
		(end 219.68968 -93.718888)
		(width 0.254)
		(layer "F.Cu")
		(net "AGND_P3V3_M2")
	)
	(segment
		(start 219.49283 -94.934024)
		(end 219.49283 -93.915738)
		(width 0.254)
		(layer "F.Cu")
		(net "AGND_P3V3_M2")
	)
	(via
		(at 214.95893 -97.327974)
		(size 0.6096)
		(drill 0.3048)
		(layers "F.Cu" "B.Cu")
		(net "AGND_P3V3_M2")
	)
	(via
		(at 214.07628 -97.071688)
		(size 0.508)
		(drill 0.254)
		(layers "F.Cu" "B.Cu")
		(net "AGND_P3V3_M2")
	)
	(via
		(at 219.68968 -93.718888)
		(size 0.508)
		(drill 0.254)
		(layers "F.Cu" "B.Cu")
		(net "AGND_P3V3_M2")
	)
	(segment
		(start 214.332566 -97.327974)
		(end 214.95893 -97.327974)
		(width 0.254)
		(layer "B.Cu")
		(net "AGND_P3V3_M2")
	)
	(segment
		(start 216.069418 -95.92945)
		(end 217.608404 -94.390464)
		(width 0.254)
		(layer "B.Cu")
		(net "AGND_P3V3_M2")
	)
	(segment
		(start 214.95893 -97.327974)
		(end 215.853518 -97.327974)
		(width 0.254)
		(layer "B.Cu")
		(net "AGND_P3V3_M2")
	)
	(segment
		(start 214.07628 -97.071688)
		(end 214.332566 -97.327974)
		(width 0.254)
		(layer "B.Cu")
		(net "AGND_P3V3_M2")
	)
	(segment
		(start 215.853518 -97.327974)
		(end 216.069418 -97.112074)
		(width 0.254)
		(layer "B.Cu")
		(net "AGND_P3V3_M2")
	)
	(segment
		(start 219.018104 -94.390464)
		(end 219.68968 -93.718888)
		(width 0.254)
		(layer "B.Cu")
		(net "AGND_P3V3_M2")
	)
	(segment
		(start 217.608404 -94.390464)
		(end 219.018104 -94.390464)
		(width 0.254)
		(layer "B.Cu")
		(net "AGND_P3V3_M2")
	)
	(segment
		(start 216.069418 -97.112074)
		(end 216.069418 -95.92945)
		(width 0.254)
		(layer "B.Cu")
		(net "AGND_P3V3_M2")
	)
	(segment
		(start 53.135022 -156.019246)
		(end 53.135022 -155.573222)
		(width 0.127)
		(layer "F.Cu")
		(net "ADC_P3V3_M2")
	)
	(segment
		(start 53.135022 -155.573222)
		(end 52.1462 -154.5844)
		(width 0.127)
		(layer "F.Cu")
		(net "ADC_P3V3_M2")
	)
	(segment
		(start 52.1462 -153.446226)
		(end 52.099972 -153.399998)
		(width 0.127)
		(layer "F.Cu")
		(net "ADC_P3V3_M2")
	)
	(segment
		(start 52.1462 -154.5844)
		(end 52.1462 -153.446226)
		(width 0.127)
		(layer "F.Cu")
		(net "ADC_P3V3_M2")
	)
	(via
		(at 52.6923 -157.988)
		(size 0.6096)
		(drill 0.3048)
		(layers "F.Cu" "B.Cu")
		(net "ADC_P3V3_M2")
	)
	(via
		(at 53.135022 -156.019246)
		(size 0.508)
		(drill 0.254)
		(layers "F.Cu" "B.Cu")
		(net "ADC_P3V3_M2")
	)
	(segment
		(start 52.6923 -162.1028)
		(end 52.5907 -162.2044)
		(width 0.127)
		(layer "B.Cu")
		(net "ADC_P3V3_M2")
	)
	(segment
		(start 52.6923 -161.1376)
		(end 52.6923 -160.6042)
		(width 0.127)
		(layer "B.Cu")
		(net "ADC_P3V3_M2")
	)
	(segment
		(start 52.6923 -157.988)
		(end 52.6923 -156.461968)
		(width 0.127)
		(layer "B.Cu")
		(net "ADC_P3V3_M2")
	)
	(segment
		(start 52.6923 -160.6042)
		(end 53.086 -160.2105)
		(width 0.127)
		(layer "B.Cu")
		(net "ADC_P3V3_M2")
	)
	(segment
		(start 53.086 -160.2105)
		(end 53.086 -158.4452)
		(width 0.127)
		(layer "B.Cu")
		(net "ADC_P3V3_M2")
	)
	(segment
		(start 52.6923 -156.461968)
		(end 53.135022 -156.019246)
		(width 0.127)
		(layer "B.Cu")
		(net "ADC_P3V3_M2")
	)
	(segment
		(start 52.5907 -162.2044)
		(end 52.5907 -163.1442)
		(width 0.127)
		(layer "B.Cu")
		(net "ADC_P3V3_M2")
	)
	(segment
		(start 52.6923 -158.0515)
		(end 52.6923 -157.988)
		(width 0.127)
		(layer "B.Cu")
		(net "ADC_P3V3_M2")
	)
	(segment
		(start 53.086 -158.4452)
		(end 52.6923 -158.0515)
		(width 0.127)
		(layer "B.Cu")
		(net "ADC_P3V3_M2")
	)
	(segment
		(start 52.6923 -162.1028)
		(end 52.6923 -161.1376)
		(width 0.127)
		(layer "B.Cu")
		(net "ADC_P3V3_M2")
	)
	(segment
		(start 51.299872 -151.000206)
		(end 51.699668 -151.400002)
		(width 0.127)
		(layer "F.Cu")
		(net "ADC_P3V3")
	)
	(segment
		(start 51.8414 -161.544)
		(end 51.8414 -162.0393)
		(width 0.127)
		(layer "F.Cu")
		(net "ADC_P3V3")
	)
	(segment
		(start 51.299872 -150.999952)
		(end 51.299872 -151.000206)
		(width 0.127)
		(layer "F.Cu")
		(net "ADC_P3V3")
	)
	(segment
		(start 51.8414 -162.0393)
		(end 52.8066 -162.0393)
		(width 0.127)
		(layer "F.Cu")
		(net "ADC_P3V3")
	)
	(segment
		(start 53.771292 -162.0393)
		(end 53.773324 -162.037268)
		(width 0.127)
		(layer "F.Cu")
		(net "ADC_P3V3")
	)
	(segment
		(start 50.8254 -160.8582)
		(end 51.1048 -161.1376)
		(width 0.127)
		(layer "F.Cu")
		(net "ADC_P3V3")
	)
	(segment
		(start 52.8066 -162.0393)
		(end 53.771292 -162.0393)
		(width 0.127)
		(layer "F.Cu")
		(net "ADC_P3V3")
	)
	(segment
		(start 51.435 -161.1376)
		(end 51.8414 -161.544)
		(width 0.127)
		(layer "F.Cu")
		(net "ADC_P3V3")
	)
	(segment
		(start 51.1048 -161.1376)
		(end 51.435 -161.1376)
		(width 0.127)
		(layer "F.Cu")
		(net "ADC_P3V3")
	)
	(via
		(at 51.699668 -151.400002)
		(size 0.4572)
		(drill 0.2032)
		(layers "F.Cu" "B.Cu")
		(net "ADC_P3V3")
	)
	(via
		(at 50.8254 -160.8582)
		(size 0.508)
		(drill 0.254)
		(layers "F.Cu" "B.Cu")
		(net "ADC_P3V3")
	)
	(via
		(at 52.5272 -159.269938)
		(size 0.6096)
		(drill 0.3048)
		(layers "F.Cu" "B.Cu")
		(net "ADC_P3V3")
	)
	(segment
		(start 51.293522 -153.148538)
		(end 51.306222 -153.161238)
		(width 0.127)
		(layer "B.Cu")
		(net "ADC_P3V3")
	)
	(segment
		(start 51.844448 -153.393648)
		(end 52.2605 -153.8097)
		(width 0.127)
		(layer "B.Cu")
		(net "ADC_P3V3")
	)
	(segment
		(start 52.0827 -160.4391)
		(end 51.2445 -160.4391)
		(width 0.127)
		(layer "B.Cu")
		(net "ADC_P3V3")
	)
	(segment
		(start 52.5272 -159.269938)
		(end 52.5272 -159.9946)
		(width 0.127)
		(layer "B.Cu")
		(net "ADC_P3V3")
	)
	(segment
		(start 52.0573 -156.5783)
		(end 52.0573 -158.1785)
		(width 0.127)
		(layer "B.Cu")
		(net "ADC_P3V3")
	)
	(segment
		(start 51.306222 -153.161238)
		(end 51.306222 -153.16327)
		(width 0.127)
		(layer "B.Cu")
		(net "ADC_P3V3")
	)
	(segment
		(start 51.306222 -153.16327)
		(end 51.5366 -153.393648)
		(width 0.127)
		(layer "B.Cu")
		(net "ADC_P3V3")
	)
	(segment
		(start 51.293522 -151.806148)
		(end 51.293522 -153.148538)
		(width 0.127)
		(layer "B.Cu")
		(net "ADC_P3V3")
	)
	(segment
		(start 52.5272 -158.6484)
		(end 52.5272 -159.269938)
		(width 0.127)
		(layer "B.Cu")
		(net "ADC_P3V3")
	)
	(segment
		(start 52.2605 -156.3751)
		(end 52.0573 -156.5783)
		(width 0.127)
		(layer "B.Cu")
		(net "ADC_P3V3")
	)
	(segment
		(start 51.5366 -153.393648)
		(end 51.844448 -153.393648)
		(width 0.127)
		(layer "B.Cu")
		(net "ADC_P3V3")
	)
	(segment
		(start 52.5272 -159.9946)
		(end 52.0827 -160.4391)
		(width 0.127)
		(layer "B.Cu")
		(net "ADC_P3V3")
	)
	(segment
		(start 51.699668 -151.400002)
		(end 51.293522 -151.806148)
		(width 0.127)
		(layer "B.Cu")
		(net "ADC_P3V3")
	)
	(segment
		(start 52.2605 -153.8097)
		(end 52.2605 -156.3751)
		(width 0.127)
		(layer "B.Cu")
		(net "ADC_P3V3")
	)
	(segment
		(start 51.2445 -160.4391)
		(end 50.8254 -160.8582)
		(width 0.127)
		(layer "B.Cu")
		(net "ADC_P3V3")
	)
	(segment
		(start 52.0573 -158.1785)
		(end 52.5272 -158.6484)
		(width 0.127)
		(layer "B.Cu")
		(net "ADC_P3V3")
	)
	(segment
		(start 52.099972 -152.599898)
		(end 51.699922 -152.999948)
		(width 0.127)
		(layer "F.Cu")
		(net "ADC_P1V8")
	)
	(via
		(at 55.4228 -154.813)
		(size 0.508)
		(drill 0.254)
		(layers "F.Cu" "B.Cu")
		(net "ADC_P1V8")
	)
	(via
		(at 51.699922 -152.999948)
		(size 0.4572)
		(drill 0.2032)
		(layers "F.Cu" "B.Cu")
		(net "ADC_P1V8")
	)
	(segment
		(start 55.626 -156.845)
		(end 55.4228 -156.6418)
		(width 0.127)
		(layer "B.Cu")
		(net "ADC_P1V8")
	)
	(segment
		(start 55.4228 -156.6418)
		(end 55.4228 -154.813)
		(width 0.127)
		(layer "B.Cu")
		(net "ADC_P1V8")
	)
	(segment
		(start 53.512974 -154.813)
		(end 55.4228 -154.813)
		(width 0.127)
		(layer "In2.Cu")
		(net "ADC_P1V8")
	)
	(segment
		(start 51.699922 -152.999948)
		(end 53.512974 -154.813)
		(width 0.127)
		(layer "In2.Cu")
		(net "ADC_P1V8")
	)
	(segment
		(start 27.559 -123.7615)
		(end 27.559 -122.4915)
		(width 0.127)
		(layer "F.Cu")
		(net "WP_DISABLE")
	)
	(segment
		(start 65.278 -177.056034)
		(end 65.626234 -176.7078)
		(width 0.4064)
		(layer "F.Cu")
		(net "VREF_2V2")
	)
	(segment
		(start 65.626234 -177.868834)
		(end 65.626234 -178.997356)
		(width 0.4064)
		(layer "F.Cu")
		(net "VREF_2V2")
	)
	(segment
		(start 65.626234 -178.997356)
		(end 65.641474 -179.012596)
		(width 0.4064)
		(layer "F.Cu")
		(net "VREF_2V2")
	)
	(segment
		(start 65.278 -177.5206)
		(end 65.278 -177.056034)
		(width 0.4064)
		(layer "F.Cu")
		(net "VREF_2V2")
	)
	(segment
		(start 65.644268 -179.01539)
		(end 65.641474 -179.012596)
		(width 0.508)
		(layer "F.Cu")
		(net "VREF_2V2")
	)
	(segment
		(start 66.71183 -179.01539)
		(end 65.644268 -179.01539)
		(width 0.508)
		(layer "F.Cu")
		(net "VREF_2V2")
	)
	(segment
		(start 65.626234 -176.7078)
		(end 65.626234 -175.913796)
		(width 0.4064)
		(layer "F.Cu")
		(net "VREF_2V2")
	)
	(segment
		(start 65.278 -177.5206)
		(end 65.626234 -177.868834)
		(width 0.4064)
		(layer "F.Cu")
		(net "VREF_2V2")
	)
	(via
		(at 65.278 -177.5206)
		(size 0.6604)
		(drill 0.3302)
		(layers "F.Cu" "B.Cu")
		(net "VREF_2V2")
	)
	(segment
		(start 93.330522 -159.383984)
		(end 93.251782 -159.305244)
		(width 0.14605)
		(layer "F.Cu")
		(net "USB_COMP_DP")
	)
	(segment
		(start 113.347246 -23.367492)
		(end 113.499646 -23.215092)
		(width 0.14605)
		(layer "F.Cu")
		(net "USB_COMP_DP")
	)
	(segment
		(start 115.04422 -30.114748)
		(end 115.04422 -44.297854)
		(width 0.14605)
		(layer "F.Cu")
		(net "USB_COMP_DP")
	)
	(segment
		(start 109.677962 -23.215092)
		(end 111.575596 -23.215092)
		(width 0.14605)
		(layer "F.Cu")
		(net "USB_COMP_DP")
	)
	(segment
		(start 116.052346 -26.873454)
		(end 114.6048 -28.321)
		(width 0.14605)
		(layer "F.Cu")
		(net "USB_COMP_DP")
	)
	(segment
		(start 111.575596 -23.215092)
		(end 111.727996 -23.367492)
		(width 0.14605)
		(layer "F.Cu")
		(net "USB_COMP_DP")
	)
	(segment
		(start 102.736142 -39.597584)
		(end 102.40391 -39.265352)
		(width 0.14605)
		(layer "F.Cu")
		(net "USB_COMP_DP")
	)
	(segment
		(start 104.39781 -25.239472)
		(end 107.653582 -25.239472)
		(width 0.14605)
		(layer "F.Cu")
		(net "USB_COMP_DP")
	)
	(segment
		(start 112.756696 -23.215092)
		(end 112.909096 -23.367492)
		(width 0.14605)
		(layer "F.Cu")
		(net "USB_COMP_DP")
	)
	(segment
		(start 117.1956 -26.873454)
		(end 116.052346 -26.873454)
		(width 0.14605)
		(layer "F.Cu")
		(net "USB_COMP_DP")
	)
	(segment
		(start 113.499646 -23.215092)
		(end 113.937796 -23.215092)
		(width 0.14605)
		(layer "F.Cu")
		(net "USB_COMP_DP")
	)
	(segment
		(start 118.2878 -24.006556)
		(end 118.2878 -25.781254)
		(width 0.14605)
		(layer "F.Cu")
		(net "USB_COMP_DP")
	)
	(segment
		(start 114.680746 -23.215092)
		(end 117.496336 -23.215092)
		(width 0.14605)
		(layer "F.Cu")
		(net "USB_COMP_DP")
	)
	(segment
		(start 115.04422 -44.297854)
		(end 114.797332 -44.544742)
		(width 0.14605)
		(layer "F.Cu")
		(net "USB_COMP_DP")
	)
	(segment
		(start 112.166146 -23.367492)
		(end 112.318546 -23.215092)
		(width 0.14605)
		(layer "F.Cu")
		(net "USB_COMP_DP")
	)
	(segment
		(start 114.3 -44.398692)
		(end 114.3 -44.000166)
		(width 0.14605)
		(layer "F.Cu")
		(net "USB_COMP_DP")
	)
	(segment
		(start 97.272094 -164.057076)
		(end 93.330522 -160.115504)
		(width 0.14605)
		(layer "F.Cu")
		(net "USB_COMP_DP")
	)
	(segment
		(start 112.909096 -23.367492)
		(end 113.347246 -23.367492)
		(width 0.14605)
		(layer "F.Cu")
		(net "USB_COMP_DP")
	)
	(segment
		(start 114.44605 -44.544742)
		(end 114.3 -44.398692)
		(width 0.14605)
		(layer "F.Cu")
		(net "USB_COMP_DP")
	)
	(segment
		(start 114.528346 -23.367492)
		(end 114.680746 -23.215092)
		(width 0.14605)
		(layer "F.Cu")
		(net "USB_COMP_DP")
	)
	(segment
		(start 98.637852 -164.375846)
		(end 98.319082 -164.057076)
		(width 0.14605)
		(layer "F.Cu")
		(net "USB_COMP_DP")
	)
	(segment
		(start 118.2878 -25.781254)
		(end 117.1956 -26.873454)
		(width 0.14605)
		(layer "F.Cu")
		(net "USB_COMP_DP")
	)
	(segment
		(start 107.653582 -25.239472)
		(end 109.677962 -23.215092)
		(width 0.14605)
		(layer "F.Cu")
		(net "USB_COMP_DP")
	)
	(segment
		(start 102.40391 -39.265352)
		(end 102.40391 -27.233372)
		(width 0.14605)
		(layer "F.Cu")
		(net "USB_COMP_DP")
	)
	(segment
		(start 93.330522 -160.115504)
		(end 93.330522 -159.383984)
		(width 0.14605)
		(layer "F.Cu")
		(net "USB_COMP_DP")
	)
	(segment
		(start 114.090196 -23.367492)
		(end 114.528346 -23.367492)
		(width 0.14605)
		(layer "F.Cu")
		(net "USB_COMP_DP")
	)
	(segment
		(start 114.6048 -28.321)
		(end 114.6048 -29.675328)
		(width 0.14605)
		(layer "F.Cu")
		(net "USB_COMP_DP")
	)
	(segment
		(start 93.251782 -159.305244)
		(end 93.251782 -158.47568)
		(width 0.14605)
		(layer "F.Cu")
		(net "USB_COMP_DP")
	)
	(segment
		(start 117.496336 -23.215092)
		(end 118.2878 -24.006556)
		(width 0.14605)
		(layer "F.Cu")
		(net "USB_COMP_DP")
	)
	(segment
		(start 112.318546 -23.215092)
		(end 112.756696 -23.215092)
		(width 0.14605)
		(layer "F.Cu")
		(net "USB_COMP_DP")
	)
	(segment
		(start 113.937796 -23.215092)
		(end 114.090196 -23.367492)
		(width 0.14605)
		(layer "F.Cu")
		(net "USB_COMP_DP")
	)
	(segment
		(start 102.40391 -27.233372)
		(end 104.39781 -25.239472)
		(width 0.14605)
		(layer "F.Cu")
		(net "USB_COMP_DP")
	)
	(segment
		(start 111.727996 -23.367492)
		(end 112.166146 -23.367492)
		(width 0.14605)
		(layer "F.Cu")
		(net "USB_COMP_DP")
	)
	(segment
		(start 114.6048 -29.675328)
		(end 115.04422 -30.114748)
		(width 0.14605)
		(layer "F.Cu")
		(net "USB_COMP_DP")
	)
	(segment
		(start 114.797332 -44.544742)
		(end 114.44605 -44.544742)
		(width 0.14605)
		(layer "F.Cu")
		(net "USB_COMP_DP")
	)
	(segment
		(start 98.319082 -164.057076)
		(end 97.272094 -164.057076)
		(width 0.14605)
		(layer "F.Cu")
		(net "USB_COMP_DP")
	)
	(via
		(at 98.637852 -164.375846)
		(size 0.508)
		(drill 0.254)
		(layers "F.Cu" "B.Cu")
		(net "USB_COMP_DP")
	)
	(via
		(at 102.736142 -39.597584)
		(size 0.508)
		(drill 0.254)
		(layers "F.Cu" "B.Cu")
		(net "USB_COMP_DP")
	)
	(segment
		(start 94.3102 -83.01736)
		(end 102.01275 -75.31481)
		(width 0.14605)
		(layer "B.Cu")
		(net "USB_COMP_DP")
	)
	(segment
		(start 99.349814 -127.948436)
		(end 98.745802 -127.344424)
		(width 0.14605)
		(layer "B.Cu")
		(net "USB_COMP_DP")
	)
	(segment
		(start 99.349814 -147.28952)
		(end 99.349814 -127.948436)
		(width 0.14605)
		(layer "B.Cu")
		(net "USB_COMP_DP")
	)
	(segment
		(start 98.986848 -164.02685)
		(end 99.722178 -164.02685)
		(width 0.14605)
		(layer "B.Cu")
		(net "USB_COMP_DP")
	)
	(segment
		(start 102.412546 -39.92118)
		(end 102.736142 -39.597584)
		(width 0.14605)
		(layer "B.Cu")
		(net "USB_COMP_DP")
	)
	(segment
		(start 102.01275 -75.31481)
		(end 102.01275 -44.553632)
		(width 0.14605)
		(layer "B.Cu")
		(net "USB_COMP_DP")
	)
	(segment
		(start 100.126292 -155.389072)
		(end 99.799648 -155.062428)
		(width 0.14605)
		(layer "B.Cu")
		(net "USB_COMP_DP")
	)
	(segment
		(start 99.799648 -155.062428)
		(end 99.799648 -147.739354)
		(width 0.14605)
		(layer "B.Cu")
		(net "USB_COMP_DP")
	)
	(segment
		(start 98.0186 -125.308106)
		(end 98.0186 -120.7008)
		(width 0.14605)
		(layer "B.Cu")
		(net "USB_COMP_DP")
	)
	(segment
		(start 98.637852 -164.375846)
		(end 98.986848 -164.02685)
		(width 0.14605)
		(layer "B.Cu")
		(net "USB_COMP_DP")
	)
	(segment
		(start 102.412546 -44.153836)
		(end 102.412546 -39.92118)
		(width 0.14605)
		(layer "B.Cu")
		(net "USB_COMP_DP")
	)
	(segment
		(start 99.342702 -119.376698)
		(end 99.342702 -92.281502)
		(width 0.14605)
		(layer "B.Cu")
		(net "USB_COMP_DP")
	)
	(segment
		(start 99.342702 -92.281502)
		(end 94.3102 -87.249)
		(width 0.14605)
		(layer "B.Cu")
		(net "USB_COMP_DP")
	)
	(segment
		(start 99.799648 -147.739354)
		(end 99.349814 -147.28952)
		(width 0.14605)
		(layer "B.Cu")
		(net "USB_COMP_DP")
	)
	(segment
		(start 98.0186 -120.7008)
		(end 99.342702 -119.376698)
		(width 0.14605)
		(layer "B.Cu")
		(net "USB_COMP_DP")
	)
	(segment
		(start 102.01275 -44.553632)
		(end 102.412546 -44.153836)
		(width 0.14605)
		(layer "B.Cu")
		(net "USB_COMP_DP")
	)
	(segment
		(start 98.745802 -127.344424)
		(end 98.745802 -126.035308)
		(width 0.14605)
		(layer "B.Cu")
		(net "USB_COMP_DP")
	)
	(segment
		(start 98.745802 -126.035308)
		(end 98.0186 -125.308106)
		(width 0.14605)
		(layer "B.Cu")
		(net "USB_COMP_DP")
	)
	(segment
		(start 94.3102 -87.249)
		(end 94.3102 -83.01736)
		(width 0.14605)
		(layer "B.Cu")
		(net "USB_COMP_DP")
	)
	(segment
		(start 99.722178 -164.02685)
		(end 100.126292 -163.622736)
		(width 0.14605)
		(layer "B.Cu")
		(net "USB_COMP_DP")
	)
	(segment
		(start 100.126292 -163.622736)
		(end 100.126292 -155.389072)
		(width 0.14605)
		(layer "B.Cu")
		(net "USB_COMP_DP")
	)
	(segment
		(start 117.625368 -22.903942)
		(end 118.59895 -23.877524)
		(width 0.14605)
		(layer "F.Cu")
		(net "USB_COMP_DN")
	)
	(segment
		(start 93.641672 -159.415226)
		(end 93.751654 -159.305244)
		(width 0.14605)
		(layer "F.Cu")
		(net "USB_COMP_DN")
	)
	(segment
		(start 101.834696 -39.597584)
		(end 102.09276 -39.33952)
		(width 0.14605)
		(layer "F.Cu")
		(net "USB_COMP_DN")
	)
	(segment
		(start 102.09276 -39.33952)
		(end 102.09276 -27.10434)
		(width 0.14605)
		(layer "F.Cu")
		(net "USB_COMP_DN")
	)
	(segment
		(start 114.3 -45.001942)
		(end 114.3 -45.39996)
		(width 0.14605)
		(layer "F.Cu")
		(net "USB_COMP_DN")
	)
	(segment
		(start 102.09276 -27.10434)
		(end 104.268778 -24.928322)
		(width 0.14605)
		(layer "F.Cu")
		(net "USB_COMP_DN")
	)
	(segment
		(start 118.59895 -23.877524)
		(end 118.59895 -25.910286)
		(width 0.14605)
		(layer "F.Cu")
		(net "USB_COMP_DN")
	)
	(segment
		(start 109.54893 -22.903942)
		(end 117.625368 -22.903942)
		(width 0.14605)
		(layer "F.Cu")
		(net "USB_COMP_DN")
	)
	(segment
		(start 115.35537 -29.985716)
		(end 115.35537 -44.426886)
		(width 0.14605)
		(layer "F.Cu")
		(net "USB_COMP_DN")
	)
	(segment
		(start 107.52455 -24.928322)
		(end 109.54893 -22.903942)
		(width 0.14605)
		(layer "F.Cu")
		(net "USB_COMP_DN")
	)
	(segment
		(start 97.401126 -163.745926)
		(end 93.641672 -159.986472)
		(width 0.14605)
		(layer "F.Cu")
		(net "USB_COMP_DN")
	)
	(segment
		(start 116.181378 -27.184604)
		(end 114.91595 -28.450032)
		(width 0.14605)
		(layer "F.Cu")
		(net "USB_COMP_DN")
	)
	(segment
		(start 115.35537 -44.426886)
		(end 114.926364 -44.855892)
		(width 0.14605)
		(layer "F.Cu")
		(net "USB_COMP_DN")
	)
	(segment
		(start 114.91595 -28.450032)
		(end 114.91595 -29.546296)
		(width 0.14605)
		(layer "F.Cu")
		(net "USB_COMP_DN")
	)
	(segment
		(start 117.324632 -27.184604)
		(end 116.181378 -27.184604)
		(width 0.14605)
		(layer "F.Cu")
		(net "USB_COMP_DN")
	)
	(segment
		(start 118.59895 -25.910286)
		(end 117.324632 -27.184604)
		(width 0.14605)
		(layer "F.Cu")
		(net "USB_COMP_DN")
	)
	(segment
		(start 98.366326 -163.745926)
		(end 97.401126 -163.745926)
		(width 0.14605)
		(layer "F.Cu")
		(net "USB_COMP_DN")
	)
	(segment
		(start 104.268778 -24.928322)
		(end 107.52455 -24.928322)
		(width 0.14605)
		(layer "F.Cu")
		(net "USB_COMP_DN")
	)
	(segment
		(start 93.751654 -159.305244)
		(end 93.751654 -158.47568)
		(width 0.14605)
		(layer "F.Cu")
		(net "USB_COMP_DN")
	)
	(segment
		(start 114.44605 -44.855892)
		(end 114.3 -45.001942)
		(width 0.14605)
		(layer "F.Cu")
		(net "USB_COMP_DN")
	)
	(segment
		(start 114.926364 -44.855892)
		(end 114.44605 -44.855892)
		(width 0.14605)
		(layer "F.Cu")
		(net "USB_COMP_DN")
	)
	(segment
		(start 93.641672 -159.986472)
		(end 93.641672 -159.415226)
		(width 0.14605)
		(layer "F.Cu")
		(net "USB_COMP_DN")
	)
	(segment
		(start 98.637852 -163.4744)
		(end 98.366326 -163.745926)
		(width 0.14605)
		(layer "F.Cu")
		(net "USB_COMP_DN")
	)
	(segment
		(start 114.91595 -29.546296)
		(end 115.35537 -29.985716)
		(width 0.14605)
		(layer "F.Cu")
		(net "USB_COMP_DN")
	)
	(via
		(at 98.637852 -163.4744)
		(size 0.508)
		(drill 0.254)
		(layers "F.Cu" "B.Cu")
		(net "USB_COMP_DN")
	)
	(via
		(at 101.834696 -39.597584)
		(size 0.508)
		(drill 0.254)
		(layers "F.Cu" "B.Cu")
		(net "USB_COMP_DN")
	)
	(segment
		(start 102.101396 -44.024804)
		(end 102.101396 -39.864284)
		(width 0.14605)
		(layer "B.Cu")
		(net "USB_COMP_DN")
	)
	(segment
		(start 99.038664 -128.077468)
		(end 98.434652 -127.473456)
		(width 0.14605)
		(layer "B.Cu")
		(net "USB_COMP_DN")
	)
	(segment
		(start 93.99905 -82.888328)
		(end 101.7016 -75.185778)
		(width 0.14605)
		(layer "B.Cu")
		(net "USB_COMP_DN")
	)
	(segment
		(start 99.488498 -147.868386)
		(end 99.038664 -147.418552)
		(width 0.14605)
		(layer "B.Cu")
		(net "USB_COMP_DN")
	)
	(segment
		(start 93.99905 -87.378032)
		(end 93.99905 -82.888328)
		(width 0.14605)
		(layer "B.Cu")
		(net "USB_COMP_DN")
	)
	(segment
		(start 99.593146 -163.7157)
		(end 99.815142 -163.493704)
		(width 0.14605)
		(layer "B.Cu")
		(net "USB_COMP_DN")
	)
	(segment
		(start 99.815142 -163.493704)
		(end 99.815142 -155.518104)
		(width 0.14605)
		(layer "B.Cu")
		(net "USB_COMP_DN")
	)
	(segment
		(start 98.879152 -163.7157)
		(end 99.593146 -163.7157)
		(width 0.14605)
		(layer "B.Cu")
		(net "USB_COMP_DN")
	)
	(segment
		(start 98.434652 -127.473456)
		(end 98.434652 -126.16434)
		(width 0.14605)
		(layer "B.Cu")
		(net "USB_COMP_DN")
	)
	(segment
		(start 101.7016 -44.4246)
		(end 102.101396 -44.024804)
		(width 0.14605)
		(layer "B.Cu")
		(net "USB_COMP_DN")
	)
	(segment
		(start 98.637852 -163.4744)
		(end 98.879152 -163.7157)
		(width 0.14605)
		(layer "B.Cu")
		(net "USB_COMP_DN")
	)
	(segment
		(start 99.815142 -155.518104)
		(end 99.488244 -155.191206)
		(width 0.14605)
		(layer "B.Cu")
		(net "USB_COMP_DN")
	)
	(segment
		(start 102.101396 -39.864284)
		(end 101.834696 -39.597584)
		(width 0.14605)
		(layer "B.Cu")
		(net "USB_COMP_DN")
	)
	(segment
		(start 97.70745 -120.571768)
		(end 99.031552 -119.247666)
		(width 0.14605)
		(layer "B.Cu")
		(net "USB_COMP_DN")
	)
	(segment
		(start 101.7016 -75.185778)
		(end 101.7016 -44.4246)
		(width 0.14605)
		(layer "B.Cu")
		(net "USB_COMP_DN")
	)
	(segment
		(start 99.488244 -154.93365)
		(end 99.488498 -154.933396)
		(width 0.14605)
		(layer "B.Cu")
		(net "USB_COMP_DN")
	)
	(segment
		(start 97.70745 -125.437138)
		(end 97.70745 -120.571768)
		(width 0.14605)
		(layer "B.Cu")
		(net "USB_COMP_DN")
	)
	(segment
		(start 99.488244 -155.191206)
		(end 99.488244 -154.93365)
		(width 0.14605)
		(layer "B.Cu")
		(net "USB_COMP_DN")
	)
	(segment
		(start 99.031552 -92.410534)
		(end 93.99905 -87.378032)
		(width 0.14605)
		(layer "B.Cu")
		(net "USB_COMP_DN")
	)
	(segment
		(start 98.434652 -126.16434)
		(end 97.70745 -125.437138)
		(width 0.14605)
		(layer "B.Cu")
		(net "USB_COMP_DN")
	)
	(segment
		(start 99.038664 -147.418552)
		(end 99.038664 -128.077468)
		(width 0.14605)
		(layer "B.Cu")
		(net "USB_COMP_DN")
	)
	(segment
		(start 99.488498 -154.933396)
		(end 99.488498 -147.868386)
		(width 0.14605)
		(layer "B.Cu")
		(net "USB_COMP_DN")
	)
	(segment
		(start 99.031552 -119.247666)
		(end 99.031552 -92.410534)
		(width 0.14605)
		(layer "B.Cu")
		(net "USB_COMP_DN")
	)
	(via
		(at 92.6084 -170.3832)
		(size 0.508)
		(drill 0.254)
		(layers "F.Cu" "B.Cu")
		(net "UART_COMP_TX")
	)
	(via
		(at 101.5746 -38.6334)
		(size 0.508)
		(drill 0.254)
		(layers "F.Cu" "B.Cu")
		(net "UART_COMP_TX")
	)
	(via
		(at 94.1832 -120.682512)
		(size 0.508)
		(drill 0.254)
		(layers "F.Cu" "B.Cu")
		(net "UART_COMP_TX")
	)
	(segment
		(start 91.689682 -171.118784)
		(end 91.872816 -171.118784)
		(width 0.127)
		(layer "B.Cu")
		(net "UART_COMP_TX")
	)
	(segment
		(start 91.872816 -171.118784)
		(end 92.6084 -170.3832)
		(width 0.127)
		(layer "B.Cu")
		(net "UART_COMP_TX")
	)
	(segment
		(start 95.190818 -126.957074)
		(end 94.16288 -125.929136)
		(width 0.127)
		(layer "In2.Cu")
		(net "UART_COMP_TX")
	)
	(segment
		(start 95.1738 -167.828976)
		(end 96.999552 -166.003224)
		(width 0.127)
		(layer "In2.Cu")
		(net "UART_COMP_TX")
	)
	(segment
		(start 115.5065 -30.450536)
		(end 115.5065 -38.60673)
		(width 0.127)
		(layer "In2.Cu")
		(net "UART_COMP_TX")
	)
	(segment
		(start 95.313246 -138.700764)
		(end 95.190818 -138.578336)
		(width 0.127)
		(layer "In2.Cu")
		(net "UART_COMP_TX")
	)
	(segment
		(start 95.190818 -138.578336)
		(end 95.190818 -126.957074)
		(width 0.127)
		(layer "In2.Cu")
		(net "UART_COMP_TX")
	)
	(segment
		(start 94.1832 -122.360182)
		(end 94.1832 -120.682512)
		(width 0.127)
		(layer "In2.Cu")
		(net "UART_COMP_TX")
	)
	(segment
		(start 93.5736 -150.90521)
		(end 93.5736 -145.9992)
		(width 0.127)
		(layer "In2.Cu")
		(net "UART_COMP_TX")
	)
	(segment
		(start 95.8469 -158.476442)
		(end 95.8469 -153.17851)
		(width 0.127)
		(layer "In2.Cu")
		(net "UART_COMP_TX")
	)
	(segment
		(start 94.16288 -125.929136)
		(end 94.16288 -122.380502)
		(width 0.127)
		(layer "In2.Cu")
		(net "UART_COMP_TX")
	)
	(segment
		(start 95.1738 -169.409618)
		(end 95.1738 -167.828976)
		(width 0.127)
		(layer "In2.Cu")
		(net "UART_COMP_TX")
	)
	(segment
		(start 96.418654 -159.048196)
		(end 95.8469 -158.476442)
		(width 0.127)
		(layer "In2.Cu")
		(net "UART_COMP_TX")
	)
	(segment
		(start 105.826814 -27.534616)
		(end 112.59058 -27.534616)
		(width 0.127)
		(layer "In2.Cu")
		(net "UART_COMP_TX")
	)
	(segment
		(start 95.313246 -144.259554)
		(end 95.313246 -138.700764)
		(width 0.127)
		(layer "In2.Cu")
		(net "UART_COMP_TX")
	)
	(segment
		(start 94.16288 -122.380502)
		(end 94.1832 -122.360182)
		(width 0.127)
		(layer "In2.Cu")
		(net "UART_COMP_TX")
	)
	(segment
		(start 102.184962 -36.168838)
		(end 102.184962 -31.176468)
		(width 0.127)
		(layer "In2.Cu")
		(net "UART_COMP_TX")
	)
	(segment
		(start 96.418654 -161.553398)
		(end 96.418654 -159.048196)
		(width 0.127)
		(layer "In2.Cu")
		(net "UART_COMP_TX")
	)
	(segment
		(start 92.6084 -170.3832)
		(end 94.200218 -170.3832)
		(width 0.127)
		(layer "In2.Cu")
		(net "UART_COMP_TX")
	)
	(segment
		(start 96.999552 -162.134296)
		(end 96.418654 -161.553398)
		(width 0.127)
		(layer "In2.Cu")
		(net "UART_COMP_TX")
	)
	(segment
		(start 96.999552 -166.003224)
		(end 96.999552 -162.134296)
		(width 0.127)
		(layer "In2.Cu")
		(net "UART_COMP_TX")
	)
	(segment
		(start 95.8469 -153.17851)
		(end 93.5736 -150.90521)
		(width 0.127)
		(layer "In2.Cu")
		(net "UART_COMP_TX")
	)
	(segment
		(start 101.5746 -38.6334)
		(end 101.5746 -36.7792)
		(width 0.127)
		(layer "In2.Cu")
		(net "UART_COMP_TX")
	)
	(segment
		(start 112.59058 -27.534616)
		(end 115.5065 -30.450536)
		(width 0.127)
		(layer "In2.Cu")
		(net "UART_COMP_TX")
	)
	(segment
		(start 93.5736 -145.9992)
		(end 95.313246 -144.259554)
		(width 0.127)
		(layer "In2.Cu")
		(net "UART_COMP_TX")
	)
	(segment
		(start 94.200218 -170.3832)
		(end 95.1738 -169.409618)
		(width 0.127)
		(layer "In2.Cu")
		(net "UART_COMP_TX")
	)
	(segment
		(start 102.184962 -31.176468)
		(end 105.826814 -27.534616)
		(width 0.127)
		(layer "In2.Cu")
		(net "UART_COMP_TX")
	)
	(segment
		(start 115.5065 -38.60673)
		(end 116.099844 -39.200074)
		(width 0.127)
		(layer "In2.Cu")
		(net "UART_COMP_TX")
	)
	(segment
		(start 101.5746 -36.7792)
		(end 102.184962 -36.168838)
		(width 0.127)
		(layer "In2.Cu")
		(net "UART_COMP_TX")
	)
	(segment
		(start 94.2848 -120.3452)
		(end 97.347024 -120.3452)
		(width 0.127)
		(layer "In5.Cu")
		(net "UART_COMP_TX")
	)
	(segment
		(start 100.5332 -40.2082)
		(end 101.5746 -39.1668)
		(width 0.127)
		(layer "In5.Cu")
		(net "UART_COMP_TX")
	)
	(segment
		(start 94.1832 -120.682512)
		(end 94.1832 -120.4468)
		(width 0.127)
		(layer "In5.Cu")
		(net "UART_COMP_TX")
	)
	(segment
		(start 97.231454 -114.6048)
		(end 98.217228 -113.619026)
		(width 0.127)
		(layer "In5.Cu")
		(net "UART_COMP_TX")
	)
	(segment
		(start 100.5332 -56.6928)
		(end 100.5332 -40.2082)
		(width 0.127)
		(layer "In5.Cu")
		(net "UART_COMP_TX")
	)
	(segment
		(start 98.217228 -110.764828)
		(end 98.933 -110.049056)
		(width 0.127)
		(layer "In5.Cu")
		(net "UART_COMP_TX")
	)
	(segment
		(start 98.350324 -121.3485)
		(end 99.3013 -121.3485)
		(width 0.127)
		(layer "In5.Cu")
		(net "UART_COMP_TX")
	)
	(segment
		(start 97.347024 -120.3452)
		(end 98.350324 -121.3485)
		(width 0.127)
		(layer "In5.Cu")
		(net "UART_COMP_TX")
	)
	(segment
		(start 101.5746 -39.1668)
		(end 101.5746 -38.6334)
		(width 0.127)
		(layer "In5.Cu")
		(net "UART_COMP_TX")
	)
	(segment
		(start 99.461828 -121.187972)
		(end 99.461828 -120.444006)
		(width 0.127)
		(layer "In5.Cu")
		(net "UART_COMP_TX")
	)
	(segment
		(start 98.933 -110.049056)
		(end 98.933 -58.293)
		(width 0.127)
		(layer "In5.Cu")
		(net "UART_COMP_TX")
	)
	(segment
		(start 98.933 -58.293)
		(end 100.5332 -56.6928)
		(width 0.127)
		(layer "In5.Cu")
		(net "UART_COMP_TX")
	)
	(segment
		(start 98.0186 -117.772942)
		(end 97.231454 -116.985796)
		(width 0.127)
		(layer "In5.Cu")
		(net "UART_COMP_TX")
	)
	(segment
		(start 99.461828 -120.444006)
		(end 98.0186 -119.000778)
		(width 0.127)
		(layer "In5.Cu")
		(net "UART_COMP_TX")
	)
	(segment
		(start 99.3013 -121.3485)
		(end 99.461828 -121.187972)
		(width 0.127)
		(layer "In5.Cu")
		(net "UART_COMP_TX")
	)
	(segment
		(start 94.1832 -120.4468)
		(end 94.2848 -120.3452)
		(width 0.127)
		(layer "In5.Cu")
		(net "UART_COMP_TX")
	)
	(segment
		(start 97.231454 -116.985796)
		(end 97.231454 -114.6048)
		(width 0.127)
		(layer "In5.Cu")
		(net "UART_COMP_TX")
	)
	(segment
		(start 98.0186 -119.000778)
		(end 98.0186 -117.772942)
		(width 0.127)
		(layer "In5.Cu")
		(net "UART_COMP_TX")
	)
	(segment
		(start 98.217228 -113.619026)
		(end 98.217228 -110.764828)
		(width 0.127)
		(layer "In5.Cu")
		(net "UART_COMP_TX")
	)
	(via
		(at 98.425 -116.3828)
		(size 0.508)
		(drill 0.254)
		(layers "F.Cu" "B.Cu")
		(net "UART_COMP_RX")
	)
	(via
		(at 96.223328 -167.56507)
		(size 0.508)
		(drill 0.254)
		(layers "F.Cu" "B.Cu")
		(net "UART_COMP_RX")
	)
	(segment
		(start 96.223328 -167.56507)
		(end 95.85833 -167.56507)
		(width 0.127)
		(layer "B.Cu")
		(net "UART_COMP_RX")
	)
	(segment
		(start 95.40113 -168.02227)
		(end 91.66479 -168.02227)
		(width 0.127)
		(layer "B.Cu")
		(net "UART_COMP_RX")
	)
	(segment
		(start 95.85833 -167.56507)
		(end 95.40113 -168.02227)
		(width 0.127)
		(layer "B.Cu")
		(net "UART_COMP_RX")
	)
	(segment
		(start 116.099844 -40.600122)
		(end 116.099844 -40.0939)
		(width 0.127)
		(layer "In2.Cu")
		(net "UART_COMP_RX")
	)
	(segment
		(start 116.671344 -29.100526)
		(end 113.327434 -25.756616)
		(width 0.127)
		(layer "In2.Cu")
		(net "UART_COMP_RX")
	)
	(segment
		(start 98.425 -82.769202)
		(end 98.425 -116.3828)
		(width 0.127)
		(layer "In2.Cu")
		(net "UART_COMP_RX")
	)
	(segment
		(start 116.671344 -39.5224)
		(end 116.671344 -29.100526)
		(width 0.127)
		(layer "In2.Cu")
		(net "UART_COMP_RX")
	)
	(segment
		(start 113.327434 -25.756616)
		(end 105.08996 -25.756616)
		(width 0.127)
		(layer "In2.Cu")
		(net "UART_COMP_RX")
	)
	(segment
		(start 105.08996 -25.756616)
		(end 100.255324 -30.591252)
		(width 0.127)
		(layer "In2.Cu")
		(net "UART_COMP_RX")
	)
	(segment
		(start 116.099844 -40.0939)
		(end 116.671344 -39.5224)
		(width 0.127)
		(layer "In2.Cu")
		(net "UART_COMP_RX")
	)
	(segment
		(start 100.255324 -30.591252)
		(end 100.255324 -35.310572)
		(width 0.127)
		(layer "In2.Cu")
		(net "UART_COMP_RX")
	)
	(segment
		(start 100.255324 -35.310572)
		(end 97.79 -37.775896)
		(width 0.127)
		(layer "In2.Cu")
		(net "UART_COMP_RX")
	)
	(segment
		(start 97.297494 -66.938906)
		(end 97.297494 -81.641696)
		(width 0.127)
		(layer "In2.Cu")
		(net "UART_COMP_RX")
	)
	(segment
		(start 97.79 -66.4464)
		(end 97.297494 -66.938906)
		(width 0.127)
		(layer "In2.Cu")
		(net "UART_COMP_RX")
	)
	(segment
		(start 97.297494 -81.641696)
		(end 98.425 -82.769202)
		(width 0.127)
		(layer "In2.Cu")
		(net "UART_COMP_RX")
	)
	(segment
		(start 97.79 -37.775896)
		(end 97.79 -66.4464)
		(width 0.127)
		(layer "In2.Cu")
		(net "UART_COMP_RX")
	)
	(segment
		(start 99.5426 -116.3828)
		(end 101.473 -118.3132)
		(width 0.127)
		(layer "In5.Cu")
		(net "UART_COMP_RX")
	)
	(segment
		(start 101.473 -163.322)
		(end 97.282 -167.513)
		(width 0.127)
		(layer "In5.Cu")
		(net "UART_COMP_RX")
	)
	(segment
		(start 101.473 -118.3132)
		(end 101.473 -163.322)
		(width 0.127)
		(layer "In5.Cu")
		(net "UART_COMP_RX")
	)
	(segment
		(start 97.282 -167.513)
		(end 96.275398 -167.513)
		(width 0.127)
		(layer "In5.Cu")
		(net "UART_COMP_RX")
	)
	(segment
		(start 96.275398 -167.513)
		(end 96.223328 -167.56507)
		(width 0.127)
		(layer "In5.Cu")
		(net "UART_COMP_RX")
	)
	(segment
		(start 98.425 -116.3828)
		(end 99.5426 -116.3828)
		(width 0.127)
		(layer "In5.Cu")
		(net "UART_COMP_RX")
	)
	(via
		(at 89.5604 -171.320206)
		(size 0.6096)
		(drill 0.3048)
		(layers "F.Cu" "B.Cu")
		(net "UART_COMP_R_TX")
	)
	(segment
		(start 89.761822 -171.118784)
		(end 89.5604 -171.320206)
		(width 0.127)
		(layer "B.Cu")
		(net "UART_COMP_R_TX")
	)
	(segment
		(start 89.5604 -171.320206)
		(end 87.690706 -171.320206)
		(width 0.127)
		(layer "B.Cu")
		(net "UART_COMP_R_TX")
	)
	(segment
		(start 90.800682 -171.118784)
		(end 89.761822 -171.118784)
		(width 0.127)
		(layer "B.Cu")
		(net "UART_COMP_R_TX")
	)
	(segment
		(start 90.77579 -168.02227)
		(end 89.20353 -168.02227)
		(width 0.127)
		(layer "B.Cu")
		(net "UART_COMP_R_RX")
	)
	(segment
		(start 89.20353 -168.02227)
		(end 88.506554 -168.719246)
		(width 0.127)
		(layer "B.Cu")
		(net "UART_COMP_R_RX")
	)
	(segment
		(start 88.506554 -168.719246)
		(end 87.690706 -168.719246)
		(width 0.127)
		(layer "B.Cu")
		(net "UART_COMP_R_RX")
	)
	(segment
		(start 97.1042 -131.6736)
		(end 96.7994 -131.9784)
		(width 0.127)
		(layer "F.Cu")
		(net "UART_COMP_OUT_TX")
	)
	(segment
		(start 97.1042 -130.567684)
		(end 97.1042 -131.6736)
		(width 0.127)
		(layer "F.Cu")
		(net "UART_COMP_OUT_TX")
	)
	(segment
		(start 38.5826 -159.5247)
		(end 39.0398 -159.0675)
		(width 0.127)
		(layer "F.Cu")
		(net "UART_COMP_OUT_TX")
	)
	(segment
		(start 36.213288 -160.955228)
		(end 37.418772 -160.955228)
		(width 0.127)
		(layer "F.Cu")
		(net "UART_COMP_OUT_TX")
	)
	(segment
		(start 96.7994 -131.9784)
		(end 95.709232 -131.9784)
		(width 0.127)
		(layer "F.Cu")
		(net "UART_COMP_OUT_TX")
	)
	(segment
		(start 38.5826 -159.7914)
		(end 38.5826 -159.5247)
		(width 0.127)
		(layer "F.Cu")
		(net "UART_COMP_OUT_TX")
	)
	(segment
		(start 37.418772 -160.955228)
		(end 38.5826 -159.7914)
		(width 0.127)
		(layer "F.Cu")
		(net "UART_COMP_OUT_TX")
	)
	(segment
		(start 95.709232 -131.9784)
		(end 95.272352 -132.41528)
		(width 0.127)
		(layer "F.Cu")
		(net "UART_COMP_OUT_TX")
	)
	(segment
		(start 36.213288 -160.793938)
		(end 36.763198 -160.244028)
		(width 0.127)
		(layer "F.Cu")
		(net "UART_COMP_OUT_TX")
	)
	(segment
		(start 95.272352 -132.41528)
		(end 95.272352 -137.995152)
		(width 0.127)
		(layer "F.Cu")
		(net "UART_COMP_OUT_TX")
	)
	(segment
		(start 36.213288 -160.955228)
		(end 36.213288 -160.793938)
		(width 0.127)
		(layer "F.Cu")
		(net "UART_COMP_OUT_TX")
	)
	(segment
		(start 95.272352 -137.995152)
		(end 95.660718 -138.383518)
		(width 0.127)
		(layer "F.Cu")
		(net "UART_COMP_OUT_TX")
	)
	(segment
		(start 95.945706 -130.311906)
		(end 96.848422 -130.311906)
		(width 0.127)
		(layer "F.Cu")
		(net "UART_COMP_OUT_TX")
	)
	(segment
		(start 96.848422 -130.311906)
		(end 97.1042 -130.567684)
		(width 0.127)
		(layer "F.Cu")
		(net "UART_COMP_OUT_TX")
	)
	(via
		(at 97.9678 -148.8694)
		(size 0.6096)
		(drill 0.3048)
		(layers "F.Cu" "B.Cu")
		(net "UART_COMP_OUT_TX")
	)
	(via
		(at 36.763198 -160.244028)
		(size 0.508)
		(drill 0.254)
		(layers "F.Cu" "B.Cu")
		(net "UART_COMP_OUT_TX")
	)
	(via
		(at 97.654364 -168.0591)
		(size 0.508)
		(drill 0.254)
		(layers "F.Cu" "B.Cu")
		(net "UART_COMP_OUT_TX")
	)
	(via
		(at 92.370656 -174.9933)
		(size 0.508)
		(drill 0.254)
		(layers "F.Cu" "B.Cu")
		(net "UART_COMP_OUT_TX")
	)
	(via
		(at 95.660718 -138.383518)
		(size 0.508)
		(drill 0.254)
		(layers "F.Cu" "B.Cu")
		(net "UART_COMP_OUT_TX")
	)
	(segment
		(start 95.3897 -169.545)
		(end 96.168464 -169.545)
		(width 0.127)
		(layer "B.Cu")
		(net "UART_COMP_OUT_TX")
	)
	(segment
		(start 96.80702 -147.016724)
		(end 96.80702 -143.711676)
		(width 0.127)
		(layer "B.Cu")
		(net "UART_COMP_OUT_TX")
	)
	(segment
		(start 95.660718 -142.565374)
		(end 95.660718 -138.383518)
		(width 0.127)
		(layer "B.Cu")
		(net "UART_COMP_OUT_TX")
	)
	(segment
		(start 97.451164 -167.8559)
		(end 97.654364 -168.0591)
		(width 0.127)
		(layer "B.Cu")
		(net "UART_COMP_OUT_TX")
	)
	(segment
		(start 96.80702 -143.711676)
		(end 95.660718 -142.565374)
		(width 0.127)
		(layer "B.Cu")
		(net "UART_COMP_OUT_TX")
	)
	(segment
		(start 93.337888 -170.122596)
		(end 94.812104 -170.122596)
		(width 0.127)
		(layer "B.Cu")
		(net "UART_COMP_OUT_TX")
	)
	(segment
		(start 97.9678 -149.613112)
		(end 98.513392 -150.158704)
		(width 0.127)
		(layer "B.Cu")
		(net "UART_COMP_OUT_TX")
	)
	(segment
		(start 98.513392 -155.595066)
		(end 98.8187 -155.900374)
		(width 0.127)
		(layer "B.Cu")
		(net "UART_COMP_OUT_TX")
	)
	(segment
		(start 88.841834 -170.669966)
		(end 89.764616 -169.747184)
		(width 0.127)
		(layer "B.Cu")
		(net "UART_COMP_OUT_TX")
	)
	(segment
		(start 87.690706 -170.669966)
		(end 88.841834 -170.669966)
		(width 0.127)
		(layer "B.Cu")
		(net "UART_COMP_OUT_TX")
	)
	(segment
		(start 98.8187 -155.900374)
		(end 98.8187 -158.5087)
		(width 0.127)
		(layer "B.Cu")
		(net "UART_COMP_OUT_TX")
	)
	(segment
		(start 89.764616 -169.747184)
		(end 92.962476 -169.747184)
		(width 0.127)
		(layer "B.Cu")
		(net "UART_COMP_OUT_TX")
	)
	(segment
		(start 98.8187 -158.5087)
		(end 97.451164 -159.876236)
		(width 0.127)
		(layer "B.Cu")
		(net "UART_COMP_OUT_TX")
	)
	(segment
		(start 97.451164 -159.876236)
		(end 97.451164 -167.8559)
		(width 0.127)
		(layer "B.Cu")
		(net "UART_COMP_OUT_TX")
	)
	(segment
		(start 94.812104 -170.122596)
		(end 95.3897 -169.545)
		(width 0.127)
		(layer "B.Cu")
		(net "UART_COMP_OUT_TX")
	)
	(segment
		(start 96.168464 -169.545)
		(end 97.654364 -168.0591)
		(width 0.127)
		(layer "B.Cu")
		(net "UART_COMP_OUT_TX")
	)
	(segment
		(start 98.513392 -150.158704)
		(end 98.513392 -155.595066)
		(width 0.127)
		(layer "B.Cu")
		(net "UART_COMP_OUT_TX")
	)
	(segment
		(start 97.9678 -148.8694)
		(end 97.9678 -148.177504)
		(width 0.127)
		(layer "B.Cu")
		(net "UART_COMP_OUT_TX")
	)
	(segment
		(start 92.962476 -169.747184)
		(end 93.337888 -170.122596)
		(width 0.127)
		(layer "B.Cu")
		(net "UART_COMP_OUT_TX")
	)
	(segment
		(start 97.9678 -148.8694)
		(end 97.9678 -149.613112)
		(width 0.127)
		(layer "B.Cu")
		(net "UART_COMP_OUT_TX")
	)
	(segment
		(start 97.9678 -148.177504)
		(end 96.80702 -147.016724)
		(width 0.127)
		(layer "B.Cu")
		(net "UART_COMP_OUT_TX")
	)
	(segment
		(start 97.654364 -169.740326)
		(end 97.654364 -168.0591)
		(width 0.127)
		(layer "In2.Cu")
		(net "UART_COMP_OUT_TX")
	)
	(segment
		(start 92.40139 -174.9933)
		(end 97.654364 -169.740326)
		(width 0.127)
		(layer "In2.Cu")
		(net "UART_COMP_OUT_TX")
	)
	(segment
		(start 92.370656 -174.9933)
		(end 92.40139 -174.9933)
		(width 0.127)
		(layer "In2.Cu")
		(net "UART_COMP_OUT_TX")
	)
	(segment
		(start 44.64431 -165.2016)
		(end 46.77791 -167.3352)
		(width 0.127)
		(layer "In5.Cu")
		(net "UART_COMP_OUT_TX")
	)
	(segment
		(start 59.69 -173.355)
		(end 68.258436 -173.355)
		(width 0.127)
		(layer "In5.Cu")
		(net "UART_COMP_OUT_TX")
	)
	(segment
		(start 46.77791 -167.3352)
		(end 51.188112 -167.3352)
		(width 0.127)
		(layer "In5.Cu")
		(net "UART_COMP_OUT_TX")
	)
	(segment
		(start 41.6306 -165.2016)
		(end 44.64431 -165.2016)
		(width 0.127)
		(layer "In5.Cu")
		(net "UART_COMP_OUT_TX")
	)
	(segment
		(start 36.763198 -160.334198)
		(end 41.6306 -165.2016)
		(width 0.127)
		(layer "In5.Cu")
		(net "UART_COMP_OUT_TX")
	)
	(segment
		(start 68.258436 -173.355)
		(end 68.372736 -173.2407)
		(width 0.127)
		(layer "In5.Cu")
		(net "UART_COMP_OUT_TX")
	)
	(segment
		(start 77.879956 -174.9933)
		(end 92.370656 -174.9933)
		(width 0.127)
		(layer "In5.Cu")
		(net "UART_COMP_OUT_TX")
	)
	(segment
		(start 68.372736 -173.2407)
		(end 76.127356 -173.2407)
		(width 0.127)
		(layer "In5.Cu")
		(net "UART_COMP_OUT_TX")
	)
	(segment
		(start 57.8358 -171.5008)
		(end 59.69 -173.355)
		(width 0.127)
		(layer "In5.Cu")
		(net "UART_COMP_OUT_TX")
	)
	(segment
		(start 55.353712 -171.5008)
		(end 57.8358 -171.5008)
		(width 0.127)
		(layer "In5.Cu")
		(net "UART_COMP_OUT_TX")
	)
	(segment
		(start 76.127356 -173.2407)
		(end 77.879956 -174.9933)
		(width 0.127)
		(layer "In5.Cu")
		(net "UART_COMP_OUT_TX")
	)
	(segment
		(start 36.763198 -160.244028)
		(end 36.763198 -160.334198)
		(width 0.127)
		(layer "In5.Cu")
		(net "UART_COMP_OUT_TX")
	)
	(segment
		(start 51.188112 -167.3352)
		(end 55.353712 -171.5008)
		(width 0.127)
		(layer "In5.Cu")
		(net "UART_COMP_OUT_TX")
	)
	(segment
		(start 92.053664 -123.041664)
		(end 92.52585 -123.51385)
		(width 0.127)
		(layer "F.Cu")
		(net "UART_COMP_IN_RX")
	)
	(segment
		(start 91.326208 -123.02363)
		(end 91.326208 -122.013472)
		(width 0.127)
		(layer "F.Cu")
		(net "UART_COMP_IN_RX")
	)
	(segment
		(start 97.1042 -129.1082)
		(end 96.901254 -129.311146)
		(width 0.127)
		(layer "F.Cu")
		(net "UART_COMP_IN_RX")
	)
	(segment
		(start 96.901254 -129.311146)
		(end 95.945706 -129.311146)
		(width 0.127)
		(layer "F.Cu")
		(net "UART_COMP_IN_RX")
	)
	(segment
		(start 95.95104 -124.965206)
		(end 95.95104 -127.57404)
		(width 0.127)
		(layer "F.Cu")
		(net "UART_COMP_IN_RX")
	)
	(segment
		(start 92.52585 -123.51385)
		(end 93.5736 -124.5616)
		(width 0.127)
		(layer "F.Cu")
		(net "UART_COMP_IN_RX")
	)
	(segment
		(start 91.308174 -123.041664)
		(end 91.326208 -123.02363)
		(width 0.127)
		(layer "F.Cu")
		(net "UART_COMP_IN_RX")
	)
	(segment
		(start 95.95104 -127.57404)
		(end 97.1042 -128.7272)
		(width 0.127)
		(layer "F.Cu")
		(net "UART_COMP_IN_RX")
	)
	(segment
		(start 91.308174 -123.041664)
		(end 92.053664 -123.041664)
		(width 0.127)
		(layer "F.Cu")
		(net "UART_COMP_IN_RX")
	)
	(segment
		(start 93.5736 -124.5616)
		(end 95.547434 -124.5616)
		(width 0.127)
		(layer "F.Cu")
		(net "UART_COMP_IN_RX")
	)
	(segment
		(start 95.547434 -124.5616)
		(end 95.95104 -124.965206)
		(width 0.127)
		(layer "F.Cu")
		(net "UART_COMP_IN_RX")
	)
	(segment
		(start 97.1042 -128.7272)
		(end 97.1042 -129.1082)
		(width 0.127)
		(layer "F.Cu")
		(net "UART_COMP_IN_RX")
	)
	(via
		(at 92.52585 -123.51385)
		(size 0.6604)
		(drill 0.3302)
		(layers "F.Cu" "B.Cu")
		(net "UART_COMP_IN_RX")
	)
	(segment
		(start 90.591894 -130.311906)
		(end 91.805506 -130.311906)
		(width 0.127)
		(layer "F.Cu")
		(net "UART_BMC_TX")
	)
	(segment
		(start 90.3224 -130.429)
		(end 90.4748 -130.429)
		(width 0.127)
		(layer "F.Cu")
		(net "UART_BMC_TX")
	)
	(segment
		(start 90.4748 -130.429)
		(end 90.591894 -130.311906)
		(width 0.127)
		(layer "F.Cu")
		(net "UART_BMC_TX")
	)
	(via
		(at 76.5302 -133.1976)
		(size 0.508)
		(drill 0.254)
		(layers "F.Cu" "B.Cu")
		(net "UART_BMC_TX")
	)
	(via
		(at 90.3224 -130.429)
		(size 0.508)
		(drill 0.254)
		(layers "F.Cu" "B.Cu")
		(net "UART_BMC_TX")
	)
	(via
		(at 74.5744 -159.7914)
		(size 0.508)
		(drill 0.254)
		(layers "F.Cu" "B.Cu")
		(net "UART_BMC_TX")
	)
	(via
		(at 51.7906 -155.9814)
		(size 0.508)
		(drill 0.254)
		(layers "F.Cu" "B.Cu")
		(net "UART_BMC_TX")
	)
	(via
		(at 50.927 -157.988)
		(size 0.6096)
		(drill 0.3048)
		(layers "F.Cu" "B.Cu")
		(net "UART_BMC_TX")
	)
	(segment
		(start 50.927 -157.988)
		(end 51.4223 -157.4927)
		(width 0.127)
		(layer "B.Cu")
		(net "UART_BMC_TX")
	)
	(segment
		(start 50.47107 -158.44393)
		(end 50.47107 -158.956756)
		(width 0.127)
		(layer "B.Cu")
		(net "UART_BMC_TX")
	)
	(segment
		(start 50.927 -157.988)
		(end 50.47107 -158.44393)
		(width 0.127)
		(layer "B.Cu")
		(net "UART_BMC_TX")
	)
	(segment
		(start 50.47107 -158.956756)
		(end 49.516792 -158.956756)
		(width 0.127)
		(layer "B.Cu")
		(net "UART_BMC_TX")
	)
	(segment
		(start 51.4223 -156.3497)
		(end 51.7906 -155.9814)
		(width 0.127)
		(layer "B.Cu")
		(net "UART_BMC_TX")
	)
	(segment
		(start 49.516792 -158.956756)
		(end 49.458372 -159.015176)
		(width 0.127)
		(layer "B.Cu")
		(net "UART_BMC_TX")
	)
	(segment
		(start 51.4223 -157.4927)
		(end 51.4223 -156.3497)
		(width 0.127)
		(layer "B.Cu")
		(net "UART_BMC_TX")
	)
	(segment
		(start 75.697588 -134.030212)
		(end 75.697588 -136.646158)
		(width 0.127)
		(layer "In2.Cu")
		(net "UART_BMC_TX")
	)
	(segment
		(start 76.454 -149.4536)
		(end 76.454 -152.111964)
		(width 0.127)
		(layer "In2.Cu")
		(net "UART_BMC_TX")
	)
	(segment
		(start 75.718416 -140.488416)
		(end 76.105258 -140.875258)
		(width 0.127)
		(layer "In2.Cu")
		(net "UART_BMC_TX")
	)
	(segment
		(start 76.5302 -133.1976)
		(end 75.697588 -134.030212)
		(width 0.127)
		(layer "In2.Cu")
		(net "UART_BMC_TX")
	)
	(segment
		(start 75.6031 -152.962864)
		(end 75.6031 -158.7627)
		(width 0.127)
		(layer "In2.Cu")
		(net "UART_BMC_TX")
	)
	(segment
		(start 75.697588 -136.646158)
		(end 75.404726 -136.93902)
		(width 0.127)
		(layer "In2.Cu")
		(net "UART_BMC_TX")
	)
	(segment
		(start 76.105258 -140.875258)
		(end 76.105258 -149.104858)
		(width 0.127)
		(layer "In2.Cu")
		(net "UART_BMC_TX")
	)
	(segment
		(start 76.454 -152.111964)
		(end 75.6031 -152.962864)
		(width 0.127)
		(layer "In2.Cu")
		(net "UART_BMC_TX")
	)
	(segment
		(start 75.404726 -138.354816)
		(end 75.718416 -138.668506)
		(width 0.127)
		(layer "In2.Cu")
		(net "UART_BMC_TX")
	)
	(segment
		(start 75.6031 -158.7627)
		(end 74.5744 -159.7914)
		(width 0.127)
		(layer "In2.Cu")
		(net "UART_BMC_TX")
	)
	(segment
		(start 76.105258 -149.104858)
		(end 76.454 -149.4536)
		(width 0.127)
		(layer "In2.Cu")
		(net "UART_BMC_TX")
	)
	(segment
		(start 75.718416 -138.668506)
		(end 75.718416 -140.488416)
		(width 0.127)
		(layer "In2.Cu")
		(net "UART_BMC_TX")
	)
	(segment
		(start 75.404726 -136.93902)
		(end 75.404726 -138.354816)
		(width 0.127)
		(layer "In2.Cu")
		(net "UART_BMC_TX")
	)
	(segment
		(start 54.842918 -158.6738)
		(end 54.483 -158.6738)
		(width 0.127)
		(layer "In5.Cu")
		(net "UART_BMC_TX")
	)
	(segment
		(start 64.118744 -160.655)
		(end 62.779656 -160.655)
		(width 0.127)
		(layer "In5.Cu")
		(net "UART_BMC_TX")
	)
	(segment
		(start 65.957958 -160.838642)
		(end 64.302386 -160.838642)
		(width 0.127)
		(layer "In5.Cu")
		(net "UART_BMC_TX")
	)
	(segment
		(start 73.398888 -159.9946)
		(end 66.802 -159.9946)
		(width 0.127)
		(layer "In5.Cu")
		(net "UART_BMC_TX")
	)
	(segment
		(start 54.483 -158.6738)
		(end 51.7906 -155.9814)
		(width 0.127)
		(layer "In5.Cu")
		(net "UART_BMC_TX")
	)
	(segment
		(start 62.779656 -160.655)
		(end 62.693804 -160.740852)
		(width 0.127)
		(layer "In5.Cu")
		(net "UART_BMC_TX")
	)
	(segment
		(start 83.4263 -132.3467)
		(end 80.627982 -132.3467)
		(width 0.127)
		(layer "In5.Cu")
		(net "UART_BMC_TX")
	)
	(segment
		(start 84.5312 -131.2418)
		(end 83.4263 -132.3467)
		(width 0.127)
		(layer "In5.Cu")
		(net "UART_BMC_TX")
	)
	(segment
		(start 73.602088 -159.7914)
		(end 73.398888 -159.9946)
		(width 0.127)
		(layer "In5.Cu")
		(net "UART_BMC_TX")
	)
	(segment
		(start 62.693804 -160.740852)
		(end 56.520334 -160.740852)
		(width 0.127)
		(layer "In5.Cu")
		(net "UART_BMC_TX")
	)
	(segment
		(start 88.006936 -130.429)
		(end 87.194136 -131.2418)
		(width 0.127)
		(layer "In5.Cu")
		(net "UART_BMC_TX")
	)
	(segment
		(start 87.194136 -131.2418)
		(end 84.5312 -131.2418)
		(width 0.127)
		(layer "In5.Cu")
		(net "UART_BMC_TX")
	)
	(segment
		(start 80.3529 -132.6261)
		(end 79.7306 -133.2484)
		(width 0.127)
		(layer "In5.Cu")
		(net "UART_BMC_TX")
	)
	(segment
		(start 55.5244 -159.744918)
		(end 55.5244 -159.355282)
		(width 0.127)
		(layer "In5.Cu")
		(net "UART_BMC_TX")
	)
	(segment
		(start 55.5244 -159.355282)
		(end 54.842918 -158.6738)
		(width 0.127)
		(layer "In5.Cu")
		(net "UART_BMC_TX")
	)
	(segment
		(start 74.5744 -159.7914)
		(end 73.602088 -159.7914)
		(width 0.127)
		(layer "In5.Cu")
		(net "UART_BMC_TX")
	)
	(segment
		(start 66.802 -159.9946)
		(end 65.957958 -160.838642)
		(width 0.127)
		(layer "In5.Cu")
		(net "UART_BMC_TX")
	)
	(segment
		(start 80.3529 -132.621782)
		(end 80.3529 -132.6261)
		(width 0.127)
		(layer "In5.Cu")
		(net "UART_BMC_TX")
	)
	(segment
		(start 79.7306 -133.2484)
		(end 76.581 -133.2484)
		(width 0.127)
		(layer "In5.Cu")
		(net "UART_BMC_TX")
	)
	(segment
		(start 56.520334 -160.740852)
		(end 55.5244 -159.744918)
		(width 0.127)
		(layer "In5.Cu")
		(net "UART_BMC_TX")
	)
	(segment
		(start 90.3224 -130.429)
		(end 88.006936 -130.429)
		(width 0.127)
		(layer "In5.Cu")
		(net "UART_BMC_TX")
	)
	(segment
		(start 64.302386 -160.838642)
		(end 64.118744 -160.655)
		(width 0.127)
		(layer "In5.Cu")
		(net "UART_BMC_TX")
	)
	(segment
		(start 76.581 -133.2484)
		(end 76.5302 -133.1976)
		(width 0.127)
		(layer "In5.Cu")
		(net "UART_BMC_TX")
	)
	(segment
		(start 80.627982 -132.3467)
		(end 80.3529 -132.621782)
		(width 0.127)
		(layer "In5.Cu")
		(net "UART_BMC_TX")
	)
	(segment
		(start 90.3224 -128.6764)
		(end 90.957146 -129.311146)
		(width 0.127)
		(layer "F.Cu")
		(net "UART_BMC_RX")
	)
	(segment
		(start 90.957146 -129.311146)
		(end 91.805506 -129.311146)
		(width 0.127)
		(layer "F.Cu")
		(net "UART_BMC_RX")
	)
	(via
		(at 49.8094 -155.9687)
		(size 0.508)
		(drill 0.254)
		(layers "F.Cu" "B.Cu")
		(net "UART_BMC_RX")
	)
	(via
		(at 75.7428 -132.3594)
		(size 0.508)
		(drill 0.254)
		(layers "F.Cu" "B.Cu")
		(net "UART_BMC_RX")
	)
	(via
		(at 74.549 -158.9024)
		(size 0.508)
		(drill 0.254)
		(layers "F.Cu" "B.Cu")
		(net "UART_BMC_RX")
	)
	(via
		(at 90.3224 -128.6764)
		(size 0.508)
		(drill 0.254)
		(layers "F.Cu" "B.Cu")
		(net "UART_BMC_RX")
	)
	(via
		(at 49.657 -156.972)
		(size 0.6096)
		(drill 0.3048)
		(layers "F.Cu" "B.Cu")
		(net "UART_BMC_RX")
	)
	(segment
		(start 49.911 -155.2829)
		(end 49.911 -155.8671)
		(width 0.127)
		(layer "B.Cu")
		(net "UART_BMC_RX")
	)
	(segment
		(start 49.911 -155.8671)
		(end 49.8094 -155.9687)
		(width 0.127)
		(layer "B.Cu")
		(net "UART_BMC_RX")
	)
	(segment
		(start 49.657 -156.972)
		(end 49.8094 -156.8196)
		(width 0.127)
		(layer "B.Cu")
		(net "UART_BMC_RX")
	)
	(segment
		(start 49.8094 -156.8196)
		(end 49.8094 -155.9687)
		(width 0.127)
		(layer "B.Cu")
		(net "UART_BMC_RX")
	)
	(segment
		(start 75.062588 -136.383014)
		(end 74.769726 -136.675876)
		(width 0.127)
		(layer "In2.Cu")
		(net "UART_BMC_RX")
	)
	(segment
		(start 75.274424 -143.432784)
		(end 75.274424 -152.393396)
		(width 0.127)
		(layer "In2.Cu")
		(net "UART_BMC_RX")
	)
	(segment
		(start 75.7428 -132.3594)
		(end 75.601576 -132.3594)
		(width 0.127)
		(layer "In2.Cu")
		(net "UART_BMC_RX")
	)
	(segment
		(start 74.9681 -152.69972)
		(end 74.9681 -158.4833)
		(width 0.127)
		(layer "In2.Cu")
		(net "UART_BMC_RX")
	)
	(segment
		(start 75.062588 -133.124956)
		(end 75.062588 -136.383014)
		(width 0.127)
		(layer "In2.Cu")
		(net "UART_BMC_RX")
	)
	(segment
		(start 75.184254 -133.00329)
		(end 75.062588 -133.124956)
		(width 0.127)
		(layer "In2.Cu")
		(net "UART_BMC_RX")
	)
	(segment
		(start 75.184254 -132.776722)
		(end 75.184254 -133.00329)
		(width 0.127)
		(layer "In2.Cu")
		(net "UART_BMC_RX")
	)
	(segment
		(start 75.274424 -152.393396)
		(end 74.9681 -152.69972)
		(width 0.127)
		(layer "In2.Cu")
		(net "UART_BMC_RX")
	)
	(segment
		(start 74.769726 -142.928086)
		(end 75.274424 -143.432784)
		(width 0.127)
		(layer "In2.Cu")
		(net "UART_BMC_RX")
	)
	(segment
		(start 75.601576 -132.3594)
		(end 75.184254 -132.776722)
		(width 0.127)
		(layer "In2.Cu")
		(net "UART_BMC_RX")
	)
	(segment
		(start 74.9681 -158.4833)
		(end 74.549 -158.9024)
		(width 0.127)
		(layer "In2.Cu")
		(net "UART_BMC_RX")
	)
	(segment
		(start 74.769726 -136.675876)
		(end 74.769726 -142.928086)
		(width 0.127)
		(layer "In2.Cu")
		(net "UART_BMC_RX")
	)
	(segment
		(start 50.2412 -155.5369)
		(end 49.8094 -155.9687)
		(width 0.127)
		(layer "In5.Cu")
		(net "UART_BMC_RX")
	)
	(segment
		(start 89.55278 -129.44602)
		(end 87.31758 -129.44602)
		(width 0.127)
		(layer "In5.Cu")
		(net "UART_BMC_RX")
	)
	(segment
		(start 62.714378 -159.822134)
		(end 62.453012 -160.0835)
		(width 0.127)
		(layer "In5.Cu")
		(net "UART_BMC_RX")
	)
	(segment
		(start 65.659 -159.3596)
		(end 65.196466 -159.822134)
		(width 0.127)
		(layer "In5.Cu")
		(net "UART_BMC_RX")
	)
	(segment
		(start 74.549 -158.9024)
		(end 73.592944 -158.9024)
		(width 0.127)
		(layer "In5.Cu")
		(net "UART_BMC_RX")
	)
	(segment
		(start 52.961286 -156.438346)
		(end 52.05984 -155.5369)
		(width 0.127)
		(layer "In5.Cu")
		(net "UART_BMC_RX")
	)
	(segment
		(start 76.79309 -132.562346)
		(end 76.26731 -132.562346)
		(width 0.127)
		(layer "In5.Cu")
		(net "UART_BMC_RX")
	)
	(segment
		(start 73.592944 -158.9024)
		(end 73.135744 -159.3596)
		(width 0.127)
		(layer "In5.Cu")
		(net "UART_BMC_RX")
	)
	(segment
		(start 65.196466 -159.822134)
		(end 62.714378 -159.822134)
		(width 0.127)
		(layer "In5.Cu")
		(net "UART_BMC_RX")
	)
	(segment
		(start 56.778144 -159.5882)
		(end 53.62829 -156.438346)
		(width 0.127)
		(layer "In5.Cu")
		(net "UART_BMC_RX")
	)
	(segment
		(start 76.241656 -132.588)
		(end 75.9714 -132.588)
		(width 0.127)
		(layer "In5.Cu")
		(net "UART_BMC_RX")
	)
	(segment
		(start 73.135744 -159.3596)
		(end 65.659 -159.3596)
		(width 0.127)
		(layer "In5.Cu")
		(net "UART_BMC_RX")
	)
	(segment
		(start 52.05984 -155.5369)
		(end 50.2412 -155.5369)
		(width 0.127)
		(layer "In5.Cu")
		(net "UART_BMC_RX")
	)
	(segment
		(start 86.1568 -130.6068)
		(end 84.268056 -130.6068)
		(width 0.127)
		(layer "In5.Cu")
		(net "UART_BMC_RX")
	)
	(segment
		(start 76.26731 -132.562346)
		(end 76.241656 -132.588)
		(width 0.127)
		(layer "In5.Cu")
		(net "UART_BMC_RX")
	)
	(segment
		(start 79.492856 -132.588)
		(end 76.818744 -132.588)
		(width 0.127)
		(layer "In5.Cu")
		(net "UART_BMC_RX")
	)
	(segment
		(start 90.3224 -128.6764)
		(end 89.55278 -129.44602)
		(width 0.127)
		(layer "In5.Cu")
		(net "UART_BMC_RX")
	)
	(segment
		(start 87.31758 -129.44602)
		(end 86.1568 -130.6068)
		(width 0.127)
		(layer "In5.Cu")
		(net "UART_BMC_RX")
	)
	(segment
		(start 80.364838 -131.7117)
		(end 79.7179 -132.358638)
		(width 0.127)
		(layer "In5.Cu")
		(net "UART_BMC_RX")
	)
	(segment
		(start 75.9714 -132.588)
		(end 75.7428 -132.3594)
		(width 0.127)
		(layer "In5.Cu")
		(net "UART_BMC_RX")
	)
	(segment
		(start 58.331862 -159.5882)
		(end 56.778144 -159.5882)
		(width 0.127)
		(layer "In5.Cu")
		(net "UART_BMC_RX")
	)
	(segment
		(start 62.453012 -160.0835)
		(end 58.827162 -160.0835)
		(width 0.127)
		(layer "In5.Cu")
		(net "UART_BMC_RX")
	)
	(segment
		(start 79.7179 -132.358638)
		(end 79.7179 -132.362956)
		(width 0.127)
		(layer "In5.Cu")
		(net "UART_BMC_RX")
	)
	(segment
		(start 79.7179 -132.362956)
		(end 79.492856 -132.588)
		(width 0.127)
		(layer "In5.Cu")
		(net "UART_BMC_RX")
	)
	(segment
		(start 58.827162 -160.0835)
		(end 58.331862 -159.5882)
		(width 0.127)
		(layer "In5.Cu")
		(net "UART_BMC_RX")
	)
	(segment
		(start 84.268056 -130.6068)
		(end 83.163156 -131.7117)
		(width 0.127)
		(layer "In5.Cu")
		(net "UART_BMC_RX")
	)
	(segment
		(start 83.163156 -131.7117)
		(end 80.364838 -131.7117)
		(width 0.127)
		(layer "In5.Cu")
		(net "UART_BMC_RX")
	)
	(segment
		(start 53.62829 -156.438346)
		(end 52.961286 -156.438346)
		(width 0.127)
		(layer "In5.Cu")
		(net "UART_BMC_RX")
	)
	(segment
		(start 76.818744 -132.588)
		(end 76.79309 -132.562346)
		(width 0.127)
		(layer "In5.Cu")
		(net "UART_BMC_RX")
	)
	(segment
		(start 50.7873 -155.956)
		(end 48.899826 -154.068526)
		(width 0.127)
		(layer "F.Cu")
		(net "UART_BMC_R_TX")
	)
	(segment
		(start 48.899826 -154.068526)
		(end 48.899826 -153.399998)
		(width 0.127)
		(layer "F.Cu")
		(net "UART_BMC_R_TX")
	)
	(via
		(at 50.7873 -156.8704)
		(size 0.6096)
		(drill 0.3048)
		(layers "F.Cu" "B.Cu")
		(net "UART_BMC_R_TX")
	)
	(via
		(at 50.7873 -155.956)
		(size 0.508)
		(drill 0.254)
		(layers "F.Cu" "B.Cu")
		(net "UART_BMC_R_TX")
	)
	(segment
		(start 50.7873 -155.956)
		(end 50.7873 -156.8704)
		(width 0.127)
		(layer "B.Cu")
		(net "UART_BMC_R_TX")
	)
	(segment
		(start 50.7873 -157.144974)
		(end 49.806098 -158.126176)
		(width 0.127)
		(layer "B.Cu")
		(net "UART_BMC_R_TX")
	)
	(segment
		(start 50.7873 -156.8704)
		(end 50.7873 -157.144974)
		(width 0.127)
		(layer "B.Cu")
		(net "UART_BMC_R_TX")
	)
	(segment
		(start 49.806098 -158.126176)
		(end 49.458372 -158.126176)
		(width 0.127)
		(layer "B.Cu")
		(net "UART_BMC_R_TX")
	)
	(segment
		(start 48.899826 -152.599898)
		(end 48.499776 -152.999948)
		(width 0.127)
		(layer "F.Cu")
		(net "UART_BMC_R_RX")
	)
	(via
		(at 48.499776 -153.888948)
		(size 0.6096)
		(drill 0.3048)
		(layers "F.Cu" "B.Cu")
		(net "UART_BMC_R_RX")
	)
	(via
		(at 48.499776 -152.999948)
		(size 0.4572)
		(drill 0.2032)
		(layers "F.Cu" "B.Cu")
		(net "UART_BMC_R_RX")
	)
	(segment
		(start 48.499776 -152.999948)
		(end 48.499776 -153.888948)
		(width 0.127)
		(layer "B.Cu")
		(net "UART_BMC_R_RX")
	)
	(segment
		(start 48.499776 -153.888948)
		(end 49.004728 -154.3939)
		(width 0.127)
		(layer "B.Cu")
		(net "UART_BMC_R_RX")
	)
	(segment
		(start 49.004728 -154.3939)
		(end 49.911 -154.3939)
		(width 0.127)
		(layer "B.Cu")
		(net "UART_BMC_R_RX")
	)
	(segment
		(start 96.683576 -155.105354)
		(end 95.621856 -155.105354)
		(width 0.127)
		(layer "F.Cu")
		(net "TP_USB_SDA")
	)
	(segment
		(start 97.10293 -154.686)
		(end 96.683576 -155.105354)
		(width 0.127)
		(layer "F.Cu")
		(net "TP_USB_SDA")
	)
	(segment
		(start 97.1804 -154.686)
		(end 97.10293 -154.686)
		(width 0.127)
		(layer "F.Cu")
		(net "TP_USB_SDA")
	)
	(via
		(at 97.1804 -154.686)
		(size 0.508)
		(drill 0.254)
		(layers "F.Cu" "B.Cu")
		(net "TP_USB_SDA")
	)
	(segment
		(start 96.25711 -155.095702)
		(end 96.770698 -155.095702)
		(width 0.127)
		(layer "B.Cu")
		(net "TP_USB_SDA")
	)
	(segment
		(start 96.770698 -155.095702)
		(end 97.1804 -154.686)
		(width 0.127)
		(layer "B.Cu")
		(net "TP_USB_SDA")
	)
	(segment
		(start 40.899842 -150.999952)
		(end 40.499792 -151.400002)
		(width 0.127)
		(layer "F.Cu")
		(net "SCC_B_HB_IN_R")
	)
	(via
		(at 39.751 -152.019)
		(size 0.6096)
		(drill 0.3048)
		(layers "F.Cu" "B.Cu")
		(net "SCC_B_HB_IN_R")
	)
	(via
		(at 40.499792 -151.400002)
		(size 0.4572)
		(drill 0.2032)
		(layers "F.Cu" "B.Cu")
		(net "SCC_B_HB_IN_R")
	)
	(segment
		(start 39.243 -152.273)
		(end 38.863778 -152.652222)
		(width 0.127)
		(layer "B.Cu")
		(net "SCC_B_HB_IN_R")
	)
	(segment
		(start 40.369998 -151.400002)
		(end 40.499792 -151.400002)
		(width 0.127)
		(layer "B.Cu")
		(net "SCC_B_HB_IN_R")
	)
	(segment
		(start 39.751 -152.019)
		(end 39.497 -152.273)
		(width 0.127)
		(layer "B.Cu")
		(net "SCC_B_HB_IN_R")
	)
	(segment
		(start 38.863778 -152.652222)
		(end 38.863778 -153.050748)
		(width 0.127)
		(layer "B.Cu")
		(net "SCC_B_HB_IN_R")
	)
	(segment
		(start 39.751 -152.019)
		(end 40.369998 -151.400002)
		(width 0.127)
		(layer "B.Cu")
		(net "SCC_B_HB_IN_R")
	)
	(segment
		(start 39.497 -152.273)
		(end 39.243 -152.273)
		(width 0.127)
		(layer "B.Cu")
		(net "SCC_B_HB_IN_R")
	)
	(segment
		(start 37.3634 -155.251658)
		(end 37.3634 -153.692098)
		(width 0.127)
		(layer "F.Cu")
		(net "SCC_A_HB_IN_R")
	)
	(segment
		(start 35.520884 -156.807916)
		(end 35.7632 -156.5656)
		(width 0.127)
		(layer "F.Cu")
		(net "SCC_A_HB_IN_R")
	)
	(segment
		(start 36.271454 -156.057346)
		(end 36.557712 -156.057346)
		(width 0.127)
		(layer "F.Cu")
		(net "SCC_A_HB_IN_R")
	)
	(segment
		(start 39.255446 -151.800052)
		(end 39.299896 -151.800052)
		(width 0.127)
		(layer "F.Cu")
		(net "SCC_A_HB_IN_R")
	)
	(segment
		(start 34.47923 -156.807916)
		(end 35.520884 -156.807916)
		(width 0.127)
		(layer "F.Cu")
		(net "SCC_A_HB_IN_R")
	)
	(segment
		(start 37.3634 -153.692098)
		(end 39.255446 -151.800052)
		(width 0.127)
		(layer "F.Cu")
		(net "SCC_A_HB_IN_R")
	)
	(segment
		(start 35.7632 -156.5656)
		(end 36.271454 -156.057346)
		(width 0.127)
		(layer "F.Cu")
		(net "SCC_A_HB_IN_R")
	)
	(segment
		(start 36.557712 -156.057346)
		(end 37.3634 -155.251658)
		(width 0.127)
		(layer "F.Cu")
		(net "SCC_A_HB_IN_R")
	)
	(via
		(at 35.7632 -156.5656)
		(size 0.6604)
		(drill 0.3302)
		(layers "F.Cu" "B.Cu")
		(net "SCC_A_HB_IN_R")
	)
	(segment
		(start 58.252868 -128.904746)
		(end 58.252868 -130.78587)
		(width 0.127)
		(layer "F.Cu")
		(net "RSTBTN_OUT_N")
	)
	(segment
		(start 66.99631 -137.29589)
		(end 66.9544 -137.3378)
		(width 0.127)
		(layer "F.Cu")
		(net "RSTBTN_OUT_N")
	)
	(segment
		(start 67.948556 -137.29589)
		(end 66.99631 -137.29589)
		(width 0.127)
		(layer "F.Cu")
		(net "RSTBTN_OUT_N")
	)
	(segment
		(start 57.494678 -128.146556)
		(end 58.252868 -128.904746)
		(width 0.127)
		(layer "F.Cu")
		(net "RSTBTN_OUT_N")
	)
	(via
		(at 66.9544 -137.3378)
		(size 0.508)
		(drill 0.254)
		(layers "F.Cu" "B.Cu")
		(net "RSTBTN_OUT_N")
	)
	(via
		(at 66.04 -131.3942)
		(size 0.6096)
		(drill 0.3048)
		(layers "F.Cu" "B.Cu")
		(net "RSTBTN_OUT_N")
	)
	(via
		(at 57.494678 -128.146556)
		(size 0.508)
		(drill 0.254)
		(layers "F.Cu" "B.Cu")
		(net "RSTBTN_OUT_N")
	)
	(segment
		(start 62.493906 -126.9492)
		(end 58.666634 -126.9492)
		(width 0.127)
		(layer "B.Cu")
		(net "RSTBTN_OUT_N")
	)
	(segment
		(start 57.494678 -128.121156)
		(end 57.494678 -128.146556)
		(width 0.127)
		(layer "B.Cu")
		(net "RSTBTN_OUT_N")
	)
	(segment
		(start 66.04 -130.495294)
		(end 62.493906 -126.9492)
		(width 0.127)
		(layer "B.Cu")
		(net "RSTBTN_OUT_N")
	)
	(segment
		(start 66.9544 -137.3378)
		(end 67.0306 -137.3378)
		(width 0.127)
		(layer "B.Cu")
		(net "RSTBTN_OUT_N")
	)
	(segment
		(start 66.04 -132.7404)
		(end 66.04 -131.3942)
		(width 0.127)
		(layer "B.Cu")
		(net "RSTBTN_OUT_N")
	)
	(segment
		(start 67.0306 -137.3378)
		(end 67.6021 -136.7663)
		(width 0.127)
		(layer "B.Cu")
		(net "RSTBTN_OUT_N")
	)
	(segment
		(start 58.666634 -126.9492)
		(end 57.494678 -128.121156)
		(width 0.127)
		(layer "B.Cu")
		(net "RSTBTN_OUT_N")
	)
	(segment
		(start 67.6021 -136.7663)
		(end 67.6021 -134.3025)
		(width 0.127)
		(layer "B.Cu")
		(net "RSTBTN_OUT_N")
	)
	(segment
		(start 67.6021 -134.3025)
		(end 66.04 -132.7404)
		(width 0.127)
		(layer "B.Cu")
		(net "RSTBTN_OUT_N")
	)
	(segment
		(start 66.04 -131.3942)
		(end 66.04 -130.495294)
		(width 0.127)
		(layer "B.Cu")
		(net "RSTBTN_OUT_N")
	)
	(segment
		(start 45.39488 -122.064272)
		(end 43.82897 -122.064272)
		(width 0.127)
		(layer "F.Cu")
		(net "RST_BMC_EXTRST_N")
	)
	(segment
		(start 69.33692 -120.49252)
		(end 69.878702 -121.034302)
		(width 0.127)
		(layer "F.Cu")
		(net "RST_BMC_EXTRST_N")
	)
	(segment
		(start 46.352206 -120.403874)
		(end 46.352206 -121.106946)
		(width 0.127)
		(layer "F.Cu")
		(net "RST_BMC_EXTRST_N")
	)
	(segment
		(start 46.352206 -121.106946)
		(end 45.39488 -122.064272)
		(width 0.127)
		(layer "F.Cu")
		(net "RST_BMC_EXTRST_N")
	)
	(segment
		(start 43.82897 -122.064272)
		(end 42.990008 -122.903234)
		(width 0.127)
		(layer "F.Cu")
		(net "RST_BMC_EXTRST_N")
	)
	(segment
		(start 68.9483 -120.49252)
		(end 69.33692 -120.49252)
		(width 0.127)
		(layer "F.Cu")
		(net "RST_BMC_EXTRST_N")
	)
	(via
		(at 57.9628 -126.0348)
		(size 0.508)
		(drill 0.254)
		(layers "F.Cu" "B.Cu")
		(net "RST_BMC_EXTRST_N")
	)
	(via
		(at 41.284398 -126.746)
		(size 0.508)
		(drill 0.254)
		(layers "F.Cu" "B.Cu")
		(net "RST_BMC_EXTRST_N")
	)
	(via
		(at 69.878702 -121.034302)
		(size 0.508)
		(drill 0.254)
		(layers "F.Cu" "B.Cu")
		(net "RST_BMC_EXTRST_N")
	)
	(via
		(at 57.1246 -126.42342)
		(size 0.6096)
		(drill 0.3048)
		(layers "F.Cu" "B.Cu")
		(net "RST_BMC_EXTRST_N")
	)
	(via
		(at 57.531 -121.158)
		(size 0.508)
		(drill 0.254)
		(layers "F.Cu" "B.Cu")
		(net "RST_BMC_EXTRST_N")
	)
	(via
		(at 42.990008 -122.903234)
		(size 0.508)
		(drill 0.254)
		(layers "F.Cu" "B.Cu")
		(net "RST_BMC_EXTRST_N")
	)
	(segment
		(start 40.6146 -124.254006)
		(end 41.965372 -122.903234)
		(width 0.127)
		(layer "B.Cu")
		(net "RST_BMC_EXTRST_N")
	)
	(segment
		(start 57.57418 -126.42342)
		(end 57.9628 -126.0348)
		(width 0.127)
		(layer "B.Cu")
		(net "RST_BMC_EXTRST_N")
	)
	(segment
		(start 41.284398 -126.746)
		(end 40.6146 -126.076202)
		(width 0.127)
		(layer "B.Cu")
		(net "RST_BMC_EXTRST_N")
	)
	(segment
		(start 57.1246 -126.42342)
		(end 55.66664 -126.42342)
		(width 0.127)
		(layer "B.Cu")
		(net "RST_BMC_EXTRST_N")
	)
	(segment
		(start 41.965372 -122.903234)
		(end 42.990008 -122.903234)
		(width 0.127)
		(layer "B.Cu")
		(net "RST_BMC_EXTRST_N")
	)
	(segment
		(start 57.1246 -126.42342)
		(end 57.57418 -126.42342)
		(width 0.127)
		(layer "B.Cu")
		(net "RST_BMC_EXTRST_N")
	)
	(segment
		(start 40.6146 -126.076202)
		(end 40.6146 -124.254006)
		(width 0.127)
		(layer "B.Cu")
		(net "RST_BMC_EXTRST_N")
	)
	(segment
		(start 41.284398 -126.746)
		(end 41.284398 -127.534416)
		(width 0.127)
		(layer "B.Cu")
		(net "RST_BMC_EXTRST_N")
	)
	(segment
		(start 57.05475 -125.12675)
		(end 57.05475 -121.63425)
		(width 0.127)
		(layer "In2.Cu")
		(net "RST_BMC_EXTRST_N")
	)
	(segment
		(start 57.9628 -126.0348)
		(end 57.05475 -125.12675)
		(width 0.127)
		(layer "In2.Cu")
		(net "RST_BMC_EXTRST_N")
	)
	(segment
		(start 57.05475 -121.63425)
		(end 57.531 -121.158)
		(width 0.127)
		(layer "In2.Cu")
		(net "RST_BMC_EXTRST_N")
	)
	(segment
		(start 59.675776 -121.158)
		(end 57.531 -121.158)
		(width 0.127)
		(layer "In5.Cu")
		(net "RST_BMC_EXTRST_N")
	)
	(segment
		(start 66.543936 -122.0343)
		(end 60.552076 -122.0343)
		(width 0.127)
		(layer "In5.Cu")
		(net "RST_BMC_EXTRST_N")
	)
	(segment
		(start 42.846498 -128.3081)
		(end 47.396146 -128.3081)
		(width 0.127)
		(layer "In5.Cu")
		(net "RST_BMC_EXTRST_N")
	)
	(segment
		(start 51.755294 -127.815848)
		(end 52.671218 -126.899924)
		(width 0.127)
		(layer "In5.Cu")
		(net "RST_BMC_EXTRST_N")
	)
	(segment
		(start 67.543934 -121.034302)
		(end 66.543936 -122.0343)
		(width 0.127)
		(layer "In5.Cu")
		(net "RST_BMC_EXTRST_N")
	)
	(segment
		(start 69.878702 -121.034302)
		(end 67.543934 -121.034302)
		(width 0.127)
		(layer "In5.Cu")
		(net "RST_BMC_EXTRST_N")
	)
	(segment
		(start 57.8612 -125.9332)
		(end 57.9628 -126.0348)
		(width 0.127)
		(layer "In5.Cu")
		(net "RST_BMC_EXTRST_N")
	)
	(segment
		(start 47.888398 -127.815848)
		(end 51.755294 -127.815848)
		(width 0.127)
		(layer "In5.Cu")
		(net "RST_BMC_EXTRST_N")
	)
	(segment
		(start 54.411626 -126.899924)
		(end 55.37835 -125.9332)
		(width 0.127)
		(layer "In5.Cu")
		(net "RST_BMC_EXTRST_N")
	)
	(segment
		(start 60.552076 -122.0343)
		(end 59.675776 -121.158)
		(width 0.127)
		(layer "In5.Cu")
		(net "RST_BMC_EXTRST_N")
	)
	(segment
		(start 55.37835 -125.9332)
		(end 57.8612 -125.9332)
		(width 0.127)
		(layer "In5.Cu")
		(net "RST_BMC_EXTRST_N")
	)
	(segment
		(start 52.671218 -126.899924)
		(end 54.411626 -126.899924)
		(width 0.127)
		(layer "In5.Cu")
		(net "RST_BMC_EXTRST_N")
	)
	(segment
		(start 41.284398 -126.746)
		(end 42.846498 -128.3081)
		(width 0.127)
		(layer "In5.Cu")
		(net "RST_BMC_EXTRST_N")
	)
	(segment
		(start 47.396146 -128.3081)
		(end 47.888398 -127.815848)
		(width 0.127)
		(layer "In5.Cu")
		(net "RST_BMC_EXTRST_N")
	)
	(via
		(at 211.865464 -83.899756)
		(size 0.6096)
		(drill 0.3048)
		(layers "F.Cu" "B.Cu")
		(net "Q20_G")
	)
	(segment
		(start 210.309206 -85.786214)
		(end 211.865464 -84.229956)
		(width 0.127)
		(layer "B.Cu")
		(net "Q20_G")
	)
	(segment
		(start 211.865464 -83.899756)
		(end 211.865464 -83.340702)
		(width 0.127)
		(layer "B.Cu")
		(net "Q20_G")
	)
	(segment
		(start 211.865464 -84.229956)
		(end 211.865464 -83.899756)
		(width 0.127)
		(layer "B.Cu")
		(net "Q20_G")
	)
	(segment
		(start 211.865464 -83.340702)
		(end 211.593938 -83.069176)
		(width 0.127)
		(layer "B.Cu")
		(net "Q20_G")
	)
	(segment
		(start 211.593938 -83.069176)
		(end 210.309714 -83.069176)
		(width 0.127)
		(layer "B.Cu")
		(net "Q20_G")
	)
	(segment
		(start 210.309206 -86.56828)
		(end 210.309206 -85.786214)
		(width 0.127)
		(layer "B.Cu")
		(net "Q20_G")
	)
	(segment
		(start 60.706 -174.5742)
		(end 60.2488 -174.117)
		(width 0.127)
		(layer "F.Cu")
		(net "I2C_TPM_SDA")
	)
	(segment
		(start 59.857386 -169.696384)
		(end 58.434224 -168.273222)
		(width 0.127)
		(layer "F.Cu")
		(net "I2C_TPM_SDA")
	)
	(segment
		(start 60.706 -175.514)
		(end 60.706 -174.5742)
		(width 0.127)
		(layer "F.Cu")
		(net "I2C_TPM_SDA")
	)
	(segment
		(start 57.399936 -168.273222)
		(end 56.780176 -168.892982)
		(width 0.127)
		(layer "F.Cu")
		(net "I2C_TPM_SDA")
	)
	(segment
		(start 58.434224 -168.273222)
		(end 57.882536 -168.273222)
		(width 0.127)
		(layer "F.Cu")
		(net "I2C_TPM_SDA")
	)
	(segment
		(start 57.869836 -168.260522)
		(end 57.412636 -168.260522)
		(width 0.127)
		(layer "F.Cu")
		(net "I2C_TPM_SDA")
	)
	(segment
		(start 60.2488 -172.392848)
		(end 59.857386 -172.001434)
		(width 0.127)
		(layer "F.Cu")
		(net "I2C_TPM_SDA")
	)
	(segment
		(start 49.440846 -130.556)
		(end 49.5808 -130.416046)
		(width 0.127)
		(layer "F.Cu")
		(net "I2C_TPM_SDA")
	)
	(segment
		(start 60.2488 -174.117)
		(end 60.2488 -172.392848)
		(width 0.127)
		(layer "F.Cu")
		(net "I2C_TPM_SDA")
	)
	(segment
		(start 49.440846 -131.292854)
		(end 49.440846 -130.556)
		(width 0.127)
		(layer "F.Cu")
		(net "I2C_TPM_SDA")
	)
	(segment
		(start 56.780176 -168.892982)
		(end 56.780176 -170.405044)
		(width 0.127)
		(layer "F.Cu")
		(net "I2C_TPM_SDA")
	)
	(segment
		(start 59.857386 -172.001434)
		(end 59.857386 -169.696384)
		(width 0.127)
		(layer "F.Cu")
		(net "I2C_TPM_SDA")
	)
	(segment
		(start 49.5808 -130.416046)
		(end 49.5808 -130.3528)
		(width 0.127)
		(layer "F.Cu")
		(net "I2C_TPM_SDA")
	)
	(segment
		(start 57.412636 -168.260522)
		(end 57.399936 -168.273222)
		(width 0.127)
		(layer "F.Cu")
		(net "I2C_TPM_SDA")
	)
	(segment
		(start 57.882536 -168.273222)
		(end 57.869836 -168.260522)
		(width 0.127)
		(layer "F.Cu")
		(net "I2C_TPM_SDA")
	)
	(via
		(at 83.073748 -177.1904)
		(size 0.508)
		(drill 0.254)
		(layers "F.Cu" "B.Cu")
		(net "I2C_TPM_SDA")
	)
	(via
		(at 60.706 -174.5742)
		(size 0.6604)
		(drill 0.3302)
		(layers "F.Cu" "B.Cu")
		(net "I2C_TPM_SDA")
	)
	(via
		(at 73.230994 -126.0348)
		(size 0.508)
		(drill 0.254)
		(layers "F.Cu" "B.Cu")
		(net "I2C_TPM_SDA")
	)
	(via
		(at 60.706 -175.514)
		(size 0.508)
		(drill 0.254)
		(layers "F.Cu" "B.Cu")
		(net "I2C_TPM_SDA")
	)
	(via
		(at 49.5808 -130.3528)
		(size 0.508)
		(drill 0.254)
		(layers "F.Cu" "B.Cu")
		(net "I2C_TPM_SDA")
	)
	(segment
		(start 83.073748 -173.800008)
		(end 83.073748 -177.1904)
		(width 0.127)
		(layer "In2.Cu")
		(net "I2C_TPM_SDA")
	)
	(segment
		(start 79.9973 -167.699436)
		(end 83.872324 -171.57446)
		(width 0.127)
		(layer "In2.Cu")
		(net "I2C_TPM_SDA")
	)
	(segment
		(start 73.6092 -126.0348)
		(end 75.944476 -128.370076)
		(width 0.127)
		(layer "In2.Cu")
		(net "I2C_TPM_SDA")
	)
	(segment
		(start 75.944476 -128.370076)
		(end 75.944476 -129.67589)
		(width 0.127)
		(layer "In2.Cu")
		(net "I2C_TPM_SDA")
	)
	(segment
		(start 76.581 -132.350256)
		(end 77.0636 -132.832856)
		(width 0.127)
		(layer "In2.Cu")
		(net "I2C_TPM_SDA")
	)
	(segment
		(start 79.9973 -160.631632)
		(end 79.9973 -167.699436)
		(width 0.127)
		(layer "In2.Cu")
		(net "I2C_TPM_SDA")
	)
	(segment
		(start 78.05928 -158.693612)
		(end 79.9973 -160.631632)
		(width 0.127)
		(layer "In2.Cu")
		(net "I2C_TPM_SDA")
	)
	(segment
		(start 76.740258 -146.818858)
		(end 77.613002 -147.691602)
		(width 0.127)
		(layer "In2.Cu")
		(net "I2C_TPM_SDA")
	)
	(segment
		(start 75.944476 -129.67589)
		(end 76.581 -130.312414)
		(width 0.127)
		(layer "In2.Cu")
		(net "I2C_TPM_SDA")
	)
	(segment
		(start 76.366624 -140.23848)
		(end 76.740258 -140.612114)
		(width 0.127)
		(layer "In2.Cu")
		(net "I2C_TPM_SDA")
	)
	(segment
		(start 83.872324 -173.001432)
		(end 83.073748 -173.800008)
		(width 0.127)
		(layer "In2.Cu")
		(net "I2C_TPM_SDA")
	)
	(segment
		(start 77.0636 -134.3152)
		(end 76.366624 -135.012176)
		(width 0.127)
		(layer "In2.Cu")
		(net "I2C_TPM_SDA")
	)
	(segment
		(start 83.872324 -171.57446)
		(end 83.872324 -173.001432)
		(width 0.127)
		(layer "In2.Cu")
		(net "I2C_TPM_SDA")
	)
	(segment
		(start 77.0636 -132.832856)
		(end 77.0636 -134.3152)
		(width 0.127)
		(layer "In2.Cu")
		(net "I2C_TPM_SDA")
	)
	(segment
		(start 76.740258 -140.612114)
		(end 76.740258 -146.818858)
		(width 0.127)
		(layer "In2.Cu")
		(net "I2C_TPM_SDA")
	)
	(segment
		(start 77.613002 -152.285446)
		(end 78.05928 -152.731724)
		(width 0.127)
		(layer "In2.Cu")
		(net "I2C_TPM_SDA")
	)
	(segment
		(start 76.366624 -135.012176)
		(end 76.366624 -140.23848)
		(width 0.127)
		(layer "In2.Cu")
		(net "I2C_TPM_SDA")
	)
	(segment
		(start 76.581 -130.312414)
		(end 76.581 -132.350256)
		(width 0.127)
		(layer "In2.Cu")
		(net "I2C_TPM_SDA")
	)
	(segment
		(start 77.613002 -147.691602)
		(end 77.613002 -152.285446)
		(width 0.127)
		(layer "In2.Cu")
		(net "I2C_TPM_SDA")
	)
	(segment
		(start 73.230994 -126.0348)
		(end 73.6092 -126.0348)
		(width 0.127)
		(layer "In2.Cu")
		(net "I2C_TPM_SDA")
	)
	(segment
		(start 78.05928 -152.731724)
		(end 78.05928 -158.693612)
		(width 0.127)
		(layer "In2.Cu")
		(net "I2C_TPM_SDA")
	)
	(segment
		(start 73.226676 -126.039118)
		(end 70.798436 -126.039118)
		(width 0.127)
		(layer "In5.Cu")
		(net "I2C_TPM_SDA")
	)
	(segment
		(start 52.870862 -129.946654)
		(end 50.266346 -129.946654)
		(width 0.127)
		(layer "In5.Cu")
		(net "I2C_TPM_SDA")
	)
	(segment
		(start 77.406246 -176.1363)
		(end 76.15682 -174.886874)
		(width 0.127)
		(layer "In5.Cu")
		(net "I2C_TPM_SDA")
	)
	(segment
		(start 76.15682 -174.886874)
		(end 66.547746 -174.886874)
		(width 0.127)
		(layer "In5.Cu")
		(net "I2C_TPM_SDA")
	)
	(segment
		(start 69.802248 -126.496318)
		(end 69.501766 -126.7968)
		(width 0.127)
		(layer "In5.Cu")
		(net "I2C_TPM_SDA")
	)
	(segment
		(start 69.501766 -126.7968)
		(end 65.765934 -126.7968)
		(width 0.127)
		(layer "In5.Cu")
		(net "I2C_TPM_SDA")
	)
	(segment
		(start 50.266346 -129.946654)
		(end 49.8602 -130.3528)
		(width 0.127)
		(layer "In5.Cu")
		(net "I2C_TPM_SDA")
	)
	(segment
		(start 58.986166 -126.5682)
		(end 58.465466 -127.0889)
		(width 0.127)
		(layer "In5.Cu")
		(net "I2C_TPM_SDA")
	)
	(segment
		(start 55.728616 -127.0889)
		(end 52.870862 -129.946654)
		(width 0.127)
		(layer "In5.Cu")
		(net "I2C_TPM_SDA")
	)
	(segment
		(start 61.2267 -174.9933)
		(end 60.706 -175.514)
		(width 0.127)
		(layer "In5.Cu")
		(net "I2C_TPM_SDA")
	)
	(segment
		(start 73.230994 -126.0348)
		(end 73.226676 -126.039118)
		(width 0.127)
		(layer "In5.Cu")
		(net "I2C_TPM_SDA")
	)
	(segment
		(start 83.073748 -177.1904)
		(end 82.019648 -176.1363)
		(width 0.127)
		(layer "In5.Cu")
		(net "I2C_TPM_SDA")
	)
	(segment
		(start 49.8602 -130.3528)
		(end 49.5808 -130.3528)
		(width 0.127)
		(layer "In5.Cu")
		(net "I2C_TPM_SDA")
	)
	(segment
		(start 65.537334 -126.5682)
		(end 58.986166 -126.5682)
		(width 0.127)
		(layer "In5.Cu")
		(net "I2C_TPM_SDA")
	)
	(segment
		(start 66.547746 -174.886874)
		(end 66.44132 -174.9933)
		(width 0.127)
		(layer "In5.Cu")
		(net "I2C_TPM_SDA")
	)
	(segment
		(start 82.019648 -176.1363)
		(end 77.406246 -176.1363)
		(width 0.127)
		(layer "In5.Cu")
		(net "I2C_TPM_SDA")
	)
	(segment
		(start 70.798436 -126.039118)
		(end 70.341236 -126.496318)
		(width 0.127)
		(layer "In5.Cu")
		(net "I2C_TPM_SDA")
	)
	(segment
		(start 66.44132 -174.9933)
		(end 61.2267 -174.9933)
		(width 0.127)
		(layer "In5.Cu")
		(net "I2C_TPM_SDA")
	)
	(segment
		(start 65.765934 -126.7968)
		(end 65.537334 -126.5682)
		(width 0.127)
		(layer "In5.Cu")
		(net "I2C_TPM_SDA")
	)
	(segment
		(start 58.465466 -127.0889)
		(end 55.728616 -127.0889)
		(width 0.127)
		(layer "In5.Cu")
		(net "I2C_TPM_SDA")
	)
	(segment
		(start 70.341236 -126.496318)
		(end 69.802248 -126.496318)
		(width 0.127)
		(layer "In5.Cu")
		(net "I2C_TPM_SDA")
	)
	(segment
		(start 47.5234 -130.1623)
		(end 47.5234 -129.4384)
		(width 0.127)
		(layer "F.Cu")
		(net "I2C_TPM_SCL")
	)
	(segment
		(start 47.540418 -129.421382)
		(end 47.540418 -128.634236)
		(width 0.127)
		(layer "F.Cu")
		(net "I2C_TPM_SCL")
	)
	(segment
		(start 55.280052 -174.994824)
		(end 55.280052 -176.672748)
		(width 0.127)
		(layer "F.Cu")
		(net "I2C_TPM_SCL")
	)
	(segment
		(start 47.5234 -129.4384)
		(end 47.540418 -129.421382)
		(width 0.127)
		(layer "F.Cu")
		(net "I2C_TPM_SCL")
	)
	(segment
		(start 48.4124 -131.0513)
		(end 47.5234 -130.1623)
		(width 0.127)
		(layer "F.Cu")
		(net "I2C_TPM_SCL")
	)
	(via
		(at 47.5234 -129.4384)
		(size 0.508)
		(drill 0.254)
		(layers "F.Cu" "B.Cu")
		(net "I2C_TPM_SCL")
	)
	(via
		(at 55.280052 -176.672748)
		(size 0.508)
		(drill 0.254)
		(layers "F.Cu" "B.Cu")
		(net "I2C_TPM_SCL")
	)
	(via
		(at 74.504804 -125.520196)
		(size 0.508)
		(drill 0.254)
		(layers "F.Cu" "B.Cu")
		(net "I2C_TPM_SCL")
	)
	(via
		(at 83.334098 -178.203098)
		(size 0.508)
		(drill 0.254)
		(layers "F.Cu" "B.Cu")
		(net "I2C_TPM_SCL")
	)
	(segment
		(start 78.585568 -149.192234)
		(end 78.585568 -151.16175)
		(width 0.127)
		(layer "In2.Cu")
		(net "I2C_TPM_SCL")
	)
	(segment
		(start 78.613 -151.189182)
		(end 78.613 -158.528766)
		(width 0.127)
		(layer "In2.Cu")
		(net "I2C_TPM_SCL")
	)
	(segment
		(start 81.1403 -166.470584)
		(end 84.468716 -169.799)
		(width 0.127)
		(layer "In2.Cu")
		(net "I2C_TPM_SCL")
	)
	(segment
		(start 83.581748 -174.010574)
		(end 83.581748 -177.955448)
		(width 0.127)
		(layer "In2.Cu")
		(net "I2C_TPM_SCL")
	)
	(segment
		(start 78.47711 -149.083776)
		(end 78.585568 -149.192234)
		(width 0.127)
		(layer "In2.Cu")
		(net "I2C_TPM_SCL")
	)
	(segment
		(start 74.504804 -125.520196)
		(end 76.452476 -127.467868)
		(width 0.127)
		(layer "In2.Cu")
		(net "I2C_TPM_SCL")
	)
	(segment
		(start 77.5716 -137.0076)
		(end 79.669386 -139.105386)
		(width 0.127)
		(layer "In2.Cu")
		(net "I2C_TPM_SCL")
	)
	(segment
		(start 77.089 -130.101848)
		(end 77.089 -132.13969)
		(width 0.127)
		(layer "In2.Cu")
		(net "I2C_TPM_SCL")
	)
	(segment
		(start 76.452476 -129.465324)
		(end 77.089 -130.101848)
		(width 0.127)
		(layer "In2.Cu")
		(net "I2C_TPM_SCL")
	)
	(segment
		(start 79.669386 -142.128494)
		(end 78.47711 -143.32077)
		(width 0.127)
		(layer "In2.Cu")
		(net "I2C_TPM_SCL")
	)
	(segment
		(start 84.468716 -173.123606)
		(end 83.581748 -174.010574)
		(width 0.127)
		(layer "In2.Cu")
		(net "I2C_TPM_SCL")
	)
	(segment
		(start 80.9752 -165.046152)
		(end 81.1403 -165.211252)
		(width 0.127)
		(layer "In2.Cu")
		(net "I2C_TPM_SCL")
	)
	(segment
		(start 80.9752 -160.890966)
		(end 80.9752 -165.046152)
		(width 0.127)
		(layer "In2.Cu")
		(net "I2C_TPM_SCL")
	)
	(segment
		(start 84.468716 -169.799)
		(end 84.468716 -173.123606)
		(width 0.127)
		(layer "In2.Cu")
		(net "I2C_TPM_SCL")
	)
	(segment
		(start 77.5716 -132.62229)
		(end 77.5716 -137.0076)
		(width 0.127)
		(layer "In2.Cu")
		(net "I2C_TPM_SCL")
	)
	(segment
		(start 83.581748 -177.955448)
		(end 83.334098 -178.203098)
		(width 0.127)
		(layer "In2.Cu")
		(net "I2C_TPM_SCL")
	)
	(segment
		(start 78.585568 -151.16175)
		(end 78.613 -151.189182)
		(width 0.127)
		(layer "In2.Cu")
		(net "I2C_TPM_SCL")
	)
	(segment
		(start 77.089 -132.13969)
		(end 77.5716 -132.62229)
		(width 0.127)
		(layer "In2.Cu")
		(net "I2C_TPM_SCL")
	)
	(segment
		(start 79.669386 -139.105386)
		(end 79.669386 -142.128494)
		(width 0.127)
		(layer "In2.Cu")
		(net "I2C_TPM_SCL")
	)
	(segment
		(start 78.47711 -143.32077)
		(end 78.47711 -149.083776)
		(width 0.127)
		(layer "In2.Cu")
		(net "I2C_TPM_SCL")
	)
	(segment
		(start 76.452476 -127.467868)
		(end 76.452476 -129.465324)
		(width 0.127)
		(layer "In2.Cu")
		(net "I2C_TPM_SCL")
	)
	(segment
		(start 81.1403 -165.211252)
		(end 81.1403 -166.470584)
		(width 0.127)
		(layer "In2.Cu")
		(net "I2C_TPM_SCL")
	)
	(segment
		(start 78.613 -158.528766)
		(end 80.9752 -160.890966)
		(width 0.127)
		(layer "In2.Cu")
		(net "I2C_TPM_SCL")
	)
	(segment
		(start 55.8292 -176.1236)
		(end 66.209164 -176.1236)
		(width 0.127)
		(layer "In5.Cu")
		(net "I2C_TPM_SCL")
	)
	(segment
		(start 69.591682 -125.988318)
		(end 69.2912 -126.2888)
		(width 0.127)
		(layer "In5.Cu")
		(net "I2C_TPM_SCL")
	)
	(segment
		(start 75.572874 -175.394874)
		(end 77.229716 -177.051716)
		(width 0.127)
		(layer "In5.Cu")
		(net "I2C_TPM_SCL")
	)
	(segment
		(start 48.1457 -128.8161)
		(end 47.5234 -129.4384)
		(width 0.127)
		(layer "In5.Cu")
		(net "I2C_TPM_SCL")
	)
	(segment
		(start 51.100482 -128.8161)
		(end 48.1457 -128.8161)
		(width 0.127)
		(layer "In5.Cu")
		(net "I2C_TPM_SCL")
	)
	(segment
		(start 55.51805 -126.5809)
		(end 52.92725 -129.1717)
		(width 0.127)
		(layer "In5.Cu")
		(net "I2C_TPM_SCL")
	)
	(segment
		(start 65.9765 -126.2888)
		(end 65.7479 -126.0602)
		(width 0.127)
		(layer "In5.Cu")
		(net "I2C_TPM_SCL")
	)
	(segment
		(start 74.504804 -125.520196)
		(end 74.498708 -125.5141)
		(width 0.127)
		(layer "In5.Cu")
		(net "I2C_TPM_SCL")
	)
	(segment
		(start 66.209164 -176.1236)
		(end 66.93789 -175.394874)
		(width 0.127)
		(layer "In5.Cu")
		(net "I2C_TPM_SCL")
	)
	(segment
		(start 58.2549 -126.5809)
		(end 55.51805 -126.5809)
		(width 0.127)
		(layer "In5.Cu")
		(net "I2C_TPM_SCL")
	)
	(segment
		(start 74.498708 -125.5141)
		(end 70.604888 -125.5141)
		(width 0.127)
		(layer "In5.Cu")
		(net "I2C_TPM_SCL")
	)
	(segment
		(start 55.280052 -176.672748)
		(end 55.8292 -176.1236)
		(width 0.127)
		(layer "In5.Cu")
		(net "I2C_TPM_SCL")
	)
	(segment
		(start 66.93789 -175.394874)
		(end 75.572874 -175.394874)
		(width 0.127)
		(layer "In5.Cu")
		(net "I2C_TPM_SCL")
	)
	(segment
		(start 70.13067 -125.988318)
		(end 69.591682 -125.988318)
		(width 0.127)
		(layer "In5.Cu")
		(net "I2C_TPM_SCL")
	)
	(segment
		(start 65.7479 -126.0602)
		(end 58.7756 -126.0602)
		(width 0.127)
		(layer "In5.Cu")
		(net "I2C_TPM_SCL")
	)
	(segment
		(start 77.229716 -177.051716)
		(end 82.182716 -177.051716)
		(width 0.127)
		(layer "In5.Cu")
		(net "I2C_TPM_SCL")
	)
	(segment
		(start 52.92725 -129.1717)
		(end 51.456082 -129.1717)
		(width 0.127)
		(layer "In5.Cu")
		(net "I2C_TPM_SCL")
	)
	(segment
		(start 70.604888 -125.5141)
		(end 70.13067 -125.988318)
		(width 0.127)
		(layer "In5.Cu")
		(net "I2C_TPM_SCL")
	)
	(segment
		(start 51.456082 -129.1717)
		(end 51.100482 -128.8161)
		(width 0.127)
		(layer "In5.Cu")
		(net "I2C_TPM_SCL")
	)
	(segment
		(start 69.2912 -126.2888)
		(end 65.9765 -126.2888)
		(width 0.127)
		(layer "In5.Cu")
		(net "I2C_TPM_SCL")
	)
	(segment
		(start 58.7756 -126.0602)
		(end 58.2549 -126.5809)
		(width 0.127)
		(layer "In5.Cu")
		(net "I2C_TPM_SCL")
	)
	(segment
		(start 82.182716 -177.051716)
		(end 83.334098 -178.203098)
		(width 0.127)
		(layer "In5.Cu")
		(net "I2C_TPM_SCL")
	)
	(via
		(at 63.1698 -137.16)
		(size 0.508)
		(drill 0.254)
		(layers "F.Cu" "B.Cu")
		(net "I2C_M2_2_SDA")
	)
	(via
		(at 65.5193 -111.9124)
		(size 0.508)
		(drill 0.254)
		(layers "F.Cu" "B.Cu")
		(net "I2C_M2_2_SDA")
	)
	(via
		(at 179.028344 -115.148106)
		(size 0.508)
		(drill 0.254)
		(layers "F.Cu" "B.Cu")
		(net "I2C_M2_2_SDA")
	)
	(via
		(at 62.601602 -140.496798)
		(size 0.6096)
		(drill 0.3048)
		(layers "F.Cu" "B.Cu")
		(net "I2C_M2_2_SDA")
	)
	(segment
		(start 63.1698 -137.16)
		(end 63.2333 -137.2235)
		(width 0.127)
		(layer "B.Cu")
		(net "I2C_M2_2_SDA")
	)
	(segment
		(start 178.53406 -116.038884)
		(end 178.53406 -117.065044)
		(width 0.127)
		(layer "B.Cu")
		(net "I2C_M2_2_SDA")
	)
	(segment
		(start 62.601602 -140.496798)
		(end 61.849 -141.2494)
		(width 0.127)
		(layer "B.Cu")
		(net "I2C_M2_2_SDA")
	)
	(segment
		(start 178.737006 -115.835938)
		(end 178.53406 -116.038884)
		(width 0.127)
		(layer "B.Cu")
		(net "I2C_M2_2_SDA")
	)
	(segment
		(start 179.028344 -115.148106)
		(end 178.737006 -115.439444)
		(width 0.127)
		(layer "B.Cu")
		(net "I2C_M2_2_SDA")
	)
	(segment
		(start 178.737006 -115.439444)
		(end 178.737006 -115.835938)
		(width 0.127)
		(layer "B.Cu")
		(net "I2C_M2_2_SDA")
	)
	(segment
		(start 63.2333 -137.2235)
		(end 63.2333 -138.0744)
		(width 0.127)
		(layer "B.Cu")
		(net "I2C_M2_2_SDA")
	)
	(segment
		(start 63.2333 -138.8618)
		(end 63.124334 -138.970766)
		(width 0.127)
		(layer "B.Cu")
		(net "I2C_M2_2_SDA")
	)
	(segment
		(start 61.849 -141.2494)
		(end 61.3283 -141.2494)
		(width 0.127)
		(layer "B.Cu")
		(net "I2C_M2_2_SDA")
	)
	(segment
		(start 63.124334 -139.974066)
		(end 62.601602 -140.496798)
		(width 0.127)
		(layer "B.Cu")
		(net "I2C_M2_2_SDA")
	)
	(segment
		(start 63.2333 -138.0744)
		(end 63.2333 -138.8618)
		(width 0.127)
		(layer "B.Cu")
		(net "I2C_M2_2_SDA")
	)
	(segment
		(start 63.124334 -138.970766)
		(end 63.124334 -139.974066)
		(width 0.127)
		(layer "B.Cu")
		(net "I2C_M2_2_SDA")
	)
	(segment
		(start 63.62446 -136.484106)
		(end 63.5508 -136.557766)
		(width 0.127)
		(layer "In2.Cu")
		(net "I2C_M2_2_SDA")
	)
	(segment
		(start 65.6844 -132.594604)
		(end 63.62446 -134.654544)
		(width 0.127)
		(layer "In2.Cu")
		(net "I2C_M2_2_SDA")
	)
	(segment
		(start 65.369186 -120.472708)
		(end 65.369186 -127.257556)
		(width 0.127)
		(layer "In2.Cu")
		(net "I2C_M2_2_SDA")
	)
	(segment
		(start 65.5193 -120.322594)
		(end 65.369186 -120.472708)
		(width 0.127)
		(layer "In2.Cu")
		(net "I2C_M2_2_SDA")
	)
	(segment
		(start 63.1698 -136.93902)
		(end 63.1698 -137.16)
		(width 0.127)
		(layer "In2.Cu")
		(net "I2C_M2_2_SDA")
	)
	(segment
		(start 65.369186 -127.257556)
		(end 65.6844 -127.57277)
		(width 0.127)
		(layer "In2.Cu")
		(net "I2C_M2_2_SDA")
	)
	(segment
		(start 63.5508 -136.55802)
		(end 63.1698 -136.93902)
		(width 0.127)
		(layer "In2.Cu")
		(net "I2C_M2_2_SDA")
	)
	(segment
		(start 63.5508 -136.557766)
		(end 63.5508 -136.55802)
		(width 0.127)
		(layer "In2.Cu")
		(net "I2C_M2_2_SDA")
	)
	(segment
		(start 65.5193 -111.9124)
		(end 65.5193 -120.322594)
		(width 0.127)
		(layer "In2.Cu")
		(net "I2C_M2_2_SDA")
	)
	(segment
		(start 65.6844 -127.57277)
		(end 65.6844 -132.594604)
		(width 0.127)
		(layer "In2.Cu")
		(net "I2C_M2_2_SDA")
	)
	(segment
		(start 63.62446 -134.654544)
		(end 63.62446 -136.484106)
		(width 0.127)
		(layer "In2.Cu")
		(net "I2C_M2_2_SDA")
	)
	(segment
		(start 174.841662 -2.9591)
		(end 97.753932 -2.9591)
		(width 0.127)
		(layer "In5.Cu")
		(net "I2C_M2_2_SDA")
	)
	(segment
		(start 179.028344 -115.148106)
		(end 181.356 -112.82045)
		(width 0.127)
		(layer "In5.Cu")
		(net "I2C_M2_2_SDA")
	)
	(segment
		(start 65.6971 -111.7346)
		(end 65.5193 -111.9124)
		(width 0.127)
		(layer "In5.Cu")
		(net "I2C_M2_2_SDA")
	)
	(segment
		(start 76.389992 -37.676074)
		(end 76.389992 -44.398438)
		(width 0.127)
		(layer "In5.Cu")
		(net "I2C_M2_2_SDA")
	)
	(segment
		(start 76.1492 -44.63923)
		(end 76.1492 -46.937676)
		(width 0.127)
		(layer "In5.Cu")
		(net "I2C_M2_2_SDA")
	)
	(segment
		(start 74.6252 -110.626398)
		(end 73.516744 -111.7346)
		(width 0.127)
		(layer "In5.Cu")
		(net "I2C_M2_2_SDA")
	)
	(segment
		(start 92.492576 -7.378192)
		(end 83.996276 -7.378192)
		(width 0.127)
		(layer "In5.Cu")
		(net "I2C_M2_2_SDA")
	)
	(segment
		(start 96.911922 -2.958846)
		(end 92.492576 -7.378192)
		(width 0.127)
		(layer "In5.Cu")
		(net "I2C_M2_2_SDA")
	)
	(segment
		(start 214.73414 -15.694914)
		(end 207.612234 -8.573008)
		(width 0.127)
		(layer "In5.Cu")
		(net "I2C_M2_2_SDA")
	)
	(segment
		(start 181.356 -110.866682)
		(end 187.167774 -105.054908)
		(width 0.127)
		(layer "In5.Cu")
		(net "I2C_M2_2_SDA")
	)
	(segment
		(start 214.73414 -33.5026)
		(end 214.73414 -15.694914)
		(width 0.127)
		(layer "In5.Cu")
		(net "I2C_M2_2_SDA")
	)
	(segment
		(start 207.612234 -8.573008)
		(end 202.285854 -8.573008)
		(width 0.127)
		(layer "In5.Cu")
		(net "I2C_M2_2_SDA")
	)
	(segment
		(start 208.711292 -105.054908)
		(end 212.73262 -101.03358)
		(width 0.127)
		(layer "In5.Cu")
		(net "I2C_M2_2_SDA")
	)
	(segment
		(start 97.753932 -2.9591)
		(end 97.753678 -2.958846)
		(width 0.127)
		(layer "In5.Cu")
		(net "I2C_M2_2_SDA")
	)
	(segment
		(start 76.1492 -46.937676)
		(end 74.6252 -48.461676)
		(width 0.127)
		(layer "In5.Cu")
		(net "I2C_M2_2_SDA")
	)
	(segment
		(start 212.73262 -47.02302)
		(end 212.73262 -35.50412)
		(width 0.127)
		(layer "In5.Cu")
		(net "I2C_M2_2_SDA")
	)
	(segment
		(start 200.494646 -6.7818)
		(end 178.664362 -6.7818)
		(width 0.127)
		(layer "In5.Cu")
		(net "I2C_M2_2_SDA")
	)
	(segment
		(start 74.6252 -48.461676)
		(end 74.6252 -110.626398)
		(width 0.127)
		(layer "In5.Cu")
		(net "I2C_M2_2_SDA")
	)
	(segment
		(start 178.664362 -6.7818)
		(end 174.841662 -2.9591)
		(width 0.127)
		(layer "In5.Cu")
		(net "I2C_M2_2_SDA")
	)
	(segment
		(start 187.167774 -105.054908)
		(end 208.711292 -105.054908)
		(width 0.127)
		(layer "In5.Cu")
		(net "I2C_M2_2_SDA")
	)
	(segment
		(start 73.516744 -111.7346)
		(end 65.6971 -111.7346)
		(width 0.127)
		(layer "In5.Cu")
		(net "I2C_M2_2_SDA")
	)
	(segment
		(start 212.73262 -35.50412)
		(end 214.73414 -33.5026)
		(width 0.127)
		(layer "In5.Cu")
		(net "I2C_M2_2_SDA")
	)
	(segment
		(start 181.356 -112.82045)
		(end 181.356 -110.866682)
		(width 0.127)
		(layer "In5.Cu")
		(net "I2C_M2_2_SDA")
	)
	(segment
		(start 83.996276 -7.378192)
		(end 79.53121 -11.843258)
		(width 0.127)
		(layer "In5.Cu")
		(net "I2C_M2_2_SDA")
	)
	(segment
		(start 213.796372 -48.086772)
		(end 212.73262 -47.02302)
		(width 0.127)
		(layer "In5.Cu")
		(net "I2C_M2_2_SDA")
	)
	(segment
		(start 76.389992 -44.398438)
		(end 76.1492 -44.63923)
		(width 0.127)
		(layer "In5.Cu")
		(net "I2C_M2_2_SDA")
	)
	(segment
		(start 79.53121 -11.843258)
		(end 79.53121 -34.534856)
		(width 0.127)
		(layer "In5.Cu")
		(net "I2C_M2_2_SDA")
	)
	(segment
		(start 212.73262 -88.870282)
		(end 213.796372 -87.80653)
		(width 0.127)
		(layer "In5.Cu")
		(net "I2C_M2_2_SDA")
	)
	(segment
		(start 79.53121 -34.534856)
		(end 76.389992 -37.676074)
		(width 0.127)
		(layer "In5.Cu")
		(net "I2C_M2_2_SDA")
	)
	(segment
		(start 212.73262 -101.03358)
		(end 212.73262 -88.870282)
		(width 0.127)
		(layer "In5.Cu")
		(net "I2C_M2_2_SDA")
	)
	(segment
		(start 213.796372 -87.80653)
		(end 213.796372 -48.086772)
		(width 0.127)
		(layer "In5.Cu")
		(net "I2C_M2_2_SDA")
	)
	(segment
		(start 202.285854 -8.573008)
		(end 200.494646 -6.7818)
		(width 0.127)
		(layer "In5.Cu")
		(net "I2C_M2_2_SDA")
	)
	(segment
		(start 97.753678 -2.958846)
		(end 96.911922 -2.958846)
		(width 0.127)
		(layer "In5.Cu")
		(net "I2C_M2_2_SDA")
	)
	(via
		(at 62.5856 -139.1666)
		(size 0.6096)
		(drill 0.3048)
		(layers "F.Cu" "B.Cu")
		(net "I2C_M2_2_SCL")
	)
	(via
		(at 62.1919 -137.1981)
		(size 0.508)
		(drill 0.254)
		(layers "F.Cu" "B.Cu")
		(net "I2C_M2_2_SCL")
	)
	(via
		(at 178.100482 -115.148106)
		(size 0.508)
		(drill 0.254)
		(layers "F.Cu" "B.Cu")
		(net "I2C_M2_2_SCL")
	)
	(via
		(at 64.5414 -111.9632)
		(size 0.508)
		(drill 0.254)
		(layers "F.Cu" "B.Cu")
		(net "I2C_M2_2_SCL")
	)
	(segment
		(start 62.5856 -139.6746)
		(end 62.0776 -140.1826)
		(width 0.127)
		(layer "B.Cu")
		(net "I2C_M2_2_SCL")
	)
	(segment
		(start 177.88382 -115.970558)
		(end 177.88382 -117.065044)
		(width 0.127)
		(layer "B.Cu")
		(net "I2C_M2_2_SCL")
	)
	(segment
		(start 62.1919 -138.0998)
		(end 62.1919 -137.1981)
		(width 0.127)
		(layer "B.Cu")
		(net "I2C_M2_2_SCL")
	)
	(segment
		(start 178.224434 -115.629944)
		(end 177.88382 -115.970558)
		(width 0.127)
		(layer "B.Cu")
		(net "I2C_M2_2_SCL")
	)
	(segment
		(start 62.0776 -140.1826)
		(end 61.3283 -140.1826)
		(width 0.127)
		(layer "B.Cu")
		(net "I2C_M2_2_SCL")
	)
	(segment
		(start 178.100482 -115.148106)
		(end 178.224434 -115.272058)
		(width 0.127)
		(layer "B.Cu")
		(net "I2C_M2_2_SCL")
	)
	(segment
		(start 62.5856 -139.1666)
		(end 62.5856 -139.6746)
		(width 0.127)
		(layer "B.Cu")
		(net "I2C_M2_2_SCL")
	)
	(segment
		(start 178.224434 -115.272058)
		(end 178.224434 -115.629944)
		(width 0.127)
		(layer "B.Cu")
		(net "I2C_M2_2_SCL")
	)
	(segment
		(start 62.1919 -138.0998)
		(end 62.5856 -138.4935)
		(width 0.127)
		(layer "B.Cu")
		(net "I2C_M2_2_SCL")
	)
	(segment
		(start 62.5856 -138.4935)
		(end 62.5856 -139.1666)
		(width 0.127)
		(layer "B.Cu")
		(net "I2C_M2_2_SCL")
	)
	(segment
		(start 64.5414 -114.648234)
		(end 64.915288 -115.022122)
		(width 0.127)
		(layer "In2.Cu")
		(net "I2C_M2_2_SCL")
	)
	(segment
		(start 65.1764 -132.384038)
		(end 63.11646 -134.443978)
		(width 0.127)
		(layer "In2.Cu")
		(net "I2C_M2_2_SCL")
	)
	(segment
		(start 64.5414 -118.223792)
		(end 64.5414 -118.81993)
		(width 0.127)
		(layer "In2.Cu")
		(net "I2C_M2_2_SCL")
	)
	(segment
		(start 64.861186 -127.468122)
		(end 65.1764 -127.783336)
		(width 0.127)
		(layer "In2.Cu")
		(net "I2C_M2_2_SCL")
	)
	(segment
		(start 64.5414 -111.9632)
		(end 64.5414 -114.648234)
		(width 0.127)
		(layer "In2.Cu")
		(net "I2C_M2_2_SCL")
	)
	(segment
		(start 65.1764 -127.783336)
		(end 65.1764 -132.384038)
		(width 0.127)
		(layer "In2.Cu")
		(net "I2C_M2_2_SCL")
	)
	(segment
		(start 64.675004 -120.07596)
		(end 64.861186 -120.262142)
		(width 0.127)
		(layer "In2.Cu")
		(net "I2C_M2_2_SCL")
	)
	(segment
		(start 64.5414 -118.81993)
		(end 64.675004 -118.953534)
		(width 0.127)
		(layer "In2.Cu")
		(net "I2C_M2_2_SCL")
	)
	(segment
		(start 64.915288 -117.849904)
		(end 64.5414 -118.223792)
		(width 0.127)
		(layer "In2.Cu")
		(net "I2C_M2_2_SCL")
	)
	(segment
		(start 63.11646 -134.443978)
		(end 63.11646 -136.27354)
		(width 0.127)
		(layer "In2.Cu")
		(net "I2C_M2_2_SCL")
	)
	(segment
		(start 64.915288 -115.022122)
		(end 64.915288 -117.849904)
		(width 0.127)
		(layer "In2.Cu")
		(net "I2C_M2_2_SCL")
	)
	(segment
		(start 64.861186 -120.262142)
		(end 64.861186 -127.468122)
		(width 0.127)
		(layer "In2.Cu")
		(net "I2C_M2_2_SCL")
	)
	(segment
		(start 64.675004 -118.953534)
		(end 64.675004 -120.07596)
		(width 0.127)
		(layer "In2.Cu")
		(net "I2C_M2_2_SCL")
	)
	(segment
		(start 63.11646 -136.27354)
		(end 62.1919 -137.1981)
		(width 0.127)
		(layer "In2.Cu")
		(net "I2C_M2_2_SCL")
	)
	(segment
		(start 82.344514 -104.16159)
		(end 80.595724 -102.4128)
		(width 0.127)
		(layer "In5.Cu")
		(net "I2C_M2_2_SCL")
	)
	(segment
		(start 92.703142 -7.886192)
		(end 97.122234 -3.4671)
		(width 0.127)
		(layer "In5.Cu")
		(net "I2C_M2_2_SCL")
	)
	(segment
		(start 75.3237 -48.481742)
		(end 76.6572 -47.148242)
		(width 0.127)
		(layer "In5.Cu")
		(net "I2C_M2_2_SCL")
	)
	(segment
		(start 212.22462 -13.90396)
		(end 212.22462 -84.687664)
		(width 0.127)
		(layer "In5.Cu")
		(net "I2C_M2_2_SCL")
	)
	(segment
		(start 185.741564 -104.546908)
		(end 180.1622 -110.126272)
		(width 0.127)
		(layer "In5.Cu")
		(net "I2C_M2_2_SCL")
	)
	(segment
		(start 76.6572 -47.148242)
		(end 76.6572 -44.849796)
		(width 0.127)
		(layer "In5.Cu")
		(net "I2C_M2_2_SCL")
	)
	(segment
		(start 84.206842 -7.886192)
		(end 92.703142 -7.886192)
		(width 0.127)
		(layer "In5.Cu")
		(net "I2C_M2_2_SCL")
	)
	(segment
		(start 80.595724 -102.4128)
		(end 78.35519 -102.4128)
		(width 0.127)
		(layer "In5.Cu")
		(net "I2C_M2_2_SCL")
	)
	(segment
		(start 81.02727 -40.479726)
		(end 81.02727 -11.065764)
		(width 0.127)
		(layer "In5.Cu")
		(net "I2C_M2_2_SCL")
	)
	(segment
		(start 207.401668 -9.081008)
		(end 212.22462 -13.90396)
		(width 0.127)
		(layer "In5.Cu")
		(net "I2C_M2_2_SCL")
	)
	(segment
		(start 200.28408 -7.2898)
		(end 202.075288 -9.081008)
		(width 0.127)
		(layer "In5.Cu")
		(net "I2C_M2_2_SCL")
	)
	(segment
		(start 213.148164 -85.611208)
		(end 213.148164 -87.736172)
		(width 0.127)
		(layer "In5.Cu")
		(net "I2C_M2_2_SCL")
	)
	(segment
		(start 174.631096 -3.4671)
		(end 178.453796 -7.2898)
		(width 0.127)
		(layer "In5.Cu")
		(net "I2C_M2_2_SCL")
	)
	(segment
		(start 180.1622 -113.212626)
		(end 179.599082 -113.775744)
		(width 0.127)
		(layer "In5.Cu")
		(net "I2C_M2_2_SCL")
	)
	(segment
		(start 75.3237 -99.38131)
		(end 75.3237 -48.481742)
		(width 0.127)
		(layer "In5.Cu")
		(net "I2C_M2_2_SCL")
	)
	(segment
		(start 64.9605 -112.3823)
		(end 65.9257 -112.3823)
		(width 0.127)
		(layer "In5.Cu")
		(net "I2C_M2_2_SCL")
	)
	(segment
		(start 79.749142 -108.533946)
		(end 82.344514 -105.938574)
		(width 0.127)
		(layer "In5.Cu")
		(net "I2C_M2_2_SCL")
	)
	(segment
		(start 78.35519 -102.4128)
		(end 75.3237 -99.38131)
		(width 0.127)
		(layer "In5.Cu")
		(net "I2C_M2_2_SCL")
	)
	(segment
		(start 66.0654 -112.2426)
		(end 73.727564 -112.2426)
		(width 0.127)
		(layer "In5.Cu")
		(net "I2C_M2_2_SCL")
	)
	(segment
		(start 213.148164 -87.736172)
		(end 212.22462 -88.659716)
		(width 0.127)
		(layer "In5.Cu")
		(net "I2C_M2_2_SCL")
	)
	(segment
		(start 82.344514 -105.938574)
		(end 82.344514 -104.16159)
		(width 0.127)
		(layer "In5.Cu")
		(net "I2C_M2_2_SCL")
	)
	(segment
		(start 64.5414 -111.9632)
		(end 64.9605 -112.3823)
		(width 0.127)
		(layer "In5.Cu")
		(net "I2C_M2_2_SCL")
	)
	(segment
		(start 212.22462 -84.687664)
		(end 213.148164 -85.611208)
		(width 0.127)
		(layer "In5.Cu")
		(net "I2C_M2_2_SCL")
	)
	(segment
		(start 76.6572 -44.849796)
		(end 81.02727 -40.479726)
		(width 0.127)
		(layer "In5.Cu")
		(net "I2C_M2_2_SCL")
	)
	(segment
		(start 178.453796 -7.2898)
		(end 200.28408 -7.2898)
		(width 0.127)
		(layer "In5.Cu")
		(net "I2C_M2_2_SCL")
	)
	(segment
		(start 73.727564 -112.2426)
		(end 77.436218 -108.533946)
		(width 0.127)
		(layer "In5.Cu")
		(net "I2C_M2_2_SCL")
	)
	(segment
		(start 180.1622 -110.126272)
		(end 180.1622 -113.212626)
		(width 0.127)
		(layer "In5.Cu")
		(net "I2C_M2_2_SCL")
	)
	(segment
		(start 179.599082 -113.775744)
		(end 179.472844 -113.775744)
		(width 0.127)
		(layer "In5.Cu")
		(net "I2C_M2_2_SCL")
	)
	(segment
		(start 212.22462 -100.514912)
		(end 208.192624 -104.546908)
		(width 0.127)
		(layer "In5.Cu")
		(net "I2C_M2_2_SCL")
	)
	(segment
		(start 212.22462 -88.659716)
		(end 212.22462 -100.514912)
		(width 0.127)
		(layer "In5.Cu")
		(net "I2C_M2_2_SCL")
	)
	(segment
		(start 202.075288 -9.081008)
		(end 207.401668 -9.081008)
		(width 0.127)
		(layer "In5.Cu")
		(net "I2C_M2_2_SCL")
	)
	(segment
		(start 65.9257 -112.3823)
		(end 66.0654 -112.2426)
		(width 0.127)
		(layer "In5.Cu")
		(net "I2C_M2_2_SCL")
	)
	(segment
		(start 179.472844 -113.775744)
		(end 178.100482 -115.148106)
		(width 0.127)
		(layer "In5.Cu")
		(net "I2C_M2_2_SCL")
	)
	(segment
		(start 77.436218 -108.533946)
		(end 79.749142 -108.533946)
		(width 0.127)
		(layer "In5.Cu")
		(net "I2C_M2_2_SCL")
	)
	(segment
		(start 208.192624 -104.546908)
		(end 185.741564 -104.546908)
		(width 0.127)
		(layer "In5.Cu")
		(net "I2C_M2_2_SCL")
	)
	(segment
		(start 81.02727 -11.065764)
		(end 84.206842 -7.886192)
		(width 0.127)
		(layer "In5.Cu")
		(net "I2C_M2_2_SCL")
	)
	(segment
		(start 97.122234 -3.4671)
		(end 174.631096 -3.4671)
		(width 0.127)
		(layer "In5.Cu")
		(net "I2C_M2_2_SCL")
	)
	(segment
		(start 43.8658 -159.080962)
		(end 43.5356 -159.411162)
		(width 0.127)
		(layer "F.Cu")
		(net "I2C_M2_1_SDA")
	)
	(segment
		(start 43.3324 -160.4518)
		(end 43.3324 -160.9725)
		(width 0.127)
		(layer "F.Cu")
		(net "I2C_M2_1_SDA")
	)
	(segment
		(start 43.5356 -159.411162)
		(end 43.5356 -160.0708)
		(width 0.127)
		(layer "F.Cu")
		(net "I2C_M2_1_SDA")
	)
	(segment
		(start 43.8658 -159.0421)
		(end 43.8658 -159.080962)
		(width 0.127)
		(layer "F.Cu")
		(net "I2C_M2_1_SDA")
	)
	(segment
		(start 43.5356 -160.2486)
		(end 43.3324 -160.4518)
		(width 0.127)
		(layer "F.Cu")
		(net "I2C_M2_1_SDA")
	)
	(segment
		(start 43.5356 -160.0708)
		(end 43.5356 -160.2486)
		(width 0.127)
		(layer "F.Cu")
		(net "I2C_M2_1_SDA")
	)
	(via
		(at 43.5356 -160.0708)
		(size 0.508)
		(drill 0.254)
		(layers "F.Cu" "B.Cu")
		(net "I2C_M2_1_SDA")
	)
	(via
		(at 88.141302 -166.64686)
		(size 0.508)
		(drill 0.254)
		(layers "F.Cu" "B.Cu")
		(net "I2C_M2_1_SDA")
	)
	(via
		(at 43.802046 -160.945576)
		(size 0.6096)
		(drill 0.3048)
		(layers "F.Cu" "B.Cu")
		(net "I2C_M2_1_SDA")
	)
	(via
		(at 208.7118 -102.5906)
		(size 0.508)
		(drill 0.254)
		(layers "F.Cu" "B.Cu")
		(net "I2C_M2_1_SDA")
	)
	(via
		(at 112.9792 -20.930616)
		(size 0.508)
		(drill 0.254)
		(layers "F.Cu" "B.Cu")
		(net "I2C_M2_1_SDA")
	)
	(segment
		(start 208.134712 -103.447088)
		(end 208.7118 -102.87)
		(width 0.127)
		(layer "B.Cu")
		(net "I2C_M2_1_SDA")
	)
	(segment
		(start 208.134712 -104.098598)
		(end 208.134712 -103.447088)
		(width 0.127)
		(layer "B.Cu")
		(net "I2C_M2_1_SDA")
	)
	(segment
		(start 44.4119 -161.55543)
		(end 43.802046 -160.945576)
		(width 0.127)
		(layer "B.Cu")
		(net "I2C_M2_1_SDA")
	)
	(segment
		(start 71.357744 -164.719)
		(end 69.544692 -162.905948)
		(width 0.127)
		(layer "B.Cu")
		(net "I2C_M2_1_SDA")
	)
	(segment
		(start 62.0014 -165.735)
		(end 61.6331 -166.1033)
		(width 0.127)
		(layer "B.Cu")
		(net "I2C_M2_1_SDA")
	)
	(segment
		(start 43.5356 -160.67913)
		(end 43.802046 -160.945576)
		(width 0.127)
		(layer "B.Cu")
		(net "I2C_M2_1_SDA")
	)
	(segment
		(start 66.17081 -162.905948)
		(end 63.341758 -165.735)
		(width 0.127)
		(layer "B.Cu")
		(net "I2C_M2_1_SDA")
	)
	(segment
		(start 63.341758 -165.735)
		(end 62.0014 -165.735)
		(width 0.127)
		(layer "B.Cu")
		(net "I2C_M2_1_SDA")
	)
	(segment
		(start 86.493096 -167.417496)
		(end 83.7946 -164.719)
		(width 0.127)
		(layer "B.Cu")
		(net "I2C_M2_1_SDA")
	)
	(segment
		(start 43.5356 -160.0708)
		(end 43.5356 -160.67913)
		(width 0.127)
		(layer "B.Cu")
		(net "I2C_M2_1_SDA")
	)
	(segment
		(start 61.6331 -166.1033)
		(end 53.8607 -166.1033)
		(width 0.127)
		(layer "B.Cu")
		(net "I2C_M2_1_SDA")
	)
	(segment
		(start 53.8607 -166.1033)
		(end 53.2765 -166.6875)
		(width 0.127)
		(layer "B.Cu")
		(net "I2C_M2_1_SDA")
	)
	(segment
		(start 45.016928 -163.2585)
		(end 44.7675 -163.2585)
		(width 0.127)
		(layer "B.Cu")
		(net "I2C_M2_1_SDA")
	)
	(segment
		(start 83.7946 -164.719)
		(end 71.357744 -164.719)
		(width 0.127)
		(layer "B.Cu")
		(net "I2C_M2_1_SDA")
	)
	(segment
		(start 88.141302 -166.64686)
		(end 87.370666 -167.417496)
		(width 0.127)
		(layer "B.Cu")
		(net "I2C_M2_1_SDA")
	)
	(segment
		(start 53.2765 -166.6875)
		(end 48.445928 -166.6875)
		(width 0.127)
		(layer "B.Cu")
		(net "I2C_M2_1_SDA")
	)
	(segment
		(start 69.544692 -162.905948)
		(end 66.17081 -162.905948)
		(width 0.127)
		(layer "B.Cu")
		(net "I2C_M2_1_SDA")
	)
	(segment
		(start 44.4119 -162.9029)
		(end 44.4119 -161.55543)
		(width 0.127)
		(layer "B.Cu")
		(net "I2C_M2_1_SDA")
	)
	(segment
		(start 87.370666 -167.417496)
		(end 86.493096 -167.417496)
		(width 0.127)
		(layer "B.Cu")
		(net "I2C_M2_1_SDA")
	)
	(segment
		(start 44.7675 -163.2585)
		(end 44.4119 -162.9029)
		(width 0.127)
		(layer "B.Cu")
		(net "I2C_M2_1_SDA")
	)
	(segment
		(start 48.445928 -166.6875)
		(end 45.016928 -163.2585)
		(width 0.127)
		(layer "B.Cu")
		(net "I2C_M2_1_SDA")
	)
	(segment
		(start 208.7118 -102.87)
		(end 208.7118 -102.5906)
		(width 0.127)
		(layer "B.Cu")
		(net "I2C_M2_1_SDA")
	)
	(segment
		(start 92.8116 -94.31274)
		(end 92.8116 -93.990668)
		(width 0.127)
		(layer "In2.Cu")
		(net "I2C_M2_1_SDA")
	)
	(segment
		(start 90.4621 -127.41529)
		(end 90.4621 -126.270512)
		(width 0.127)
		(layer "In2.Cu")
		(net "I2C_M2_1_SDA")
	)
	(segment
		(start 90.7034 -120.083834)
		(end 90.792554 -119.99468)
		(width 0.127)
		(layer "In2.Cu")
		(net "I2C_M2_1_SDA")
	)
	(segment
		(start 88.141302 -163.875974)
		(end 88.001856 -163.736528)
		(width 0.127)
		(layer "In2.Cu")
		(net "I2C_M2_1_SDA")
	)
	(segment
		(start 92.878148 -35.711384)
		(end 95.300546 -33.288986)
		(width 0.127)
		(layer "In2.Cu")
		(net "I2C_M2_1_SDA")
	)
	(segment
		(start 92.4306 -63.541656)
		(end 92.964 -63.008256)
		(width 0.127)
		(layer "In2.Cu")
		(net "I2C_M2_1_SDA")
	)
	(segment
		(start 87.867236 -150.580344)
		(end 87.867236 -145.950686)
		(width 0.127)
		(layer "In2.Cu")
		(net "I2C_M2_1_SDA")
	)
	(segment
		(start 89.3191 -152.032208)
		(end 87.867236 -150.580344)
		(width 0.127)
		(layer "In2.Cu")
		(net "I2C_M2_1_SDA")
	)
	(segment
		(start 91.7956 -52.122832)
		(end 91.7956 -48.714914)
		(width 0.127)
		(layer "In2.Cu")
		(net "I2C_M2_1_SDA")
	)
	(segment
		(start 87.867236 -145.950686)
		(end 90.619834 -143.198088)
		(width 0.127)
		(layer "In2.Cu")
		(net "I2C_M2_1_SDA")
	)
	(segment
		(start 93.4212 -110.600236)
		(end 93.4212 -94.92234)
		(width 0.127)
		(layer "In2.Cu")
		(net "I2C_M2_1_SDA")
	)
	(segment
		(start 92.964 -53.291232)
		(end 91.7956 -52.122832)
		(width 0.127)
		(layer "In2.Cu")
		(net "I2C_M2_1_SDA")
	)
	(segment
		(start 88.001856 -163.736528)
		(end 88.001856 -162.07232)
		(width 0.127)
		(layer "In2.Cu")
		(net "I2C_M2_1_SDA")
	)
	(segment
		(start 90.619834 -143.198088)
		(end 90.619834 -131.574286)
		(width 0.127)
		(layer "In2.Cu")
		(net "I2C_M2_1_SDA")
	)
	(segment
		(start 90.4621 -126.270512)
		(end 90.7034 -126.029212)
		(width 0.127)
		(layer "In2.Cu")
		(net "I2C_M2_1_SDA")
	)
	(segment
		(start 88.001856 -162.07232)
		(end 89.3191 -160.755076)
		(width 0.127)
		(layer "In2.Cu")
		(net "I2C_M2_1_SDA")
	)
	(segment
		(start 89.8525 -130.806952)
		(end 89.8525 -128.02489)
		(width 0.127)
		(layer "In2.Cu")
		(net "I2C_M2_1_SDA")
	)
	(segment
		(start 92.8116 -93.990668)
		(end 92.4306 -93.609668)
		(width 0.127)
		(layer "In2.Cu")
		(net "I2C_M2_1_SDA")
	)
	(segment
		(start 103.08971 -20.930616)
		(end 112.9792 -20.930616)
		(width 0.127)
		(layer "In2.Cu")
		(net "I2C_M2_1_SDA")
	)
	(segment
		(start 89.3699 -155.21051)
		(end 89.3191 -155.15971)
		(width 0.127)
		(layer "In2.Cu")
		(net "I2C_M2_1_SDA")
	)
	(segment
		(start 89.3699 -156.021278)
		(end 89.3699 -155.21051)
		(width 0.127)
		(layer "In2.Cu")
		(net "I2C_M2_1_SDA")
	)
	(segment
		(start 92.964 -63.008256)
		(end 92.964 -53.291232)
		(width 0.127)
		(layer "In2.Cu")
		(net "I2C_M2_1_SDA")
	)
	(segment
		(start 91.336368 -112.685068)
		(end 93.4212 -110.600236)
		(width 0.127)
		(layer "In2.Cu")
		(net "I2C_M2_1_SDA")
	)
	(segment
		(start 92.4306 -93.609668)
		(end 92.4306 -63.541656)
		(width 0.127)
		(layer "In2.Cu")
		(net "I2C_M2_1_SDA")
	)
	(segment
		(start 90.7034 -126.029212)
		(end 90.7034 -120.083834)
		(width 0.127)
		(layer "In2.Cu")
		(net "I2C_M2_1_SDA")
	)
	(segment
		(start 95.300546 -28.71978)
		(end 103.08971 -20.930616)
		(width 0.127)
		(layer "In2.Cu")
		(net "I2C_M2_1_SDA")
	)
	(segment
		(start 89.3191 -160.755076)
		(end 89.3191 -156.072078)
		(width 0.127)
		(layer "In2.Cu")
		(net "I2C_M2_1_SDA")
	)
	(segment
		(start 90.792554 -119.99468)
		(end 90.792554 -114.426746)
		(width 0.127)
		(layer "In2.Cu")
		(net "I2C_M2_1_SDA")
	)
	(segment
		(start 91.7956 -48.714914)
		(end 92.878148 -47.632366)
		(width 0.127)
		(layer "In2.Cu")
		(net "I2C_M2_1_SDA")
	)
	(segment
		(start 90.792554 -114.426746)
		(end 91.336368 -113.882932)
		(width 0.127)
		(layer "In2.Cu")
		(net "I2C_M2_1_SDA")
	)
	(segment
		(start 91.336368 -113.882932)
		(end 91.336368 -112.685068)
		(width 0.127)
		(layer "In2.Cu")
		(net "I2C_M2_1_SDA")
	)
	(segment
		(start 93.4212 -94.92234)
		(end 92.8116 -94.31274)
		(width 0.127)
		(layer "In2.Cu")
		(net "I2C_M2_1_SDA")
	)
	(segment
		(start 90.619834 -131.574286)
		(end 89.8525 -130.806952)
		(width 0.127)
		(layer "In2.Cu")
		(net "I2C_M2_1_SDA")
	)
	(segment
		(start 89.3191 -155.15971)
		(end 89.3191 -152.032208)
		(width 0.127)
		(layer "In2.Cu")
		(net "I2C_M2_1_SDA")
	)
	(segment
		(start 92.878148 -47.632366)
		(end 92.878148 -35.711384)
		(width 0.127)
		(layer "In2.Cu")
		(net "I2C_M2_1_SDA")
	)
	(segment
		(start 89.3191 -156.072078)
		(end 89.3699 -156.021278)
		(width 0.127)
		(layer "In2.Cu")
		(net "I2C_M2_1_SDA")
	)
	(segment
		(start 88.141302 -166.64686)
		(end 88.141302 -163.875974)
		(width 0.127)
		(layer "In2.Cu")
		(net "I2C_M2_1_SDA")
	)
	(segment
		(start 89.8525 -128.02489)
		(end 90.4621 -127.41529)
		(width 0.127)
		(layer "In2.Cu")
		(net "I2C_M2_1_SDA")
	)
	(segment
		(start 95.300546 -33.288986)
		(end 95.300546 -28.71978)
		(width 0.127)
		(layer "In2.Cu")
		(net "I2C_M2_1_SDA")
	)
	(segment
		(start 175.24603 -6.77672)
		(end 179.455318 -10.986008)
		(width 0.127)
		(layer "In5.Cu")
		(net "I2C_M2_1_SDA")
	)
	(segment
		(start 118.038372 -4.682998)
		(end 127.200914 -4.682998)
		(width 0.127)
		(layer "In5.Cu")
		(net "I2C_M2_1_SDA")
	)
	(segment
		(start 127.65786 -5.139944)
		(end 129.72669 -5.139944)
		(width 0.127)
		(layer "In5.Cu")
		(net "I2C_M2_1_SDA")
	)
	(segment
		(start 172.366686 -6.77672)
		(end 175.24603 -6.77672)
		(width 0.127)
		(layer "In5.Cu")
		(net "I2C_M2_1_SDA")
	)
	(segment
		(start 127.200914 -4.682998)
		(end 127.65786 -5.139944)
		(width 0.127)
		(layer "In5.Cu")
		(net "I2C_M2_1_SDA")
	)
	(segment
		(start 111.990632 -10.730738)
		(end 118.038372 -4.682998)
		(width 0.127)
		(layer "In5.Cu")
		(net "I2C_M2_1_SDA")
	)
	(segment
		(start 210.307682 -100.994718)
		(end 208.7118 -102.5906)
		(width 0.127)
		(layer "In5.Cu")
		(net "I2C_M2_1_SDA")
	)
	(segment
		(start 112.9792 -20.930616)
		(end 111.990632 -19.942048)
		(width 0.127)
		(layer "In5.Cu")
		(net "I2C_M2_1_SDA")
	)
	(segment
		(start 129.72669 -5.139944)
		(end 130.066288 -4.800346)
		(width 0.127)
		(layer "In5.Cu")
		(net "I2C_M2_1_SDA")
	)
	(segment
		(start 206.444596 -10.986008)
		(end 210.307682 -14.849094)
		(width 0.127)
		(layer "In5.Cu")
		(net "I2C_M2_1_SDA")
	)
	(segment
		(start 111.990632 -19.942048)
		(end 111.990632 -10.730738)
		(width 0.127)
		(layer "In5.Cu")
		(net "I2C_M2_1_SDA")
	)
	(segment
		(start 170.390312 -4.800346)
		(end 172.366686 -6.77672)
		(width 0.127)
		(layer "In5.Cu")
		(net "I2C_M2_1_SDA")
	)
	(segment
		(start 210.307682 -14.849094)
		(end 210.307682 -100.994718)
		(width 0.127)
		(layer "In5.Cu")
		(net "I2C_M2_1_SDA")
	)
	(segment
		(start 179.455318 -10.986008)
		(end 206.444596 -10.986008)
		(width 0.127)
		(layer "In5.Cu")
		(net "I2C_M2_1_SDA")
	)
	(segment
		(start 130.066288 -4.800346)
		(end 170.390312 -4.800346)
		(width 0.127)
		(layer "In5.Cu")
		(net "I2C_M2_1_SDA")
	)
	(segment
		(start 44.9072 -159.0421)
		(end 44.398946 -159.550354)
		(width 0.127)
		(layer "F.Cu")
		(net "I2C_M2_1_SCL")
	)
	(segment
		(start 44.3738 -160.9725)
		(end 44.3738 -160.122108)
		(width 0.127)
		(layer "F.Cu")
		(net "I2C_M2_1_SCL")
	)
	(segment
		(start 44.3738 -160.122108)
		(end 44.398946 -160.096962)
		(width 0.127)
		(layer "F.Cu")
		(net "I2C_M2_1_SCL")
	)
	(segment
		(start 44.398946 -159.550354)
		(end 44.398946 -160.096962)
		(width 0.127)
		(layer "F.Cu")
		(net "I2C_M2_1_SCL")
	)
	(via
		(at 208.7372 -101.727)
		(size 0.508)
		(drill 0.254)
		(layers "F.Cu" "B.Cu")
		(net "I2C_M2_1_SCL")
	)
	(via
		(at 87.216488 -166.582344)
		(size 0.508)
		(drill 0.254)
		(layers "F.Cu" "B.Cu")
		(net "I2C_M2_1_SCL")
	)
	(via
		(at 44.398946 -160.096962)
		(size 0.508)
		(drill 0.254)
		(layers "F.Cu" "B.Cu")
		(net "I2C_M2_1_SCL")
	)
	(via
		(at 113.792 -20.422616)
		(size 0.508)
		(drill 0.254)
		(layers "F.Cu" "B.Cu")
		(net "I2C_M2_1_SCL")
	)
	(via
		(at 45.0088 -160.909)
		(size 0.6096)
		(drill 0.3048)
		(layers "F.Cu" "B.Cu")
		(net "I2C_M2_1_SCL")
	)
	(segment
		(start 65.960244 -162.397948)
		(end 63.131192 -165.227)
		(width 0.127)
		(layer "B.Cu")
		(net "I2C_M2_1_SCL")
	)
	(segment
		(start 207.9752 -102.489)
		(end 208.7372 -101.727)
		(width 0.127)
		(layer "B.Cu")
		(net "I2C_M2_1_SCL")
	)
	(segment
		(start 69.803264 -162.397948)
		(end 65.960244 -162.397948)
		(width 0.127)
		(layer "B.Cu")
		(net "I2C_M2_1_SCL")
	)
	(segment
		(start 61.422534 -165.5953)
		(end 52.55895 -165.5953)
		(width 0.127)
		(layer "B.Cu")
		(net "I2C_M2_1_SCL")
	)
	(segment
		(start 61.790834 -165.227)
		(end 61.422534 -165.5953)
		(width 0.127)
		(layer "B.Cu")
		(net "I2C_M2_1_SCL")
	)
	(segment
		(start 207.9752 -102.8446)
		(end 207.9752 -102.489)
		(width 0.127)
		(layer "B.Cu")
		(net "I2C_M2_1_SCL")
	)
	(segment
		(start 45.5041 -162.794442)
		(end 45.5041 -161.4043)
		(width 0.127)
		(layer "B.Cu")
		(net "I2C_M2_1_SCL")
	)
	(segment
		(start 63.131192 -165.227)
		(end 61.790834 -165.227)
		(width 0.127)
		(layer "B.Cu")
		(net "I2C_M2_1_SCL")
	)
	(segment
		(start 87.216488 -166.582344)
		(end 86.470744 -166.582344)
		(width 0.127)
		(layer "B.Cu")
		(net "I2C_M2_1_SCL")
	)
	(segment
		(start 48.584358 -165.8747)
		(end 45.5041 -162.794442)
		(width 0.127)
		(layer "B.Cu")
		(net "I2C_M2_1_SCL")
	)
	(segment
		(start 86.470744 -166.582344)
		(end 84.0486 -164.1602)
		(width 0.127)
		(layer "B.Cu")
		(net "I2C_M2_1_SCL")
	)
	(segment
		(start 51.775614 -165.8747)
		(end 48.584358 -165.8747)
		(width 0.127)
		(layer "B.Cu")
		(net "I2C_M2_1_SCL")
	)
	(segment
		(start 52.40655 -165.7477)
		(end 51.902614 -165.7477)
		(width 0.127)
		(layer "B.Cu")
		(net "I2C_M2_1_SCL")
	)
	(segment
		(start 71.565516 -164.1602)
		(end 69.803264 -162.397948)
		(width 0.127)
		(layer "B.Cu")
		(net "I2C_M2_1_SCL")
	)
	(segment
		(start 84.0486 -164.1602)
		(end 71.565516 -164.1602)
		(width 0.127)
		(layer "B.Cu")
		(net "I2C_M2_1_SCL")
	)
	(segment
		(start 207.484472 -103.335328)
		(end 207.9752 -102.8446)
		(width 0.127)
		(layer "B.Cu")
		(net "I2C_M2_1_SCL")
	)
	(segment
		(start 44.398946 -160.096962)
		(end 44.398946 -160.299146)
		(width 0.127)
		(layer "B.Cu")
		(net "I2C_M2_1_SCL")
	)
	(segment
		(start 44.398946 -160.299146)
		(end 45.0088 -160.909)
		(width 0.127)
		(layer "B.Cu")
		(net "I2C_M2_1_SCL")
	)
	(segment
		(start 52.55895 -165.5953)
		(end 52.40655 -165.7477)
		(width 0.127)
		(layer "B.Cu")
		(net "I2C_M2_1_SCL")
	)
	(segment
		(start 207.484472 -104.098598)
		(end 207.484472 -103.335328)
		(width 0.127)
		(layer "B.Cu")
		(net "I2C_M2_1_SCL")
	)
	(segment
		(start 45.5041 -161.4043)
		(end 45.0088 -160.909)
		(width 0.127)
		(layer "B.Cu")
		(net "I2C_M2_1_SCL")
	)
	(segment
		(start 51.902614 -165.7477)
		(end 51.775614 -165.8747)
		(width 0.127)
		(layer "B.Cu")
		(net "I2C_M2_1_SCL")
	)
	(segment
		(start 87.359236 -150.79091)
		(end 88.8111 -152.242774)
		(width 0.127)
		(layer "In2.Cu")
		(net "I2C_M2_1_SCL")
	)
	(segment
		(start 88.8619 -155.421076)
		(end 88.8619 -155.810712)
		(width 0.127)
		(layer "In2.Cu")
		(net "I2C_M2_1_SCL")
	)
	(segment
		(start 90.284554 -114.21618)
		(end 90.284554 -119.784114)
		(width 0.127)
		(layer "In2.Cu")
		(net "I2C_M2_1_SCL")
	)
	(segment
		(start 90.828368 -112.474502)
		(end 90.828368 -113.672366)
		(width 0.127)
		(layer "In2.Cu")
		(net "I2C_M2_1_SCL")
	)
	(segment
		(start 102.879144 -20.422616)
		(end 94.792038 -28.509722)
		(width 0.127)
		(layer "In2.Cu")
		(net "I2C_M2_1_SCL")
	)
	(segment
		(start 88.8111 -152.242774)
		(end 88.8111 -155.370276)
		(width 0.127)
		(layer "In2.Cu")
		(net "I2C_M2_1_SCL")
	)
	(segment
		(start 90.111834 -142.987522)
		(end 87.359236 -145.74012)
		(width 0.127)
		(layer "In2.Cu")
		(net "I2C_M2_1_SCL")
	)
	(segment
		(start 91.2495 -52.4383)
		(end 92.456 -53.6448)
		(width 0.127)
		(layer "In2.Cu")
		(net "I2C_M2_1_SCL")
	)
	(segment
		(start 90.1954 -125.818646)
		(end 89.3445 -126.669546)
		(width 0.127)
		(layer "In2.Cu")
		(net "I2C_M2_1_SCL")
	)
	(segment
		(start 89.3445 -126.669546)
		(end 89.3445 -131.017518)
		(width 0.127)
		(layer "In2.Cu")
		(net "I2C_M2_1_SCL")
	)
	(segment
		(start 90.828368 -113.672366)
		(end 90.284554 -114.21618)
		(width 0.127)
		(layer "In2.Cu")
		(net "I2C_M2_1_SCL")
	)
	(segment
		(start 89.3445 -131.017518)
		(end 90.111834 -131.784852)
		(width 0.127)
		(layer "In2.Cu")
		(net "I2C_M2_1_SCL")
	)
	(segment
		(start 92.3036 -94.523306)
		(end 92.9132 -95.132906)
		(width 0.127)
		(layer "In2.Cu")
		(net "I2C_M2_1_SCL")
	)
	(segment
		(start 113.792 -20.422616)
		(end 102.879144 -20.422616)
		(width 0.127)
		(layer "In2.Cu")
		(net "I2C_M2_1_SCL")
	)
	(segment
		(start 87.359236 -145.74012)
		(end 87.359236 -150.79091)
		(width 0.127)
		(layer "In2.Cu")
		(net "I2C_M2_1_SCL")
	)
	(segment
		(start 92.3036 -94.201234)
		(end 92.3036 -94.523306)
		(width 0.127)
		(layer "In2.Cu")
		(net "I2C_M2_1_SCL")
	)
	(segment
		(start 92.456 -53.6448)
		(end 92.456 -55.2958)
		(width 0.127)
		(layer "In2.Cu")
		(net "I2C_M2_1_SCL")
	)
	(segment
		(start 88.8111 -155.370276)
		(end 88.8619 -155.421076)
		(width 0.127)
		(layer "In2.Cu")
		(net "I2C_M2_1_SCL")
	)
	(segment
		(start 91.9226 -55.8292)
		(end 91.9226 -93.820234)
		(width 0.127)
		(layer "In2.Cu")
		(net "I2C_M2_1_SCL")
	)
	(segment
		(start 92.9132 -95.132906)
		(end 92.9132 -110.38967)
		(width 0.127)
		(layer "In2.Cu")
		(net "I2C_M2_1_SCL")
	)
	(segment
		(start 92.9132 -110.38967)
		(end 90.828368 -112.474502)
		(width 0.127)
		(layer "In2.Cu")
		(net "I2C_M2_1_SCL")
	)
	(segment
		(start 92.370148 -35.500564)
		(end 92.370148 -47.4218)
		(width 0.127)
		(layer "In2.Cu")
		(net "I2C_M2_1_SCL")
	)
	(segment
		(start 90.111834 -131.784852)
		(end 90.111834 -142.987522)
		(width 0.127)
		(layer "In2.Cu")
		(net "I2C_M2_1_SCL")
	)
	(segment
		(start 90.1954 -119.873268)
		(end 90.1954 -125.818646)
		(width 0.127)
		(layer "In2.Cu")
		(net "I2C_M2_1_SCL")
	)
	(segment
		(start 88.8619 -155.810712)
		(end 88.8111 -155.861512)
		(width 0.127)
		(layer "In2.Cu")
		(net "I2C_M2_1_SCL")
	)
	(segment
		(start 91.2495 -48.542448)
		(end 91.2495 -52.4383)
		(width 0.127)
		(layer "In2.Cu")
		(net "I2C_M2_1_SCL")
	)
	(segment
		(start 91.9226 -93.820234)
		(end 92.3036 -94.201234)
		(width 0.127)
		(layer "In2.Cu")
		(net "I2C_M2_1_SCL")
	)
	(segment
		(start 88.8111 -160.54451)
		(end 87.493856 -161.861754)
		(width 0.127)
		(layer "In2.Cu")
		(net "I2C_M2_1_SCL")
	)
	(segment
		(start 92.456 -55.2958)
		(end 91.9226 -55.8292)
		(width 0.127)
		(layer "In2.Cu")
		(net "I2C_M2_1_SCL")
	)
	(segment
		(start 90.284554 -119.784114)
		(end 90.1954 -119.873268)
		(width 0.127)
		(layer "In2.Cu")
		(net "I2C_M2_1_SCL")
	)
	(segment
		(start 92.370148 -47.4218)
		(end 91.2495 -48.542448)
		(width 0.127)
		(layer "In2.Cu")
		(net "I2C_M2_1_SCL")
	)
	(segment
		(start 94.792038 -28.509722)
		(end 94.792038 -33.078674)
		(width 0.127)
		(layer "In2.Cu")
		(net "I2C_M2_1_SCL")
	)
	(segment
		(start 87.493856 -166.304976)
		(end 87.216488 -166.582344)
		(width 0.127)
		(layer "In2.Cu")
		(net "I2C_M2_1_SCL")
	)
	(segment
		(start 94.792038 -33.078674)
		(end 92.370148 -35.500564)
		(width 0.127)
		(layer "In2.Cu")
		(net "I2C_M2_1_SCL")
	)
	(segment
		(start 88.8111 -155.861512)
		(end 88.8111 -160.54451)
		(width 0.127)
		(layer "In2.Cu")
		(net "I2C_M2_1_SCL")
	)
	(segment
		(start 87.493856 -161.861754)
		(end 87.493856 -166.304976)
		(width 0.127)
		(layer "In2.Cu")
		(net "I2C_M2_1_SCL")
	)
	(segment
		(start 172.15612 -7.28472)
		(end 175.035464 -7.28472)
		(width 0.127)
		(layer "In5.Cu")
		(net "I2C_M2_1_SCL")
	)
	(segment
		(start 112.89284 -19.523456)
		(end 112.89284 -10.547096)
		(width 0.127)
		(layer "In5.Cu")
		(net "I2C_M2_1_SCL")
	)
	(segment
		(start 122.182382 -5.190998)
		(end 126.990348 -5.190998)
		(width 0.127)
		(layer "In5.Cu")
		(net "I2C_M2_1_SCL")
	)
	(segment
		(start 179.244752 -11.494008)
		(end 206.23403 -11.494008)
		(width 0.127)
		(layer "In5.Cu")
		(net "I2C_M2_1_SCL")
	)
	(segment
		(start 175.035464 -7.28472)
		(end 179.244752 -11.494008)
		(width 0.127)
		(layer "In5.Cu")
		(net "I2C_M2_1_SCL")
	)
	(segment
		(start 121.71426 -5.65912)
		(end 122.182382 -5.190998)
		(width 0.127)
		(layer "In5.Cu")
		(net "I2C_M2_1_SCL")
	)
	(segment
		(start 127.447294 -5.647944)
		(end 129.937256 -5.647944)
		(width 0.127)
		(layer "In5.Cu")
		(net "I2C_M2_1_SCL")
	)
	(segment
		(start 113.792 -20.422616)
		(end 112.89284 -19.523456)
		(width 0.127)
		(layer "In5.Cu")
		(net "I2C_M2_1_SCL")
	)
	(segment
		(start 117.780816 -5.65912)
		(end 121.71426 -5.65912)
		(width 0.127)
		(layer "In5.Cu")
		(net "I2C_M2_1_SCL")
	)
	(segment
		(start 130.2766 -5.3086)
		(end 170.18 -5.3086)
		(width 0.127)
		(layer "In5.Cu")
		(net "I2C_M2_1_SCL")
	)
	(segment
		(start 126.990348 -5.190998)
		(end 127.447294 -5.647944)
		(width 0.127)
		(layer "In5.Cu")
		(net "I2C_M2_1_SCL")
	)
	(segment
		(start 209.799682 -100.664518)
		(end 208.7372 -101.727)
		(width 0.127)
		(layer "In5.Cu")
		(net "I2C_M2_1_SCL")
	)
	(segment
		(start 170.18 -5.3086)
		(end 172.15612 -7.28472)
		(width 0.127)
		(layer "In5.Cu")
		(net "I2C_M2_1_SCL")
	)
	(segment
		(start 206.23403 -11.494008)
		(end 209.799682 -15.05966)
		(width 0.127)
		(layer "In5.Cu")
		(net "I2C_M2_1_SCL")
	)
	(segment
		(start 209.799682 -15.05966)
		(end 209.799682 -100.664518)
		(width 0.127)
		(layer "In5.Cu")
		(net "I2C_M2_1_SCL")
	)
	(segment
		(start 129.937256 -5.647944)
		(end 130.2766 -5.3086)
		(width 0.127)
		(layer "In5.Cu")
		(net "I2C_M2_1_SCL")
	)
	(segment
		(start 112.89284 -10.547096)
		(end 117.780816 -5.65912)
		(width 0.127)
		(layer "In5.Cu")
		(net "I2C_M2_1_SCL")
	)
	(segment
		(start 116.788692 -17.788636)
		(end 109.973364 -17.788636)
		(width 0.127)
		(layer "F.Cu")
		(net "I2C_IOM_SDA")
	)
	(segment
		(start 96.8756 -117.348)
		(end 95.8342 -117.348)
		(width 0.127)
		(layer "F.Cu")
		(net "I2C_IOM_SDA")
	)
	(segment
		(start 123.3678 -17.907)
		(end 122.3772 -18.8976)
		(width 0.127)
		(layer "F.Cu")
		(net "I2C_IOM_SDA")
	)
	(segment
		(start 95.8342 -117.348)
		(end 95.642176 -117.155976)
		(width 0.127)
		(layer "F.Cu")
		(net "I2C_IOM_SDA")
	)
	(segment
		(start 122.3772 -18.8976)
		(end 117.897656 -18.8976)
		(width 0.127)
		(layer "F.Cu")
		(net "I2C_IOM_SDA")
	)
	(segment
		(start 98.551746 -26.392378)
		(end 98.551746 -48.333914)
		(width 0.127)
		(layer "F.Cu")
		(net "I2C_IOM_SDA")
	)
	(segment
		(start 109.973364 -17.788636)
		(end 106.268012 -21.493988)
		(width 0.127)
		(layer "F.Cu")
		(net "I2C_IOM_SDA")
	)
	(segment
		(start 117.897656 -18.8976)
		(end 116.788692 -17.788636)
		(width 0.127)
		(layer "F.Cu")
		(net "I2C_IOM_SDA")
	)
	(segment
		(start 125.92177 -5.5372)
		(end 126.045468 -5.660898)
		(width 0.127)
		(layer "F.Cu")
		(net "I2C_IOM_SDA")
	)
	(segment
		(start 95.642176 -117.155976)
		(end 95.642176 -117.012212)
		(width 0.127)
		(layer "F.Cu")
		(net "I2C_IOM_SDA")
	)
	(segment
		(start 98.4758 -132.4864)
		(end 97.72777 -132.4864)
		(width 0.127)
		(layer "F.Cu")
		(net "I2C_IOM_SDA")
	)
	(segment
		(start 98.7171 -113.0173)
		(end 95.642176 -116.092224)
		(width 0.127)
		(layer "F.Cu")
		(net "I2C_IOM_SDA")
	)
	(segment
		(start 95.642176 -116.092224)
		(end 95.642176 -117.012212)
		(width 0.127)
		(layer "F.Cu")
		(net "I2C_IOM_SDA")
	)
	(segment
		(start 97.402396 -132.811774)
		(end 96.288352 -132.811774)
		(width 0.127)
		(layer "F.Cu")
		(net "I2C_IOM_SDA")
	)
	(segment
		(start 103.450136 -21.493988)
		(end 98.551746 -26.392378)
		(width 0.127)
		(layer "F.Cu")
		(net "I2C_IOM_SDA")
	)
	(segment
		(start 106.268012 -21.493988)
		(end 103.450136 -21.493988)
		(width 0.127)
		(layer "F.Cu")
		(net "I2C_IOM_SDA")
	)
	(segment
		(start 98.551746 -48.333914)
		(end 98.7171 -48.499268)
		(width 0.127)
		(layer "F.Cu")
		(net "I2C_IOM_SDA")
	)
	(segment
		(start 98.7171 -48.499268)
		(end 98.7171 -113.0173)
		(width 0.127)
		(layer "F.Cu")
		(net "I2C_IOM_SDA")
	)
	(segment
		(start 181.1528 -99.2505)
		(end 181.1528 -98.4758)
		(width 0.127)
		(layer "F.Cu")
		(net "I2C_IOM_SDA")
	)
	(segment
		(start 125.2601 -5.5372)
		(end 125.92177 -5.5372)
		(width 0.127)
		(layer "F.Cu")
		(net "I2C_IOM_SDA")
	)
	(segment
		(start 202.2094 -98.9965)
		(end 202.2094 -98.2218)
		(width 0.127)
		(layer "F.Cu")
		(net "I2C_IOM_SDA")
	)
	(segment
		(start 97.72777 -132.4864)
		(end 97.402396 -132.811774)
		(width 0.127)
		(layer "F.Cu")
		(net "I2C_IOM_SDA")
	)
	(via
		(at 126.045468 -5.660898)
		(size 0.508)
		(drill 0.254)
		(layers "F.Cu" "B.Cu")
		(net "I2C_IOM_SDA")
	)
	(via
		(at 181.1528 -98.4758)
		(size 0.508)
		(drill 0.254)
		(layers "F.Cu" "B.Cu")
		(net "I2C_IOM_SDA")
	)
	(via
		(at 96.8756 -117.348)
		(size 0.508)
		(drill 0.254)
		(layers "F.Cu" "B.Cu")
		(net "I2C_IOM_SDA")
	)
	(via
		(at 123.3678 -17.907)
		(size 0.508)
		(drill 0.254)
		(layers "F.Cu" "B.Cu")
		(net "I2C_IOM_SDA")
	)
	(via
		(at 98.4758 -132.4864)
		(size 0.508)
		(drill 0.254)
		(layers "F.Cu" "B.Cu")
		(net "I2C_IOM_SDA")
	)
	(via
		(at 202.2094 -98.2218)
		(size 0.508)
		(drill 0.254)
		(layers "F.Cu" "B.Cu")
		(net "I2C_IOM_SDA")
	)
	(via
		(at 42.671746 -121.7168)
		(size 0.6096)
		(drill 0.3048)
		(layers "F.Cu" "B.Cu")
		(net "I2C_IOM_SDA")
	)
	(via
		(at 95.642176 -117.012212)
		(size 0.6604)
		(drill 0.3302)
		(layers "F.Cu" "B.Cu")
		(net "I2C_IOM_SDA")
	)
	(via
		(at 43.9166 -122.961654)
		(size 0.508)
		(drill 0.254)
		(layers "F.Cu" "B.Cu")
		(net "I2C_IOM_SDA")
	)
	(via
		(at 163.213796 -33.488122)
		(size 0.508)
		(drill 0.254)
		(layers "F.Cu" "B.Cu")
		(net "I2C_IOM_SDA")
	)
	(segment
		(start 46.1645 -129.234946)
		(end 45.964856 -129.43459)
		(width 0.127)
		(layer "B.Cu")
		(net "I2C_IOM_SDA")
	)
	(segment
		(start 172.099732 -41.974008)
		(end 172.099732 -68.75653)
		(width 0.127)
		(layer "B.Cu")
		(net "I2C_IOM_SDA")
	)
	(segment
		(start 181.632098 -97.996502)
		(end 181.1528 -98.4758)
		(width 0.127)
		(layer "B.Cu")
		(net "I2C_IOM_SDA")
	)
	(segment
		(start 42.671746 -121.7168)
		(end 41.6814 -120.726454)
		(width 0.127)
		(layer "B.Cu")
		(net "I2C_IOM_SDA")
	)
	(segment
		(start 172.099732 -68.75653)
		(end 177.371502 -74.0283)
		(width 0.127)
		(layer "B.Cu")
		(net "I2C_IOM_SDA")
	)
	(segment
		(start 45.964856 -129.43459)
		(end 45.964856 -130.972814)
		(width 0.127)
		(layer "B.Cu")
		(net "I2C_IOM_SDA")
	)
	(segment
		(start 45.77842 -131.854448)
		(end 45.1358 -132.497068)
		(width 0.127)
		(layer "B.Cu")
		(net "I2C_IOM_SDA")
	)
	(segment
		(start 43.9166 -122.961654)
		(end 42.671746 -121.7168)
		(width 0.127)
		(layer "B.Cu")
		(net "I2C_IOM_SDA")
	)
	(segment
		(start 45.964856 -130.972814)
		(end 45.77842 -131.15925)
		(width 0.127)
		(layer "B.Cu")
		(net "I2C_IOM_SDA")
	)
	(segment
		(start 41.968928 -119.168672)
		(end 42.684954 -119.168672)
		(width 0.127)
		(layer "B.Cu")
		(net "I2C_IOM_SDA")
	)
	(segment
		(start 45.1358 -132.497068)
		(end 45.1358 -133.0833)
		(width 0.127)
		(layer "B.Cu")
		(net "I2C_IOM_SDA")
	)
	(segment
		(start 45.77842 -131.15925)
		(end 45.77842 -131.854448)
		(width 0.127)
		(layer "B.Cu")
		(net "I2C_IOM_SDA")
	)
	(segment
		(start 177.371502 -95.248984)
		(end 179.12588 -97.003362)
		(width 0.127)
		(layer "B.Cu")
		(net "I2C_IOM_SDA")
	)
	(segment
		(start 41.6814 -119.4562)
		(end 41.968928 -119.168672)
		(width 0.127)
		(layer "B.Cu")
		(net "I2C_IOM_SDA")
	)
	(segment
		(start 41.6814 -120.726454)
		(end 41.6814 -119.4562)
		(width 0.127)
		(layer "B.Cu")
		(net "I2C_IOM_SDA")
	)
	(segment
		(start 163.213796 -33.488122)
		(end 163.613846 -33.488122)
		(width 0.127)
		(layer "B.Cu")
		(net "I2C_IOM_SDA")
	)
	(segment
		(start 177.371502 -74.0283)
		(end 177.371502 -95.248984)
		(width 0.127)
		(layer "B.Cu")
		(net "I2C_IOM_SDA")
	)
	(segment
		(start 45.5676 -134.2009)
		(end 44.8564 -134.2009)
		(width 0.127)
		(layer "B.Cu")
		(net "I2C_IOM_SDA")
	)
	(segment
		(start 44.8564 -134.2009)
		(end 44.4373 -133.7818)
		(width 0.127)
		(layer "B.Cu")
		(net "I2C_IOM_SDA")
	)
	(segment
		(start 181.632098 -97.49155)
		(end 181.632098 -97.996502)
		(width 0.127)
		(layer "B.Cu")
		(net "I2C_IOM_SDA")
	)
	(segment
		(start 181.14391 -97.003362)
		(end 181.632098 -97.49155)
		(width 0.127)
		(layer "B.Cu")
		(net "I2C_IOM_SDA")
	)
	(segment
		(start 43.9166 -122.961654)
		(end 43.9166 -124.333)
		(width 0.127)
		(layer "B.Cu")
		(net "I2C_IOM_SDA")
	)
	(segment
		(start 46.1645 -126.5809)
		(end 46.1645 -129.234946)
		(width 0.127)
		(layer "B.Cu")
		(net "I2C_IOM_SDA")
	)
	(segment
		(start 179.12588 -97.003362)
		(end 181.14391 -97.003362)
		(width 0.127)
		(layer "B.Cu")
		(net "I2C_IOM_SDA")
	)
	(segment
		(start 43.9166 -124.333)
		(end 46.1645 -126.5809)
		(width 0.127)
		(layer "B.Cu")
		(net "I2C_IOM_SDA")
	)
	(segment
		(start 163.613846 -33.488122)
		(end 172.099732 -41.974008)
		(width 0.127)
		(layer "B.Cu")
		(net "I2C_IOM_SDA")
	)
	(segment
		(start 45.1358 -133.0833)
		(end 44.4373 -133.7818)
		(width 0.127)
		(layer "B.Cu")
		(net "I2C_IOM_SDA")
	)
	(segment
		(start 126.045468 -5.660898)
		(end 130.063494 -5.660898)
		(width 0.127)
		(layer "In2.Cu")
		(net "I2C_IOM_SDA")
	)
	(segment
		(start 144.931384 -6.506718)
		(end 144.931384 -17.314926)
		(width 0.127)
		(layer "In2.Cu")
		(net "I2C_IOM_SDA")
	)
	(segment
		(start 130.54711 -5.177282)
		(end 143.601948 -5.177282)
		(width 0.127)
		(layer "In2.Cu")
		(net "I2C_IOM_SDA")
	)
	(segment
		(start 97.857818 -125.768354)
		(end 97.857818 -131.868418)
		(width 0.127)
		(layer "In2.Cu")
		(net "I2C_IOM_SDA")
	)
	(segment
		(start 144.931384 -17.314926)
		(end 160.480756 -32.864298)
		(width 0.127)
		(layer "In2.Cu")
		(net "I2C_IOM_SDA")
	)
	(segment
		(start 97.857818 -131.868418)
		(end 98.4758 -132.4864)
		(width 0.127)
		(layer "In2.Cu")
		(net "I2C_IOM_SDA")
	)
	(segment
		(start 97.3582 -117.8306)
		(end 97.3582 -125.268736)
		(width 0.127)
		(layer "In2.Cu")
		(net "I2C_IOM_SDA")
	)
	(segment
		(start 97.3582 -125.268736)
		(end 97.857818 -125.768354)
		(width 0.127)
		(layer "In2.Cu")
		(net "I2C_IOM_SDA")
	)
	(segment
		(start 160.480756 -32.864298)
		(end 162.589972 -32.864298)
		(width 0.127)
		(layer "In2.Cu")
		(net "I2C_IOM_SDA")
	)
	(segment
		(start 143.601948 -5.177282)
		(end 144.931384 -6.506718)
		(width 0.127)
		(layer "In2.Cu")
		(net "I2C_IOM_SDA")
	)
	(segment
		(start 162.589972 -32.864298)
		(end 163.213796 -33.488122)
		(width 0.127)
		(layer "In2.Cu")
		(net "I2C_IOM_SDA")
	)
	(segment
		(start 96.8756 -117.348)
		(end 97.3582 -117.8306)
		(width 0.127)
		(layer "In2.Cu")
		(net "I2C_IOM_SDA")
	)
	(segment
		(start 130.063494 -5.660898)
		(end 130.54711 -5.177282)
		(width 0.127)
		(layer "In2.Cu")
		(net "I2C_IOM_SDA")
	)
	(segment
		(start 124.77496 -13.726414)
		(end 124.77496 -6.931152)
		(width 0.127)
		(layer "In5.Cu")
		(net "I2C_IOM_SDA")
	)
	(segment
		(start 183.191912 -100.6094)
		(end 182.052722 -100.6094)
		(width 0.127)
		(layer "In5.Cu")
		(net "I2C_IOM_SDA")
	)
	(segment
		(start 72.619362 -117.303042)
		(end 65.692782 -117.303042)
		(width 0.127)
		(layer "In5.Cu")
		(net "I2C_IOM_SDA")
	)
	(segment
		(start 96.7486 -117.475)
		(end 96.4946 -117.475)
		(width 0.127)
		(layer "In5.Cu")
		(net "I2C_IOM_SDA")
	)
	(segment
		(start 202.2094 -98.2218)
		(end 200.924414 -99.506786)
		(width 0.127)
		(layer "In5.Cu")
		(net "I2C_IOM_SDA")
	)
	(segment
		(start 181.424834 -99.981512)
		(end 181.424834 -98.747834)
		(width 0.127)
		(layer "In5.Cu")
		(net "I2C_IOM_SDA")
	)
	(segment
		(start 46.280324 -122.961654)
		(end 43.9166 -122.961654)
		(width 0.127)
		(layer "In5.Cu")
		(net "I2C_IOM_SDA")
	)
	(segment
		(start 123.571 -17.7038)
		(end 123.571 -14.930374)
		(width 0.127)
		(layer "In5.Cu")
		(net "I2C_IOM_SDA")
	)
	(segment
		(start 95.5294 -116.5098)
		(end 88.932766 -116.5098)
		(width 0.127)
		(layer "In5.Cu")
		(net "I2C_IOM_SDA")
	)
	(segment
		(start 124.77496 -6.931152)
		(end 125.193044 -6.513068)
		(width 0.127)
		(layer "In5.Cu")
		(net "I2C_IOM_SDA")
	)
	(segment
		(start 125.193044 -6.513068)
		(end 125.193298 -6.513068)
		(width 0.127)
		(layer "In5.Cu")
		(net "I2C_IOM_SDA")
	)
	(segment
		(start 96.8756 -117.348)
		(end 96.7486 -117.475)
		(width 0.127)
		(layer "In5.Cu")
		(net "I2C_IOM_SDA")
	)
	(segment
		(start 52.14747 -118.1862)
		(end 49.89957 -120.4341)
		(width 0.127)
		(layer "In5.Cu")
		(net "I2C_IOM_SDA")
	)
	(segment
		(start 125.193298 -6.513068)
		(end 126.045468 -5.660898)
		(width 0.127)
		(layer "In5.Cu")
		(net "I2C_IOM_SDA")
	)
	(segment
		(start 88.932766 -116.5098)
		(end 85.325966 -112.903)
		(width 0.127)
		(layer "In5.Cu")
		(net "I2C_IOM_SDA")
	)
	(segment
		(start 184.294526 -99.506786)
		(end 183.191912 -100.6094)
		(width 0.127)
		(layer "In5.Cu")
		(net "I2C_IOM_SDA")
	)
	(segment
		(start 65.692782 -117.303042)
		(end 64.809624 -118.1862)
		(width 0.127)
		(layer "In5.Cu")
		(net "I2C_IOM_SDA")
	)
	(segment
		(start 96.4946 -117.475)
		(end 95.5294 -116.5098)
		(width 0.127)
		(layer "In5.Cu")
		(net "I2C_IOM_SDA")
	)
	(segment
		(start 200.924414 -99.506786)
		(end 184.294526 -99.506786)
		(width 0.127)
		(layer "In5.Cu")
		(net "I2C_IOM_SDA")
	)
	(segment
		(start 181.424834 -98.747834)
		(end 181.1528 -98.4758)
		(width 0.127)
		(layer "In5.Cu")
		(net "I2C_IOM_SDA")
	)
	(segment
		(start 48.807878 -120.4341)
		(end 46.280324 -122.961654)
		(width 0.127)
		(layer "In5.Cu")
		(net "I2C_IOM_SDA")
	)
	(segment
		(start 182.052722 -100.6094)
		(end 181.424834 -99.981512)
		(width 0.127)
		(layer "In5.Cu")
		(net "I2C_IOM_SDA")
	)
	(segment
		(start 77.019404 -112.903)
		(end 72.619362 -117.303042)
		(width 0.127)
		(layer "In5.Cu")
		(net "I2C_IOM_SDA")
	)
	(segment
		(start 85.325966 -112.903)
		(end 77.019404 -112.903)
		(width 0.127)
		(layer "In5.Cu")
		(net "I2C_IOM_SDA")
	)
	(segment
		(start 123.3678 -17.907)
		(end 123.571 -17.7038)
		(width 0.127)
		(layer "In5.Cu")
		(net "I2C_IOM_SDA")
	)
	(segment
		(start 64.809624 -118.1862)
		(end 52.14747 -118.1862)
		(width 0.127)
		(layer "In5.Cu")
		(net "I2C_IOM_SDA")
	)
	(segment
		(start 123.571 -14.930374)
		(end 124.77496 -13.726414)
		(width 0.127)
		(layer "In5.Cu")
		(net "I2C_IOM_SDA")
	)
	(segment
		(start 49.89957 -120.4341)
		(end 48.807878 -120.4341)
		(width 0.127)
		(layer "In5.Cu")
		(net "I2C_IOM_SDA")
	)
	(segment
		(start 125.2855 -6.604)
		(end 126.07417 -6.604)
		(width 0.127)
		(layer "F.Cu")
		(net "I2C_IOM_SCL")
	)
	(segment
		(start 203.5048 -98.9965)
		(end 203.5048 -98.2218)
		(width 0.127)
		(layer "F.Cu")
		(net "I2C_IOM_SCL")
	)
	(segment
		(start 110.190534 -18.296636)
		(end 106.485182 -22.001988)
		(width 0.127)
		(layer "F.Cu")
		(net "I2C_IOM_SCL")
	)
	(segment
		(start 103.660702 -22.001988)
		(end 99.059746 -26.602944)
		(width 0.127)
		(layer "F.Cu")
		(net "I2C_IOM_SCL")
	)
	(segment
		(start 123.825 -18.6436)
		(end 122.994928 -19.473672)
		(width 0.127)
		(layer "F.Cu")
		(net "I2C_IOM_SCL")
	)
	(segment
		(start 122.994928 -19.473672)
		(end 117.755162 -19.473672)
		(width 0.127)
		(layer "F.Cu")
		(net "I2C_IOM_SCL")
	)
	(segment
		(start 99.059746 -26.602944)
		(end 99.059746 -48.123348)
		(width 0.127)
		(layer "F.Cu")
		(net "I2C_IOM_SCL")
	)
	(segment
		(start 97.376996 -134.081774)
		(end 96.288352 -134.081774)
		(width 0.127)
		(layer "F.Cu")
		(net "I2C_IOM_SCL")
	)
	(segment
		(start 98.5012 -133.477)
		(end 97.98177 -133.477)
		(width 0.127)
		(layer "F.Cu")
		(net "I2C_IOM_SCL")
	)
	(segment
		(start 106.485182 -22.001988)
		(end 103.660702 -22.001988)
		(width 0.127)
		(layer "F.Cu")
		(net "I2C_IOM_SCL")
	)
	(segment
		(start 182.4482 -99.2505)
		(end 182.4482 -98.4758)
		(width 0.127)
		(layer "F.Cu")
		(net "I2C_IOM_SCL")
	)
	(segment
		(start 117.755162 -19.473672)
		(end 116.578126 -18.296636)
		(width 0.127)
		(layer "F.Cu")
		(net "I2C_IOM_SCL")
	)
	(segment
		(start 99.059746 -48.123348)
		(end 99.2378 -48.301402)
		(width 0.127)
		(layer "F.Cu")
		(net "I2C_IOM_SCL")
	)
	(segment
		(start 97.98177 -133.477)
		(end 97.376996 -134.081774)
		(width 0.127)
		(layer "F.Cu")
		(net "I2C_IOM_SCL")
	)
	(segment
		(start 96.5708 -115.9256)
		(end 96.5708 -116.2812)
		(width 0.127)
		(layer "F.Cu")
		(net "I2C_IOM_SCL")
	)
	(segment
		(start 99.2378 -113.2586)
		(end 96.5708 -115.9256)
		(width 0.127)
		(layer "F.Cu")
		(net "I2C_IOM_SCL")
	)
	(segment
		(start 116.578126 -18.296636)
		(end 110.190534 -18.296636)
		(width 0.127)
		(layer "F.Cu")
		(net "I2C_IOM_SCL")
	)
	(segment
		(start 99.2378 -48.301402)
		(end 99.2378 -113.2586)
		(width 0.127)
		(layer "F.Cu")
		(net "I2C_IOM_SCL")
	)
	(via
		(at 43.7642 -121.5136)
		(size 0.508)
		(drill 0.254)
		(layers "F.Cu" "B.Cu")
		(net "I2C_IOM_SCL")
	)
	(via
		(at 98.5012 -133.477)
		(size 0.508)
		(drill 0.254)
		(layers "F.Cu" "B.Cu")
		(net "I2C_IOM_SCL")
	)
	(via
		(at 45.339 -125.0188)
		(size 0.6096)
		(drill 0.3048)
		(layers "F.Cu" "B.Cu")
		(net "I2C_IOM_SCL")
	)
	(via
		(at 163.321492 -32.477202)
		(size 0.508)
		(drill 0.254)
		(layers "F.Cu" "B.Cu")
		(net "I2C_IOM_SCL")
	)
	(via
		(at 123.825 -18.6436)
		(size 0.508)
		(drill 0.254)
		(layers "F.Cu" "B.Cu")
		(net "I2C_IOM_SCL")
	)
	(via
		(at 126.07417 -6.604)
		(size 0.508)
		(drill 0.254)
		(layers "F.Cu" "B.Cu")
		(net "I2C_IOM_SCL")
	)
	(via
		(at 203.5048 -98.2218)
		(size 0.508)
		(drill 0.254)
		(layers "F.Cu" "B.Cu")
		(net "I2C_IOM_SCL")
	)
	(via
		(at 182.4482 -98.4758)
		(size 0.508)
		(drill 0.254)
		(layers "F.Cu" "B.Cu")
		(net "I2C_IOM_SCL")
	)
	(via
		(at 96.5708 -116.2812)
		(size 0.508)
		(drill 0.254)
		(layers "F.Cu" "B.Cu")
		(net "I2C_IOM_SCL")
	)
	(segment
		(start 44.580556 -124.260356)
		(end 45.339 -125.0188)
		(width 0.127)
		(layer "B.Cu")
		(net "I2C_IOM_SCL")
	)
	(segment
		(start 47.42688 -130.107944)
		(end 47.0408 -129.721864)
		(width 0.127)
		(layer "B.Cu")
		(net "I2C_IOM_SCL")
	)
	(segment
		(start 46.1518 -132.9182)
		(end 46.1518 -133.691884)
		(width 0.127)
		(layer "B.Cu")
		(net "I2C_IOM_SCL")
	)
	(segment
		(start 179.336446 -96.495362)
		(end 181.354476 -96.495362)
		(width 0.127)
		(layer "B.Cu")
		(net "I2C_IOM_SCL")
	)
	(segment
		(start 182.140098 -98.167698)
		(end 182.4482 -98.4758)
		(width 0.127)
		(layer "B.Cu")
		(net "I2C_IOM_SCL")
	)
	(segment
		(start 181.354476 -96.495362)
		(end 182.140098 -97.280984)
		(width 0.127)
		(layer "B.Cu")
		(net "I2C_IOM_SCL")
	)
	(segment
		(start 47.42688 -130.947922)
		(end 47.42688 -130.107944)
		(width 0.127)
		(layer "B.Cu")
		(net "I2C_IOM_SCL")
	)
	(segment
		(start 177.879502 -95.038418)
		(end 179.336446 -96.495362)
		(width 0.127)
		(layer "B.Cu")
		(net "I2C_IOM_SCL")
	)
	(segment
		(start 44.580556 -122.329956)
		(end 44.580556 -124.260356)
		(width 0.127)
		(layer "B.Cu")
		(net "I2C_IOM_SCL")
	)
	(segment
		(start 177.879502 -73.817734)
		(end 177.879502 -95.038418)
		(width 0.127)
		(layer "B.Cu")
		(net "I2C_IOM_SCL")
	)
	(segment
		(start 46.79442 -132.09143)
		(end 46.79442 -131.580382)
		(width 0.127)
		(layer "B.Cu")
		(net "I2C_IOM_SCL")
	)
	(segment
		(start 172.607732 -68.545964)
		(end 177.879502 -73.817734)
		(width 0.127)
		(layer "B.Cu")
		(net "I2C_IOM_SCL")
	)
	(segment
		(start 46.79442 -131.580382)
		(end 47.42688 -130.947922)
		(width 0.127)
		(layer "B.Cu")
		(net "I2C_IOM_SCL")
	)
	(segment
		(start 43.7642 -121.5136)
		(end 44.580556 -122.329956)
		(width 0.127)
		(layer "B.Cu")
		(net "I2C_IOM_SCL")
	)
	(segment
		(start 163.321492 -32.477202)
		(end 172.607732 -41.763442)
		(width 0.127)
		(layer "B.Cu")
		(net "I2C_IOM_SCL")
	)
	(segment
		(start 42.684954 -120.210072)
		(end 42.684954 -120.434354)
		(width 0.127)
		(layer "B.Cu")
		(net "I2C_IOM_SCL")
	)
	(segment
		(start 46.6725 -129.126234)
		(end 46.6725 -126.791466)
		(width 0.127)
		(layer "B.Cu")
		(net "I2C_IOM_SCL")
	)
	(segment
		(start 172.607732 -41.763442)
		(end 172.607732 -68.545964)
		(width 0.127)
		(layer "B.Cu")
		(net "I2C_IOM_SCL")
	)
	(segment
		(start 46.79442 -132.27558)
		(end 46.1518 -132.9182)
		(width 0.127)
		(layer "B.Cu")
		(net "I2C_IOM_SCL")
	)
	(segment
		(start 45.339 -125.036834)
		(end 45.339 -125.0188)
		(width 0.127)
		(layer "B.Cu")
		(net "I2C_IOM_SCL")
	)
	(segment
		(start 42.684954 -120.434354)
		(end 43.7642 -121.5136)
		(width 0.127)
		(layer "B.Cu")
		(net "I2C_IOM_SCL")
	)
	(segment
		(start 46.79442 -132.09143)
		(end 46.79442 -132.27558)
		(width 0.127)
		(layer "B.Cu")
		(net "I2C_IOM_SCL")
	)
	(segment
		(start 182.140098 -97.280984)
		(end 182.140098 -98.167698)
		(width 0.127)
		(layer "B.Cu")
		(net "I2C_IOM_SCL")
	)
	(segment
		(start 46.1518 -133.691884)
		(end 46.65218 -134.192264)
		(width 0.127)
		(layer "B.Cu")
		(net "I2C_IOM_SCL")
	)
	(segment
		(start 47.0408 -129.721864)
		(end 47.0408 -129.494534)
		(width 0.127)
		(layer "B.Cu")
		(net "I2C_IOM_SCL")
	)
	(segment
		(start 47.0408 -129.494534)
		(end 46.6725 -129.126234)
		(width 0.127)
		(layer "B.Cu")
		(net "I2C_IOM_SCL")
	)
	(segment
		(start 46.6725 -126.791466)
		(end 46.672754 -126.791212)
		(width 0.127)
		(layer "B.Cu")
		(net "I2C_IOM_SCL")
	)
	(segment
		(start 46.672754 -126.791212)
		(end 46.672754 -126.370588)
		(width 0.127)
		(layer "B.Cu")
		(net "I2C_IOM_SCL")
	)
	(segment
		(start 46.672754 -126.370588)
		(end 45.339 -125.036834)
		(width 0.127)
		(layer "B.Cu")
		(net "I2C_IOM_SCL")
	)
	(segment
		(start 125.537468 -5.40893)
		(end 125.537468 -6.067298)
		(width 0.127)
		(layer "In2.Cu")
		(net "I2C_IOM_SCL")
	)
	(segment
		(start 145.439384 -17.10436)
		(end 145.439384 -6.460744)
		(width 0.127)
		(layer "In2.Cu")
		(net "I2C_IOM_SCL")
	)
	(segment
		(start 97.349818 -132.325618)
		(end 98.5012 -133.477)
		(width 0.127)
		(layer "In2.Cu")
		(net "I2C_IOM_SCL")
	)
	(segment
		(start 96.374204 -119.412004)
		(end 96.8502 -119.888)
		(width 0.127)
		(layer "In2.Cu")
		(net "I2C_IOM_SCL")
	)
	(segment
		(start 143.812514 -4.669282)
		(end 130.336544 -4.669282)
		(width 0.127)
		(layer "In2.Cu")
		(net "I2C_IOM_SCL")
	)
	(segment
		(start 129.852928 -5.152898)
		(end 125.7935 -5.152898)
		(width 0.127)
		(layer "In2.Cu")
		(net "I2C_IOM_SCL")
	)
	(segment
		(start 97.349818 -125.97892)
		(end 97.349818 -132.325618)
		(width 0.127)
		(layer "In2.Cu")
		(net "I2C_IOM_SCL")
	)
	(segment
		(start 96.8502 -119.888)
		(end 96.8502 -125.479302)
		(width 0.127)
		(layer "In2.Cu")
		(net "I2C_IOM_SCL")
	)
	(segment
		(start 145.439638 -6.46049)
		(end 145.439638 -6.296406)
		(width 0.127)
		(layer "In2.Cu")
		(net "I2C_IOM_SCL")
	)
	(segment
		(start 145.439384 -6.460744)
		(end 145.439638 -6.46049)
		(width 0.127)
		(layer "In2.Cu")
		(net "I2C_IOM_SCL")
	)
	(segment
		(start 163.091622 -32.247332)
		(end 160.582356 -32.247332)
		(width 0.127)
		(layer "In2.Cu")
		(net "I2C_IOM_SCL")
	)
	(segment
		(start 125.537468 -6.067298)
		(end 126.07417 -6.604)
		(width 0.127)
		(layer "In2.Cu")
		(net "I2C_IOM_SCL")
	)
	(segment
		(start 145.439638 -6.296406)
		(end 143.812514 -4.669282)
		(width 0.127)
		(layer "In2.Cu")
		(net "I2C_IOM_SCL")
	)
	(segment
		(start 163.321492 -32.477202)
		(end 163.091622 -32.247332)
		(width 0.127)
		(layer "In2.Cu")
		(net "I2C_IOM_SCL")
	)
	(segment
		(start 160.582356 -32.247332)
		(end 145.439384 -17.10436)
		(width 0.127)
		(layer "In2.Cu")
		(net "I2C_IOM_SCL")
	)
	(segment
		(start 96.374204 -116.477796)
		(end 96.374204 -119.412004)
		(width 0.127)
		(layer "In2.Cu")
		(net "I2C_IOM_SCL")
	)
	(segment
		(start 96.8502 -125.479302)
		(end 97.349818 -125.97892)
		(width 0.127)
		(layer "In2.Cu")
		(net "I2C_IOM_SCL")
	)
	(segment
		(start 130.336544 -4.669282)
		(end 129.852928 -5.152898)
		(width 0.127)
		(layer "In2.Cu")
		(net "I2C_IOM_SCL")
	)
	(segment
		(start 96.5708 -116.2812)
		(end 96.374204 -116.477796)
		(width 0.127)
		(layer "In2.Cu")
		(net "I2C_IOM_SCL")
	)
	(segment
		(start 125.7935 -5.152898)
		(end 125.537468 -5.40893)
		(width 0.127)
		(layer "In2.Cu")
		(net "I2C_IOM_SCL")
	)
	(segment
		(start 125.28296 -13.93698)
		(end 125.28296 -7.141718)
		(width 0.127)
		(layer "In5.Cu")
		(net "I2C_IOM_SCL")
	)
	(segment
		(start 68.8467 -116.1161)
		(end 68.167758 -116.795042)
		(width 0.127)
		(layer "In5.Cu")
		(net "I2C_IOM_SCL")
	)
	(segment
		(start 58.6232 -117.6782)
		(end 57.7088 -116.7638)
		(width 0.127)
		(layer "In5.Cu")
		(net "I2C_IOM_SCL")
	)
	(segment
		(start 54.6481 -116.7638)
		(end 54.337204 -116.452904)
		(width 0.127)
		(layer "In5.Cu")
		(net "I2C_IOM_SCL")
	)
	(segment
		(start 182.514748 -100.0506)
		(end 182.214774 -99.750626)
		(width 0.127)
		(layer "In5.Cu")
		(net "I2C_IOM_SCL")
	)
	(segment
		(start 96.2914 -116.0018)
		(end 89.143332 -116.0018)
		(width 0.127)
		(layer "In5.Cu")
		(net "I2C_IOM_SCL")
	)
	(segment
		(start 54.337204 -116.452904)
		(end 53.947568 -116.452904)
		(width 0.127)
		(layer "In5.Cu")
		(net "I2C_IOM_SCL")
	)
	(segment
		(start 85.536532 -112.395)
		(end 76.808838 -112.395)
		(width 0.127)
		(layer "In5.Cu")
		(net "I2C_IOM_SCL")
	)
	(segment
		(start 125.403864 -7.021068)
		(end 125.820932 -6.604)
		(width 0.127)
		(layer "In5.Cu")
		(net "I2C_IOM_SCL")
	)
	(segment
		(start 47.009812 -121.5136)
		(end 43.7642 -121.5136)
		(width 0.127)
		(layer "In5.Cu")
		(net "I2C_IOM_SCL")
	)
	(segment
		(start 53.636672 -116.7638)
		(end 51.759612 -116.7638)
		(width 0.127)
		(layer "In5.Cu")
		(net "I2C_IOM_SCL")
	)
	(segment
		(start 183.032146 -100.0506)
		(end 182.514748 -100.0506)
		(width 0.127)
		(layer "In5.Cu")
		(net "I2C_IOM_SCL")
	)
	(segment
		(start 65.482216 -116.795042)
		(end 64.599058 -117.6782)
		(width 0.127)
		(layer "In5.Cu")
		(net "I2C_IOM_SCL")
	)
	(segment
		(start 184.08396 -98.998786)
		(end 183.032146 -100.0506)
		(width 0.127)
		(layer "In5.Cu")
		(net "I2C_IOM_SCL")
	)
	(segment
		(start 124.079 -15.14094)
		(end 125.28296 -13.93698)
		(width 0.127)
		(layer "In5.Cu")
		(net "I2C_IOM_SCL")
	)
	(segment
		(start 200.174606 -98.998786)
		(end 184.08396 -98.998786)
		(width 0.127)
		(layer "In5.Cu")
		(net "I2C_IOM_SCL")
	)
	(segment
		(start 123.825 -18.6436)
		(end 124.079 -18.3896)
		(width 0.127)
		(layer "In5.Cu")
		(net "I2C_IOM_SCL")
	)
	(segment
		(start 89.143332 -116.0018)
		(end 85.536532 -112.395)
		(width 0.127)
		(layer "In5.Cu")
		(net "I2C_IOM_SCL")
	)
	(segment
		(start 51.759612 -116.7638)
		(end 47.009812 -121.5136)
		(width 0.127)
		(layer "In5.Cu")
		(net "I2C_IOM_SCL")
	)
	(segment
		(start 124.079 -18.3896)
		(end 124.079 -15.14094)
		(width 0.127)
		(layer "In5.Cu")
		(net "I2C_IOM_SCL")
	)
	(segment
		(start 182.214774 -98.709226)
		(end 182.4482 -98.4758)
		(width 0.127)
		(layer "In5.Cu")
		(net "I2C_IOM_SCL")
	)
	(segment
		(start 76.808838 -112.395)
		(end 73.087738 -116.1161)
		(width 0.127)
		(layer "In5.Cu")
		(net "I2C_IOM_SCL")
	)
	(segment
		(start 64.599058 -117.6782)
		(end 58.6232 -117.6782)
		(width 0.127)
		(layer "In5.Cu")
		(net "I2C_IOM_SCL")
	)
	(segment
		(start 53.947568 -116.452904)
		(end 53.636672 -116.7638)
		(width 0.127)
		(layer "In5.Cu")
		(net "I2C_IOM_SCL")
	)
	(segment
		(start 57.7088 -116.7638)
		(end 54.6481 -116.7638)
		(width 0.127)
		(layer "In5.Cu")
		(net "I2C_IOM_SCL")
	)
	(segment
		(start 125.28296 -7.141718)
		(end 125.40361 -7.021068)
		(width 0.127)
		(layer "In5.Cu")
		(net "I2C_IOM_SCL")
	)
	(segment
		(start 96.5708 -116.2812)
		(end 96.2914 -116.0018)
		(width 0.127)
		(layer "In5.Cu")
		(net "I2C_IOM_SCL")
	)
	(segment
		(start 125.40361 -7.021068)
		(end 125.403864 -7.021068)
		(width 0.127)
		(layer "In5.Cu")
		(net "I2C_IOM_SCL")
	)
	(segment
		(start 73.087738 -116.1161)
		(end 68.8467 -116.1161)
		(width 0.127)
		(layer "In5.Cu")
		(net "I2C_IOM_SCL")
	)
	(segment
		(start 203.0222 -97.7392)
		(end 201.434192 -97.7392)
		(width 0.127)
		(layer "In5.Cu")
		(net "I2C_IOM_SCL")
	)
	(segment
		(start 203.5048 -98.2218)
		(end 203.0222 -97.7392)
		(width 0.127)
		(layer "In5.Cu")
		(net "I2C_IOM_SCL")
	)
	(segment
		(start 201.434192 -97.7392)
		(end 200.174606 -98.998786)
		(width 0.127)
		(layer "In5.Cu")
		(net "I2C_IOM_SCL")
	)
	(segment
		(start 182.214774 -99.750626)
		(end 182.214774 -98.709226)
		(width 0.127)
		(layer "In5.Cu")
		(net "I2C_IOM_SCL")
	)
	(segment
		(start 68.167758 -116.795042)
		(end 65.482216 -116.795042)
		(width 0.127)
		(layer "In5.Cu")
		(net "I2C_IOM_SCL")
	)
	(segment
		(start 125.820932 -6.604)
		(end 126.07417 -6.604)
		(width 0.127)
		(layer "In5.Cu")
		(net "I2C_IOM_SCL")
	)
	(segment
		(start 122.263662 -4.598416)
		(end 122.92965 -4.598416)
		(width 0.127)
		(layer "F.Cu")
		(net "HSW_SDA")
	)
	(segment
		(start 120.121934 -5.606542)
		(end 121.13006 -4.598416)
		(width 0.127)
		(layer "F.Cu")
		(net "HSW_SDA")
	)
	(segment
		(start 121.13006 -4.598416)
		(end 122.263662 -4.598416)
		(width 0.127)
		(layer "F.Cu")
		(net "HSW_SDA")
	)
	(segment
		(start 120.121934 -6.5151)
		(end 120.121934 -5.606542)
		(width 0.127)
		(layer "F.Cu")
		(net "HSW_SDA")
	)
	(segment
		(start 123.868434 -5.5372)
		(end 124.3711 -5.5372)
		(width 0.127)
		(layer "F.Cu")
		(net "HSW_SDA")
	)
	(segment
		(start 122.92965 -4.598416)
		(end 123.868434 -5.5372)
		(width 0.127)
		(layer "F.Cu")
		(net "HSW_SDA")
	)
	(via
		(at 122.263662 -4.598416)
		(size 0.6604)
		(drill 0.3302)
		(layers "F.Cu" "B.Cu")
		(net "HSW_SDA")
	)
	(segment
		(start 123.275598 -5.727192)
		(end 124.152406 -6.604)
		(width 0.127)
		(layer "F.Cu")
		(net "HSW_SCL")
	)
	(segment
		(start 123.066302 -5.727192)
		(end 122.371866 -5.727192)
		(width 0.127)
		(layer "F.Cu")
		(net "HSW_SCL")
	)
	(segment
		(start 124.152406 -6.604)
		(end 124.3965 -6.604)
		(width 0.127)
		(layer "F.Cu")
		(net "HSW_SCL")
	)
	(segment
		(start 123.066302 -5.727192)
		(end 123.275598 -5.727192)
		(width 0.127)
		(layer "F.Cu")
		(net "HSW_SCL")
	)
	(segment
		(start 122.371866 -5.727192)
		(end 121.660158 -6.4389)
		(width 0.127)
		(layer "F.Cu")
		(net "HSW_SCL")
	)
	(segment
		(start 121.660158 -6.4389)
		(end 120.62206 -6.4389)
		(width 0.127)
		(layer "F.Cu")
		(net "HSW_SCL")
	)
	(via
		(at 123.066302 -5.727192)
		(size 0.6604)
		(drill 0.3302)
		(layers "F.Cu" "B.Cu")
		(net "HSW_SCL")
	)
	(segment
		(start 67.948556 -138.18489)
		(end 67.948556 -139.137644)
		(width 0.127)
		(layer "F.Cu")
		(net "FP_RETBTN")
	)
	(segment
		(start 67.948556 -139.137644)
		(end 67.7418 -139.3444)
		(width 0.127)
		(layer "F.Cu")
		(net "FP_RETBTN")
	)
	(segment
		(start 68.5038 -140.4874)
		(end 68.794884 -140.196316)
		(width 0.127)
		(layer "F.Cu")
		(net "FP_RETBTN")
	)
	(segment
		(start 67.7418 -139.3444)
		(end 67.7418 -140.2969)
		(width 0.127)
		(layer "F.Cu")
		(net "FP_RETBTN")
	)
	(segment
		(start 67.9323 -140.4874)
		(end 68.5038 -140.4874)
		(width 0.127)
		(layer "F.Cu")
		(net "FP_RETBTN")
	)
	(segment
		(start 68.794884 -140.196316)
		(end 69.65823 -140.196316)
		(width 0.127)
		(layer "F.Cu")
		(net "FP_RETBTN")
	)
	(segment
		(start 67.7418 -140.2969)
		(end 67.9323 -140.4874)
		(width 0.127)
		(layer "F.Cu")
		(net "FP_RETBTN")
	)
	(via
		(at 67.7418 -139.3444)
		(size 0.6604)
		(drill 0.3302)
		(layers "F.Cu" "B.Cu")
		(net "FP_RETBTN")
	)
	(segment
		(start 73.257664 -141.151864)
		(end 73.376282 -141.033246)
		(width 0.127)
		(layer "F.Cu")
		(net "FP_RESET_RC_N")
	)
	(segment
		(start 71.53783 -140.196316)
		(end 71.838566 -140.196316)
		(width 0.127)
		(layer "F.Cu")
		(net "FP_RESET_RC_N")
	)
	(segment
		(start 72.794114 -141.151864)
		(end 73.257664 -141.151864)
		(width 0.127)
		(layer "F.Cu")
		(net "FP_RESET_RC_N")
	)
	(segment
		(start 73.5457 -140.0302)
		(end 73.5457 -140.863828)
		(width 0.127)
		(layer "F.Cu")
		(net "FP_RESET_RC_N")
	)
	(segment
		(start 73.5457 -140.863828)
		(end 73.376282 -141.033246)
		(width 0.127)
		(layer "F.Cu")
		(net "FP_RESET_RC_N")
	)
	(segment
		(start 71.838566 -140.196316)
		(end 72.794114 -141.151864)
		(width 0.127)
		(layer "F.Cu")
		(net "FP_RESET_RC_N")
	)
	(via
		(at 73.376282 -141.033246)
		(size 0.6604)
		(drill 0.3302)
		(layers "F.Cu" "B.Cu")
		(net "FP_RESET_RC_N")
	)
	(segment
		(start 68.1609 -124.333)
		(end 67.267836 -124.333)
		(width 0.127)
		(layer "F.Cu")
		(net "FLA_CS_1_R")
	)
	(segment
		(start 67.267836 -124.333)
		(end 67.064636 -124.5362)
		(width 0.127)
		(layer "F.Cu")
		(net "FLA_CS_1_R")
	)
	(segment
		(start 69.215 -125.3871)
		(end 68.1609 -124.333)
		(width 0.127)
		(layer "F.Cu")
		(net "FLA_CS_1_R")
	)
	(segment
		(start 67.064636 -124.5362)
		(end 65.806066 -124.5362)
		(width 0.127)
		(layer "F.Cu")
		(net "FLA_CS_1_R")
	)
	(segment
		(start 69.215 -128.438402)
		(end 69.215 -125.3871)
		(width 0.127)
		(layer "F.Cu")
		(net "FLA_CS_1_R")
	)
	(segment
		(start 68.3514 -129.302002)
		(end 69.215 -128.438402)
		(width 0.127)
		(layer "F.Cu")
		(net "FLA_CS_1_R")
	)
	(via
		(at 39.2176 -135.509)
		(size 0.508)
		(drill 0.254)
		(layers "F.Cu" "B.Cu")
		(net "FLA_CS_1_R")
	)
	(via
		(at 68.3514 -129.302002)
		(size 0.508)
		(drill 0.254)
		(layers "F.Cu" "B.Cu")
		(net "FLA_CS_1_R")
	)
	(segment
		(start 38.4175 -133.7691)
		(end 39.2176 -134.5692)
		(width 0.127)
		(layer "B.Cu")
		(net "FLA_CS_1_R")
	)
	(segment
		(start 39.2176 -134.5692)
		(end 39.2176 -135.509)
		(width 0.127)
		(layer "B.Cu")
		(net "FLA_CS_1_R")
	)
	(segment
		(start 37.2618 -133.7691)
		(end 38.4175 -133.7691)
		(width 0.127)
		(layer "B.Cu")
		(net "FLA_CS_1_R")
	)
	(segment
		(start 55.0164 -132.8928)
		(end 58.928 -128.9812)
		(width 0.127)
		(layer "In5.Cu")
		(net "FLA_CS_1_R")
	)
	(segment
		(start 58.928 -128.9812)
		(end 63.342266 -128.9812)
		(width 0.127)
		(layer "In5.Cu")
		(net "FLA_CS_1_R")
	)
	(segment
		(start 39.2176 -134.874)
		(end 39.9542 -134.1374)
		(width 0.127)
		(layer "In5.Cu")
		(net "FLA_CS_1_R")
	)
	(segment
		(start 51.0286 -132.8928)
		(end 55.0164 -132.8928)
		(width 0.127)
		(layer "In5.Cu")
		(net "FLA_CS_1_R")
	)
	(segment
		(start 63.342266 -128.9812)
		(end 63.663068 -129.302002)
		(width 0.127)
		(layer "In5.Cu")
		(net "FLA_CS_1_R")
	)
	(segment
		(start 39.9542 -134.1374)
		(end 49.784 -134.1374)
		(width 0.127)
		(layer "In5.Cu")
		(net "FLA_CS_1_R")
	)
	(segment
		(start 39.2176 -135.509)
		(end 39.2176 -134.874)
		(width 0.127)
		(layer "In5.Cu")
		(net "FLA_CS_1_R")
	)
	(segment
		(start 63.663068 -129.302002)
		(end 68.3514 -129.302002)
		(width 0.127)
		(layer "In5.Cu")
		(net "FLA_CS_1_R")
	)
	(segment
		(start 49.784 -134.1374)
		(end 51.0286 -132.8928)
		(width 0.127)
		(layer "In5.Cu")
		(net "FLA_CS_1_R")
	)
	(segment
		(start 39.700454 -138.600434)
		(end 40.099996 -138.999976)
		(width 0.127)
		(layer "F.Cu")
		(net "FLA_CS_1")
	)
	(segment
		(start 39.699946 -138.600434)
		(end 39.700454 -138.600434)
		(width 0.127)
		(layer "F.Cu")
		(net "FLA_CS_1")
	)
	(via
		(at 39.699946 -138.600434)
		(size 0.4572)
		(drill 0.2032)
		(layers "F.Cu" "B.Cu")
		(net "FLA_CS_1")
	)
	(segment
		(start 37.2618 -135.221218)
		(end 37.2618 -134.6581)
		(width 0.127)
		(layer "B.Cu")
		(net "FLA_CS_1")
	)
	(segment
		(start 36.923218 -135.5598)
		(end 37.2618 -135.221218)
		(width 0.127)
		(layer "B.Cu")
		(net "FLA_CS_1")
	)
	(segment
		(start 38.04285 -138.670538)
		(end 36.923218 -137.550906)
		(width 0.127)
		(layer "B.Cu")
		(net "FLA_CS_1")
	)
	(segment
		(start 39.629842 -138.670538)
		(end 38.04285 -138.670538)
		(width 0.127)
		(layer "B.Cu")
		(net "FLA_CS_1")
	)
	(segment
		(start 39.699946 -138.600434)
		(end 39.629842 -138.670538)
		(width 0.127)
		(layer "B.Cu")
		(net "FLA_CS_1")
	)
	(segment
		(start 36.923218 -137.550906)
		(end 36.923218 -135.5598)
		(width 0.127)
		(layer "B.Cu")
		(net "FLA_CS_1")
	)
	(segment
		(start 34.7599 -134.5438)
		(end 34.29 -134.5438)
		(width 0.127)
		(layer "F.Cu")
		(net "FLA_CS_0_R")
	)
	(segment
		(start 38.76802 -125.070108)
		(end 36.648898 -125.070108)
		(width 0.127)
		(layer "F.Cu")
		(net "FLA_CS_0_R")
	)
	(segment
		(start 36.648898 -125.070108)
		(end 35.68446 -124.10567)
		(width 0.127)
		(layer "F.Cu")
		(net "FLA_CS_0_R")
	)
	(segment
		(start 41.00576 -124.5362)
		(end 39.301928 -124.5362)
		(width 0.127)
		(layer "F.Cu")
		(net "FLA_CS_0_R")
	)
	(segment
		(start 34.29 -134.5438)
		(end 33.9852 -134.239)
		(width 0.127)
		(layer "F.Cu")
		(net "FLA_CS_0_R")
	)
	(segment
		(start 39.301928 -124.5362)
		(end 38.76802 -125.070108)
		(width 0.127)
		(layer "F.Cu")
		(net "FLA_CS_0_R")
	)
	(via
		(at 35.68446 -124.10567)
		(size 0.508)
		(drill 0.254)
		(layers "F.Cu" "B.Cu")
		(net "FLA_CS_0_R")
	)
	(via
		(at 33.9852 -134.239)
		(size 0.508)
		(drill 0.254)
		(layers "F.Cu" "B.Cu")
		(net "FLA_CS_0_R")
	)
	(segment
		(start 34.7853 -121.8438)
		(end 34.7853 -122.9106)
		(width 0.127)
		(layer "B.Cu")
		(net "FLA_CS_0_R")
	)
	(segment
		(start 34.7853 -123.20651)
		(end 35.68446 -124.10567)
		(width 0.127)
		(layer "B.Cu")
		(net "FLA_CS_0_R")
	)
	(segment
		(start 34.7853 -122.9106)
		(end 34.7853 -123.20651)
		(width 0.127)
		(layer "B.Cu")
		(net "FLA_CS_0_R")
	)
	(segment
		(start 30.015942 -127.324358)
		(end 29.671518 -127.668782)
		(width 0.127)
		(layer "In2.Cu")
		(net "FLA_CS_0_R")
	)
	(segment
		(start 29.671518 -127.668782)
		(end 29.671518 -133.656832)
		(width 0.127)
		(layer "In2.Cu")
		(net "FLA_CS_0_R")
	)
	(segment
		(start 30.129734 -134.115048)
		(end 33.861248 -134.115048)
		(width 0.127)
		(layer "In2.Cu")
		(net "FLA_CS_0_R")
	)
	(segment
		(start 35.68446 -124.10567)
		(end 35.68446 -126.181104)
		(width 0.127)
		(layer "In2.Cu")
		(net "FLA_CS_0_R")
	)
	(segment
		(start 29.671518 -133.656832)
		(end 30.129734 -134.115048)
		(width 0.127)
		(layer "In2.Cu")
		(net "FLA_CS_0_R")
	)
	(segment
		(start 33.861248 -134.115048)
		(end 33.9852 -134.239)
		(width 0.127)
		(layer "In2.Cu")
		(net "FLA_CS_0_R")
	)
	(segment
		(start 34.541206 -127.324358)
		(end 30.015942 -127.324358)
		(width 0.127)
		(layer "In2.Cu")
		(net "FLA_CS_0_R")
	)
	(segment
		(start 35.68446 -126.181104)
		(end 34.541206 -127.324358)
		(width 0.127)
		(layer "In2.Cu")
		(net "FLA_CS_0_R")
	)
	(segment
		(start 36.5506 -135.4455)
		(end 35.6489 -134.5438)
		(width 0.127)
		(layer "F.Cu")
		(net "FLA_CS_0")
	)
	(segment
		(start 39.299896 -138.999976)
		(end 38.649148 -138.999976)
		(width 0.127)
		(layer "F.Cu")
		(net "FLA_CS_0")
	)
	(segment
		(start 36.5506 -136.901428)
		(end 36.5506 -135.4455)
		(width 0.127)
		(layer "F.Cu")
		(net "FLA_CS_0")
	)
	(segment
		(start 38.649148 -138.999976)
		(end 36.5506 -136.901428)
		(width 0.127)
		(layer "F.Cu")
		(net "FLA_CS_0")
	)
	(segment
		(start 53.699918 -138.199876)
		(end 53.699918 -138.199622)
		(width 0.127)
		(layer "F.Cu")
		(net "COMP_PWR_BTN_R_N")
	)
	(segment
		(start 53.699918 -138.199622)
		(end 54.099714 -137.799826)
		(width 0.127)
		(layer "F.Cu")
		(net "COMP_PWR_BTN_R_N")
	)
	(via
		(at 54.099714 -137.799826)
		(size 0.4572)
		(drill 0.2032)
		(layers "F.Cu" "B.Cu")
		(net "COMP_PWR_BTN_R_N")
	)
	(via
		(at 54.41569 -136.956292)
		(size 0.6096)
		(drill 0.3048)
		(layers "F.Cu" "B.Cu")
		(net "COMP_PWR_BTN_R_N")
	)
	(segment
		(start 54.099714 -137.272268)
		(end 54.41569 -136.956292)
		(width 0.127)
		(layer "B.Cu")
		(net "COMP_PWR_BTN_R_N")
	)
	(segment
		(start 54.099714 -137.799826)
		(end 54.099714 -137.272268)
		(width 0.127)
		(layer "B.Cu")
		(net "COMP_PWR_BTN_R_N")
	)
	(segment
		(start 54.592982 -136.779)
		(end 55.015384 -136.779)
		(width 0.127)
		(layer "B.Cu")
		(net "COMP_PWR_BTN_R_N")
	)
	(segment
		(start 54.41569 -136.956292)
		(end 54.592982 -136.779)
		(width 0.127)
		(layer "B.Cu")
		(net "COMP_PWR_BTN_R_N")
	)
	(segment
		(start 55.015384 -136.779)
		(end 55.746142 -136.048242)
		(width 0.127)
		(layer "B.Cu")
		(net "COMP_PWR_BTN_R_N")
	)
	(segment
		(start 110.5662 -27.095196)
		(end 110.5662 -29.8196)
		(width 0.127)
		(layer "F.Cu")
		(net "COMP_PWR_BTN_N")
	)
	(segment
		(start 109.390942 -26.340562)
		(end 109.811566 -26.340562)
		(width 0.127)
		(layer "F.Cu")
		(net "COMP_PWR_BTN_N")
	)
	(segment
		(start 98.6282 -121.5898)
		(end 99.43592 -120.78208)
		(width 0.127)
		(layer "F.Cu")
		(net "COMP_PWR_BTN_N")
	)
	(segment
		(start 109.811566 -26.340562)
		(end 110.5662 -27.095196)
		(width 0.127)
		(layer "F.Cu")
		(net "COMP_PWR_BTN_N")
	)
	(segment
		(start 109.390688 -26.340816)
		(end 109.390942 -26.340562)
		(width 0.127)
		(layer "F.Cu")
		(net "COMP_PWR_BTN_N")
	)
	(segment
		(start 101.2698 -46.682406)
		(end 103.759762 -44.192444)
		(width 0.127)
		(layer "F.Cu")
		(net "COMP_PWR_BTN_N")
	)
	(segment
		(start 101.2698 -114.506502)
		(end 101.2698 -46.682406)
		(width 0.127)
		(layer "F.Cu")
		(net "COMP_PWR_BTN_N")
	)
	(segment
		(start 104.992932 -26.340816)
		(end 109.390688 -26.340816)
		(width 0.127)
		(layer "F.Cu")
		(net "COMP_PWR_BTN_N")
	)
	(segment
		(start 99.43592 -120.78208)
		(end 99.43592 -116.340382)
		(width 0.127)
		(layer "F.Cu")
		(net "COMP_PWR_BTN_N")
	)
	(segment
		(start 103.759762 -44.192444)
		(end 103.759762 -27.573986)
		(width 0.127)
		(layer "F.Cu")
		(net "COMP_PWR_BTN_N")
	)
	(segment
		(start 99.225354 -126.746)
		(end 99.7712 -126.200154)
		(width 0.127)
		(layer "F.Cu")
		(net "COMP_PWR_BTN_N")
	)
	(segment
		(start 110.5662 -29.8196)
		(end 111.271558 -30.524958)
		(width 0.127)
		(layer "F.Cu")
		(net "COMP_PWR_BTN_N")
	)
	(segment
		(start 111.271558 -39.82847)
		(end 110.700058 -40.39997)
		(width 0.127)
		(layer "F.Cu")
		(net "COMP_PWR_BTN_N")
	)
	(segment
		(start 99.7712 -126.200154)
		(end 99.7712 -124.9426)
		(width 0.127)
		(layer "F.Cu")
		(net "COMP_PWR_BTN_N")
	)
	(segment
		(start 99.43592 -116.340382)
		(end 101.2698 -114.506502)
		(width 0.127)
		(layer "F.Cu")
		(net "COMP_PWR_BTN_N")
	)
	(segment
		(start 99.7712 -124.9426)
		(end 99.7712 -124.841)
		(width 0.127)
		(layer "F.Cu")
		(net "COMP_PWR_BTN_N")
	)
	(segment
		(start 103.759762 -27.573986)
		(end 104.992932 -26.340816)
		(width 0.127)
		(layer "F.Cu")
		(net "COMP_PWR_BTN_N")
	)
	(segment
		(start 98.6282 -123.698)
		(end 98.6282 -121.5898)
		(width 0.127)
		(layer "F.Cu")
		(net "COMP_PWR_BTN_N")
	)
	(segment
		(start 99.7712 -124.841)
		(end 98.6282 -123.698)
		(width 0.127)
		(layer "F.Cu")
		(net "COMP_PWR_BTN_N")
	)
	(segment
		(start 111.271558 -30.524958)
		(end 111.271558 -39.82847)
		(width 0.127)
		(layer "F.Cu")
		(net "COMP_PWR_BTN_N")
	)
	(via
		(at 99.225354 -126.746)
		(size 0.508)
		(drill 0.254)
		(layers "F.Cu" "B.Cu")
		(net "COMP_PWR_BTN_N")
	)
	(via
		(at 63.108586 -133.068568)
		(size 0.508)
		(drill 0.254)
		(layers "F.Cu" "B.Cu")
		(net "COMP_PWR_BTN_N")
	)
	(via
		(at 99.7712 -124.9426)
		(size 0.6604)
		(drill 0.3302)
		(layers "F.Cu" "B.Cu")
		(net "COMP_PWR_BTN_N")
	)
	(segment
		(start 57.878218 -133.9215)
		(end 58.348118 -133.4516)
		(width 0.127)
		(layer "B.Cu")
		(net "COMP_PWR_BTN_N")
	)
	(segment
		(start 56.8325 -133.9215)
		(end 57.878218 -133.9215)
		(width 0.127)
		(layer "B.Cu")
		(net "COMP_PWR_BTN_N")
	)
	(segment
		(start 58.348118 -133.4516)
		(end 61.5442 -133.4516)
		(width 0.127)
		(layer "B.Cu")
		(net "COMP_PWR_BTN_N")
	)
	(segment
		(start 55.753762 -134.134352)
		(end 56.619648 -134.134352)
		(width 0.127)
		(layer "B.Cu")
		(net "COMP_PWR_BTN_N")
	)
	(segment
		(start 55.753762 -135.151622)
		(end 55.746142 -135.159242)
		(width 0.127)
		(layer "B.Cu")
		(net "COMP_PWR_BTN_N")
	)
	(segment
		(start 61.927232 -133.068568)
		(end 63.108586 -133.068568)
		(width 0.127)
		(layer "B.Cu")
		(net "COMP_PWR_BTN_N")
	)
	(segment
		(start 55.753762 -134.134352)
		(end 55.753762 -135.151622)
		(width 0.127)
		(layer "B.Cu")
		(net "COMP_PWR_BTN_N")
	)
	(segment
		(start 56.619648 -134.134352)
		(end 56.8325 -133.9215)
		(width 0.127)
		(layer "B.Cu")
		(net "COMP_PWR_BTN_N")
	)
	(segment
		(start 61.5442 -133.4516)
		(end 61.927232 -133.068568)
		(width 0.127)
		(layer "B.Cu")
		(net "COMP_PWR_BTN_N")
	)
	(segment
		(start 81.497678 -133.451346)
		(end 81.065624 -133.8834)
		(width 0.127)
		(layer "In5.Cu")
		(net "COMP_PWR_BTN_N")
	)
	(segment
		(start 63.741554 -132.4356)
		(end 63.108586 -133.068568)
		(width 0.127)
		(layer "In5.Cu")
		(net "COMP_PWR_BTN_N")
	)
	(segment
		(start 91.077542 -131.699)
		(end 88.533224 -131.699)
		(width 0.127)
		(layer "In5.Cu")
		(net "COMP_PWR_BTN_N")
	)
	(segment
		(start 82.880454 -133.451346)
		(end 81.497678 -133.451346)
		(width 0.127)
		(layer "In5.Cu")
		(net "COMP_PWR_BTN_N")
	)
	(segment
		(start 75.4888 -133.8834)
		(end 75.1459 -133.5405)
		(width 0.127)
		(layer "In5.Cu")
		(net "COMP_PWR_BTN_N")
	)
	(segment
		(start 94.316042 -128.4605)
		(end 91.077542 -131.699)
		(width 0.127)
		(layer "In5.Cu")
		(net "COMP_PWR_BTN_N")
	)
	(segment
		(start 73.9648 -132.207)
		(end 73.7362 -132.4356)
		(width 0.127)
		(layer "In5.Cu")
		(net "COMP_PWR_BTN_N")
	)
	(segment
		(start 97.510854 -128.4605)
		(end 94.316042 -128.4605)
		(width 0.127)
		(layer "In5.Cu")
		(net "COMP_PWR_BTN_N")
	)
	(segment
		(start 83.2358 -133.096)
		(end 82.880454 -133.451346)
		(width 0.127)
		(layer "In5.Cu")
		(net "COMP_PWR_BTN_N")
	)
	(segment
		(start 88.533224 -131.699)
		(end 87.136224 -133.096)
		(width 0.127)
		(layer "In5.Cu")
		(net "COMP_PWR_BTN_N")
	)
	(segment
		(start 81.065624 -133.8834)
		(end 75.4888 -133.8834)
		(width 0.127)
		(layer "In5.Cu")
		(net "COMP_PWR_BTN_N")
	)
	(segment
		(start 73.7362 -132.4356)
		(end 63.741554 -132.4356)
		(width 0.127)
		(layer "In5.Cu")
		(net "COMP_PWR_BTN_N")
	)
	(segment
		(start 99.225354 -126.746)
		(end 97.510854 -128.4605)
		(width 0.127)
		(layer "In5.Cu")
		(net "COMP_PWR_BTN_N")
	)
	(segment
		(start 75.1459 -133.5405)
		(end 75.1459 -132.6261)
		(width 0.127)
		(layer "In5.Cu")
		(net "COMP_PWR_BTN_N")
	)
	(segment
		(start 87.136224 -133.096)
		(end 83.2358 -133.096)
		(width 0.127)
		(layer "In5.Cu")
		(net "COMP_PWR_BTN_N")
	)
	(segment
		(start 75.1459 -132.6261)
		(end 74.7268 -132.207)
		(width 0.127)
		(layer "In5.Cu")
		(net "COMP_PWR_BTN_N")
	)
	(segment
		(start 74.7268 -132.207)
		(end 73.9648 -132.207)
		(width 0.127)
		(layer "In5.Cu")
		(net "COMP_PWR_BTN_N")
	)
	(segment
		(start 40.099996 -150.999952)
		(end 39.668196 -151.431752)
		(width 0.127)
		(layer "F.Cu")
		(net "COMP_POWER_FAIL_R_N")
	)
	(segment
		(start 34.840418 -155.829)
		(end 35.64636 -155.829)
		(width 0.127)
		(layer "F.Cu")
		(net "COMP_POWER_FAIL_R_N")
	)
	(segment
		(start 34.728658 -155.71724)
		(end 34.840418 -155.829)
		(width 0.127)
		(layer "F.Cu")
		(net "COMP_POWER_FAIL_R_N")
	)
	(segment
		(start 37.128196 -155.031186)
		(end 36.717732 -155.44165)
		(width 0.127)
		(layer "F.Cu")
		(net "COMP_POWER_FAIL_R_N")
	)
	(segment
		(start 37.128196 -153.595324)
		(end 37.128196 -155.031186)
		(width 0.127)
		(layer "F.Cu")
		(net "COMP_POWER_FAIL_R_N")
	)
	(segment
		(start 39.668196 -151.431752)
		(end 39.147242 -151.431752)
		(width 0.127)
		(layer "F.Cu")
		(net "COMP_POWER_FAIL_R_N")
	)
	(segment
		(start 38.931596 -151.791924)
		(end 37.128196 -153.595324)
		(width 0.127)
		(layer "F.Cu")
		(net "COMP_POWER_FAIL_R_N")
	)
	(segment
		(start 36.717732 -155.44165)
		(end 36.378134 -155.44165)
		(width 0.127)
		(layer "F.Cu")
		(net "COMP_POWER_FAIL_R_N")
	)
	(segment
		(start 35.64636 -155.829)
		(end 36.03371 -155.44165)
		(width 0.127)
		(layer "F.Cu")
		(net "COMP_POWER_FAIL_R_N")
	)
	(segment
		(start 38.931596 -151.647398)
		(end 38.931596 -151.791924)
		(width 0.127)
		(layer "F.Cu")
		(net "COMP_POWER_FAIL_R_N")
	)
	(segment
		(start 36.03371 -155.44165)
		(end 36.378134 -155.44165)
		(width 0.127)
		(layer "F.Cu")
		(net "COMP_POWER_FAIL_R_N")
	)
	(segment
		(start 39.147242 -151.431752)
		(end 38.931596 -151.647398)
		(width 0.127)
		(layer "F.Cu")
		(net "COMP_POWER_FAIL_R_N")
	)
	(via
		(at 36.378134 -155.44165)
		(size 0.6604)
		(drill 0.3302)
		(layers "F.Cu" "B.Cu")
		(net "COMP_POWER_FAIL_R_N")
	)
	(segment
		(start 32.3342 -155.460192)
		(end 32.3342 -156.0068)
		(width 0.127)
		(layer "F.Cu")
		(net "COMP_POWER_FAIL_N")
	)
	(segment
		(start 32.574992 -155.2194)
		(end 32.3342 -155.460192)
		(width 0.127)
		(layer "F.Cu")
		(net "COMP_POWER_FAIL_N")
	)
	(segment
		(start 32.7152 -155.2194)
		(end 32.574992 -155.2194)
		(width 0.127)
		(layer "F.Cu")
		(net "COMP_POWER_FAIL_N")
	)
	(segment
		(start 31.216346 -156.793946)
		(end 30.950662 -156.528262)
		(width 0.127)
		(layer "F.Cu")
		(net "COMP_POWER_FAIL_N")
	)
	(segment
		(start 32.0167 -156.3243)
		(end 32.0167 -156.474668)
		(width 0.127)
		(layer "F.Cu")
		(net "COMP_POWER_FAIL_N")
	)
	(segment
		(start 31.697422 -156.793946)
		(end 31.216346 -156.793946)
		(width 0.127)
		(layer "F.Cu")
		(net "COMP_POWER_FAIL_N")
	)
	(segment
		(start 33.341818 -155.2194)
		(end 33.839658 -155.71724)
		(width 0.127)
		(layer "F.Cu")
		(net "COMP_POWER_FAIL_N")
	)
	(segment
		(start 30.950662 -156.528262)
		(end 30.950662 -155.909772)
		(width 0.127)
		(layer "F.Cu")
		(net "COMP_POWER_FAIL_N")
	)
	(segment
		(start 32.7152 -155.2194)
		(end 33.341818 -155.2194)
		(width 0.127)
		(layer "F.Cu")
		(net "COMP_POWER_FAIL_N")
	)
	(segment
		(start 32.0167 -156.474668)
		(end 31.697422 -156.793946)
		(width 0.127)
		(layer "F.Cu")
		(net "COMP_POWER_FAIL_N")
	)
	(segment
		(start 32.3342 -156.0068)
		(end 32.0167 -156.3243)
		(width 0.127)
		(layer "F.Cu")
		(net "COMP_POWER_FAIL_N")
	)
	(via
		(at 31.697422 -156.793946)
		(size 0.508)
		(drill 0.254)
		(layers "F.Cu" "B.Cu")
		(net "COMP_POWER_FAIL_N")
	)
	(via
		(at 32.7152 -155.2194)
		(size 0.6604)
		(drill 0.3302)
		(layers "F.Cu" "B.Cu")
		(net "COMP_POWER_FAIL_N")
	)
	(via
		(at 96.2914 -178.6382)
		(size 0.508)
		(drill 0.254)
		(layers "F.Cu" "B.Cu")
		(net "COMP_POWER_FAIL_N")
	)
	(segment
		(start 106.985054 -30.328616)
		(end 105.423462 -31.890208)
		(width 0.127)
		(layer "In2.Cu")
		(net "COMP_POWER_FAIL_N")
	)
	(segment
		(start 101.33711 -138.508232)
		(end 101.33711 -166.150036)
		(width 0.127)
		(layer "In2.Cu")
		(net "COMP_POWER_FAIL_N")
	)
	(segment
		(start 99.3902 -123.603004)
		(end 100.487988 -124.700792)
		(width 0.127)
		(layer "In2.Cu")
		(net "COMP_POWER_FAIL_N")
	)
	(segment
		(start 99.4664 -136.637522)
		(end 101.33711 -138.508232)
		(width 0.127)
		(layer "In2.Cu")
		(net "COMP_POWER_FAIL_N")
	)
	(segment
		(start 99.3902 -121.680224)
		(end 99.3902 -123.603004)
		(width 0.127)
		(layer "In2.Cu")
		(net "COMP_POWER_FAIL_N")
	)
	(segment
		(start 111.4044 -31.996126)
		(end 109.73689 -30.328616)
		(width 0.127)
		(layer "In2.Cu")
		(net "COMP_POWER_FAIL_N")
	)
	(segment
		(start 96.671892 -178.6382)
		(end 96.2914 -178.6382)
		(width 0.127)
		(layer "In2.Cu")
		(net "COMP_POWER_FAIL_N")
	)
	(segment
		(start 99.4664 -135.494776)
		(end 99.4664 -136.637522)
		(width 0.127)
		(layer "In2.Cu")
		(net "COMP_POWER_FAIL_N")
	)
	(segment
		(start 100.457 -174.853092)
		(end 96.671892 -178.6382)
		(width 0.127)
		(layer "In2.Cu")
		(net "COMP_POWER_FAIL_N")
	)
	(segment
		(start 99.7966 -135.164576)
		(end 99.4664 -135.494776)
		(width 0.127)
		(layer "In2.Cu")
		(net "COMP_POWER_FAIL_N")
	)
	(segment
		(start 100.487988 -124.700792)
		(end 100.487988 -127.400812)
		(width 0.127)
		(layer "In2.Cu")
		(net "COMP_POWER_FAIL_N")
	)
	(segment
		(start 99.7966 -130.578606)
		(end 99.7966 -135.164576)
		(width 0.127)
		(layer "In2.Cu")
		(net "COMP_POWER_FAIL_N")
	)
	(segment
		(start 100.203 -46.346364)
		(end 100.203 -120.867424)
		(width 0.127)
		(layer "In2.Cu")
		(net "COMP_POWER_FAIL_N")
	)
	(segment
		(start 100.076 -167.411146)
		(end 100.076 -168.5544)
		(width 0.127)
		(layer "In2.Cu")
		(net "COMP_POWER_FAIL_N")
	)
	(segment
		(start 111.4044 -39.50462)
		(end 111.4044 -31.996126)
		(width 0.127)
		(layer "In2.Cu")
		(net "COMP_POWER_FAIL_N")
	)
	(segment
		(start 100.487988 -127.400812)
		(end 99.508818 -128.379982)
		(width 0.127)
		(layer "In2.Cu")
		(net "COMP_POWER_FAIL_N")
	)
	(segment
		(start 99.508818 -128.379982)
		(end 99.508818 -130.290824)
		(width 0.127)
		(layer "In2.Cu")
		(net "COMP_POWER_FAIL_N")
	)
	(segment
		(start 99.508818 -130.290824)
		(end 99.7966 -130.578606)
		(width 0.127)
		(layer "In2.Cu")
		(net "COMP_POWER_FAIL_N")
	)
	(segment
		(start 100.203 -120.867424)
		(end 99.3902 -121.680224)
		(width 0.127)
		(layer "In2.Cu")
		(net "COMP_POWER_FAIL_N")
	)
	(segment
		(start 105.423462 -31.890208)
		(end 105.423462 -41.125902)
		(width 0.127)
		(layer "In2.Cu")
		(net "COMP_POWER_FAIL_N")
	)
	(segment
		(start 112.499902 -40.600122)
		(end 111.4044 -39.50462)
		(width 0.127)
		(layer "In2.Cu")
		(net "COMP_POWER_FAIL_N")
	)
	(segment
		(start 105.423462 -41.125902)
		(end 100.203 -46.346364)
		(width 0.127)
		(layer "In2.Cu")
		(net "COMP_POWER_FAIL_N")
	)
	(segment
		(start 100.457 -168.9354)
		(end 100.457 -174.853092)
		(width 0.127)
		(layer "In2.Cu")
		(net "COMP_POWER_FAIL_N")
	)
	(segment
		(start 101.33711 -166.150036)
		(end 100.076 -167.411146)
		(width 0.127)
		(layer "In2.Cu")
		(net "COMP_POWER_FAIL_N")
	)
	(segment
		(start 100.076 -168.5544)
		(end 100.457 -168.9354)
		(width 0.127)
		(layer "In2.Cu")
		(net "COMP_POWER_FAIL_N")
	)
	(segment
		(start 109.73689 -30.328616)
		(end 106.985054 -30.328616)
		(width 0.127)
		(layer "In2.Cu")
		(net "COMP_POWER_FAIL_N")
	)
	(segment
		(start 66.230754 -174.4853)
		(end 59.8043 -174.4853)
		(width 0.127)
		(layer "In5.Cu")
		(net "COMP_POWER_FAIL_N")
	)
	(segment
		(start 85.344 -177.927)
		(end 83.0453 -175.6283)
		(width 0.127)
		(layer "In5.Cu")
		(net "COMP_POWER_FAIL_N")
	)
	(segment
		(start 44.380912 -165.8366)
		(end 40.849042 -165.8366)
		(width 0.127)
		(layer "In5.Cu")
		(net "COMP_POWER_FAIL_N")
	)
	(segment
		(start 57.4802 -172.1612)
		(end 55.115968 -172.1612)
		(width 0.127)
		(layer "In5.Cu")
		(net "COMP_POWER_FAIL_N")
	)
	(segment
		(start 34.212022 -159.308546)
		(end 31.697422 -156.793946)
		(width 0.127)
		(layer "In5.Cu")
		(net "COMP_POWER_FAIL_N")
	)
	(segment
		(start 68.318888 -174.192946)
		(end 66.523108 -174.192946)
		(width 0.127)
		(layer "In5.Cu")
		(net "COMP_POWER_FAIL_N")
	)
	(segment
		(start 50.924968 -167.9702)
		(end 46.514512 -167.9702)
		(width 0.127)
		(layer "In5.Cu")
		(net "COMP_POWER_FAIL_N")
	)
	(segment
		(start 83.0453 -175.6283)
		(end 77.616812 -175.6283)
		(width 0.127)
		(layer "In5.Cu")
		(net "COMP_POWER_FAIL_N")
	)
	(segment
		(start 59.8043 -174.4853)
		(end 57.4802 -172.1612)
		(width 0.127)
		(layer "In5.Cu")
		(net "COMP_POWER_FAIL_N")
	)
	(segment
		(start 68.636134 -173.8757)
		(end 68.318888 -174.192946)
		(width 0.127)
		(layer "In5.Cu")
		(net "COMP_POWER_FAIL_N")
	)
	(segment
		(start 77.616812 -175.6283)
		(end 75.864212 -173.8757)
		(width 0.127)
		(layer "In5.Cu")
		(net "COMP_POWER_FAIL_N")
	)
	(segment
		(start 66.523108 -174.192946)
		(end 66.230754 -174.4853)
		(width 0.127)
		(layer "In5.Cu")
		(net "COMP_POWER_FAIL_N")
	)
	(segment
		(start 36.683188 -161.670746)
		(end 36.683188 -161.22904)
		(width 0.127)
		(layer "In5.Cu")
		(net "COMP_POWER_FAIL_N")
	)
	(segment
		(start 55.115968 -172.1612)
		(end 50.924968 -167.9702)
		(width 0.127)
		(layer "In5.Cu")
		(net "COMP_POWER_FAIL_N")
	)
	(segment
		(start 96.2914 -178.6382)
		(end 95.5802 -177.927)
		(width 0.127)
		(layer "In5.Cu")
		(net "COMP_POWER_FAIL_N")
	)
	(segment
		(start 95.5802 -177.927)
		(end 85.344 -177.927)
		(width 0.127)
		(layer "In5.Cu")
		(net "COMP_POWER_FAIL_N")
	)
	(segment
		(start 34.762694 -159.308546)
		(end 34.212022 -159.308546)
		(width 0.127)
		(layer "In5.Cu")
		(net "COMP_POWER_FAIL_N")
	)
	(segment
		(start 46.514512 -167.9702)
		(end 44.380912 -165.8366)
		(width 0.127)
		(layer "In5.Cu")
		(net "COMP_POWER_FAIL_N")
	)
	(segment
		(start 36.683188 -161.22904)
		(end 34.762694 -159.308546)
		(width 0.127)
		(layer "In5.Cu")
		(net "COMP_POWER_FAIL_N")
	)
	(segment
		(start 40.849042 -165.8366)
		(end 36.683188 -161.670746)
		(width 0.127)
		(layer "In5.Cu")
		(net "COMP_POWER_FAIL_N")
	)
	(segment
		(start 75.864212 -173.8757)
		(end 68.636134 -173.8757)
		(width 0.127)
		(layer "In5.Cu")
		(net "COMP_POWER_FAIL_N")
	)
	(segment
		(start 33.162748 -152.161748)
		(end 33.147 -152.146)
		(width 0.127)
		(layer "F.Cu")
		(net "COMP_FAST_THROTTLE_N")
	)
	(segment
		(start 112.499902 -39.200074)
		(end 112.371632 -39.200074)
		(width 0.127)
		(layer "F.Cu")
		(net "COMP_FAST_THROTTLE_N")
	)
	(segment
		(start 32.1945 -152.146)
		(end 33.147 -152.146)
		(width 0.127)
		(layer "F.Cu")
		(net "COMP_FAST_THROTTLE_N")
	)
	(segment
		(start 111.652558 -38.481)
		(end 111.652558 -29.673042)
		(width 0.127)
		(layer "F.Cu")
		(net "COMP_FAST_THROTTLE_N")
	)
	(segment
		(start 32.394906 -152.346406)
		(end 32.1945 -152.146)
		(width 0.127)
		(layer "F.Cu")
		(net "COMP_FAST_THROTTLE_N")
	)
	(segment
		(start 113.0554 -27.94)
		(end 116.0145 -24.9809)
		(width 0.127)
		(layer "F.Cu")
		(net "COMP_FAST_THROTTLE_N")
	)
	(segment
		(start 116.953284 -24.9809)
		(end 117.569996 -24.364188)
		(width 0.127)
		(layer "F.Cu")
		(net "COMP_FAST_THROTTLE_N")
	)
	(segment
		(start 112.371632 -39.200074)
		(end 111.652558 -38.481)
		(width 0.127)
		(layer "F.Cu")
		(net "COMP_FAST_THROTTLE_N")
	)
	(segment
		(start 34.086546 -152.161748)
		(end 33.162748 -152.161748)
		(width 0.127)
		(layer "F.Cu")
		(net "COMP_FAST_THROTTLE_N")
	)
	(segment
		(start 113.0554 -28.2702)
		(end 113.0554 -27.94)
		(width 0.127)
		(layer "F.Cu")
		(net "COMP_FAST_THROTTLE_N")
	)
	(segment
		(start 116.0145 -24.9809)
		(end 116.953284 -24.9809)
		(width 0.127)
		(layer "F.Cu")
		(net "COMP_FAST_THROTTLE_N")
	)
	(segment
		(start 31.725362 -155.015438)
		(end 32.394906 -154.345894)
		(width 0.127)
		(layer "F.Cu")
		(net "COMP_FAST_THROTTLE_N")
	)
	(segment
		(start 31.725362 -155.9306)
		(end 31.725362 -155.015438)
		(width 0.127)
		(layer "F.Cu")
		(net "COMP_FAST_THROTTLE_N")
	)
	(segment
		(start 32.394906 -154.345894)
		(end 32.394906 -152.346406)
		(width 0.127)
		(layer "F.Cu")
		(net "COMP_FAST_THROTTLE_N")
	)
	(segment
		(start 111.652558 -29.673042)
		(end 113.0554 -28.2702)
		(width 0.127)
		(layer "F.Cu")
		(net "COMP_FAST_THROTTLE_N")
	)
	(via
		(at 83.4644 -167.9194)
		(size 0.508)
		(drill 0.254)
		(layers "F.Cu" "B.Cu")
		(net "COMP_FAST_THROTTLE_N")
	)
	(via
		(at 31.725362 -155.9306)
		(size 0.508)
		(drill 0.254)
		(layers "F.Cu" "B.Cu")
		(net "COMP_FAST_THROTTLE_N")
	)
	(via
		(at 33.147 -152.146)
		(size 0.6604)
		(drill 0.3302)
		(layers "F.Cu" "B.Cu")
		(net "COMP_FAST_THROTTLE_N")
	)
	(via
		(at 117.569996 -24.364188)
		(size 0.508)
		(drill 0.254)
		(layers "F.Cu" "B.Cu")
		(net "COMP_FAST_THROTTLE_N")
	)
	(via
		(at 108.14431 -14.29131)
		(size 0.508)
		(drill 0.254)
		(layers "F.Cu" "B.Cu")
		(net "COMP_FAST_THROTTLE_N")
	)
	(segment
		(start 114.986308 -21.4376)
		(end 111.9124 -21.4376)
		(width 0.127)
		(layer "B.Cu")
		(net "COMP_FAST_THROTTLE_N")
	)
	(segment
		(start 31.06928 -155.9306)
		(end 30.897322 -156.102558)
		(width 0.127)
		(layer "B.Cu")
		(net "COMP_FAST_THROTTLE_N")
	)
	(segment
		(start 108.14431 -17.66951)
		(end 108.14431 -14.29131)
		(width 0.127)
		(layer "B.Cu")
		(net "COMP_FAST_THROTTLE_N")
	)
	(segment
		(start 111.9124 -21.4376)
		(end 108.14431 -17.66951)
		(width 0.127)
		(layer "B.Cu")
		(net "COMP_FAST_THROTTLE_N")
	)
	(segment
		(start 117.569996 -24.021288)
		(end 114.986308 -21.4376)
		(width 0.127)
		(layer "B.Cu")
		(net "COMP_FAST_THROTTLE_N")
	)
	(segment
		(start 31.725362 -155.9306)
		(end 31.06928 -155.9306)
		(width 0.127)
		(layer "B.Cu")
		(net "COMP_FAST_THROTTLE_N")
	)
	(segment
		(start 117.569996 -24.364188)
		(end 117.569996 -24.021288)
		(width 0.127)
		(layer "B.Cu")
		(net "COMP_FAST_THROTTLE_N")
	)
	(segment
		(start 106.299 -4.1148)
		(end 95.994728 -4.1148)
		(width 0.127)
		(layer "In2.Cu")
		(net "COMP_FAST_THROTTLE_N")
	)
	(segment
		(start 83.813396 -90.195654)
		(end 82.91322 -91.09583)
		(width 0.127)
		(layer "In2.Cu")
		(net "COMP_FAST_THROTTLE_N")
	)
	(segment
		(start 82.540348 -164.12972)
		(end 82.540348 -166.995348)
		(width 0.127)
		(layer "In2.Cu")
		(net "COMP_FAST_THROTTLE_N")
	)
	(segment
		(start 108.4834 -13.95222)
		(end 108.4834 -6.2992)
		(width 0.127)
		(layer "In2.Cu")
		(net "COMP_FAST_THROTTLE_N")
	)
	(segment
		(start 108.14431 -14.29131)
		(end 108.4834 -13.95222)
		(width 0.127)
		(layer "In2.Cu")
		(net "COMP_FAST_THROTTLE_N")
	)
	(segment
		(start 86.2203 -102.893368)
		(end 86.2203 -107.615228)
		(width 0.127)
		(layer "In2.Cu")
		(net "COMP_FAST_THROTTLE_N")
	)
	(segment
		(start 95.994728 -4.1148)
		(end 93.087952 -7.021576)
		(width 0.127)
		(layer "In2.Cu")
		(net "COMP_FAST_THROTTLE_N")
	)
	(segment
		(start 74.066654 -117.541802)
		(end 74.066654 -123.328176)
		(width 0.127)
		(layer "In2.Cu")
		(net "COMP_FAST_THROTTLE_N")
	)
	(segment
		(start 82.91322 -99.586288)
		(end 86.2203 -102.893368)
		(width 0.127)
		(layer "In2.Cu")
		(net "COMP_FAST_THROTTLE_N")
	)
	(segment
		(start 81.018634 -33.038034)
		(end 82.7659 -34.7853)
		(width 0.127)
		(layer "In2.Cu")
		(net "COMP_FAST_THROTTLE_N")
	)
	(segment
		(start 79.121 -158.3182)
		(end 81.4959 -160.6931)
		(width 0.127)
		(layer "In2.Cu")
		(net "COMP_FAST_THROTTLE_N")
	)
	(segment
		(start 82.540348 -166.995348)
		(end 83.4644 -167.9194)
		(width 0.127)
		(layer "In2.Cu")
		(net "COMP_FAST_THROTTLE_N")
	)
	(segment
		(start 78.0796 -136.797034)
		(end 80.177386 -138.89482)
		(width 0.127)
		(layer "In2.Cu")
		(net "COMP_FAST_THROTTLE_N")
	)
	(segment
		(start 81.01838 -10.007092)
		(end 81.018634 -10.007346)
		(width 0.127)
		(layer "In2.Cu")
		(net "COMP_FAST_THROTTLE_N")
	)
	(segment
		(start 77.724 -131.131818)
		(end 77.724 -132.056124)
		(width 0.127)
		(layer "In2.Cu")
		(net "COMP_FAST_THROTTLE_N")
	)
	(segment
		(start 83.407504 -71.393304)
		(end 83.813396 -71.799196)
		(width 0.127)
		(layer "In2.Cu")
		(net "COMP_FAST_THROTTLE_N")
	)
	(segment
		(start 83.9597 -109.875828)
		(end 83.9597 -110.847124)
		(width 0.127)
		(layer "In2.Cu")
		(net "COMP_FAST_THROTTLE_N")
	)
	(segment
		(start 79.093568 -150.951184)
		(end 79.121 -150.978616)
		(width 0.127)
		(layer "In2.Cu")
		(net "COMP_FAST_THROTTLE_N")
	)
	(segment
		(start 80.177386 -142.33906)
		(end 78.98511 -143.531336)
		(width 0.127)
		(layer "In2.Cu")
		(net "COMP_FAST_THROTTLE_N")
	)
	(segment
		(start 79.121 -150.978616)
		(end 79.121 -158.3182)
		(width 0.127)
		(layer "In2.Cu")
		(net "COMP_FAST_THROTTLE_N")
	)
	(segment
		(start 82.7659 -68.5927)
		(end 83.407504 -69.234304)
		(width 0.127)
		(layer "In2.Cu")
		(net "COMP_FAST_THROTTLE_N")
	)
	(segment
		(start 78.98511 -148.87321)
		(end 79.093568 -148.981668)
		(width 0.127)
		(layer "In2.Cu")
		(net "COMP_FAST_THROTTLE_N")
	)
	(segment
		(start 77.302106 -128.766824)
		(end 78.0796 -129.544318)
		(width 0.127)
		(layer "In2.Cu")
		(net "COMP_FAST_THROTTLE_N")
	)
	(segment
		(start 78.0796 -132.411724)
		(end 78.0796 -136.797034)
		(width 0.127)
		(layer "In2.Cu")
		(net "COMP_FAST_THROTTLE_N")
	)
	(segment
		(start 81.01838 -9.691624)
		(end 81.01838 -10.007092)
		(width 0.127)
		(layer "In2.Cu")
		(net "COMP_FAST_THROTTLE_N")
	)
	(segment
		(start 82.7659 -34.7853)
		(end 82.7659 -68.5927)
		(width 0.127)
		(layer "In2.Cu")
		(net "COMP_FAST_THROTTLE_N")
	)
	(segment
		(start 79.093568 -148.981668)
		(end 79.093568 -150.951184)
		(width 0.127)
		(layer "In2.Cu")
		(net "COMP_FAST_THROTTLE_N")
	)
	(segment
		(start 77.302106 -126.563628)
		(end 77.302106 -128.766824)
		(width 0.127)
		(layer "In2.Cu")
		(net "COMP_FAST_THROTTLE_N")
	)
	(segment
		(start 77.724 -132.056124)
		(end 78.0796 -132.411724)
		(width 0.127)
		(layer "In2.Cu")
		(net "COMP_FAST_THROTTLE_N")
	)
	(segment
		(start 108.4834 -6.2992)
		(end 106.299 -4.1148)
		(width 0.127)
		(layer "In2.Cu")
		(net "COMP_FAST_THROTTLE_N")
	)
	(segment
		(start 83.407504 -69.234304)
		(end 83.407504 -71.393304)
		(width 0.127)
		(layer "In2.Cu")
		(net "COMP_FAST_THROTTLE_N")
	)
	(segment
		(start 74.066654 -123.328176)
		(end 77.302106 -126.563628)
		(width 0.127)
		(layer "In2.Cu")
		(net "COMP_FAST_THROTTLE_N")
	)
	(segment
		(start 80.177386 -138.89482)
		(end 80.177386 -142.33906)
		(width 0.127)
		(layer "In2.Cu")
		(net "COMP_FAST_THROTTLE_N")
	)
	(segment
		(start 86.2203 -107.615228)
		(end 83.9597 -109.875828)
		(width 0.127)
		(layer "In2.Cu")
		(net "COMP_FAST_THROTTLE_N")
	)
	(segment
		(start 83.813396 -71.799196)
		(end 83.813396 -90.195654)
		(width 0.127)
		(layer "In2.Cu")
		(net "COMP_FAST_THROTTLE_N")
	)
	(segment
		(start 81.4959 -163.085272)
		(end 82.540348 -164.12972)
		(width 0.127)
		(layer "In2.Cu")
		(net "COMP_FAST_THROTTLE_N")
	)
	(segment
		(start 83.688428 -7.021576)
		(end 81.01838 -9.691624)
		(width 0.127)
		(layer "In2.Cu")
		(net "COMP_FAST_THROTTLE_N")
	)
	(segment
		(start 80.827626 -113.979198)
		(end 77.629258 -113.979198)
		(width 0.127)
		(layer "In2.Cu")
		(net "COMP_FAST_THROTTLE_N")
	)
	(segment
		(start 93.087952 -7.021576)
		(end 83.688428 -7.021576)
		(width 0.127)
		(layer "In2.Cu")
		(net "COMP_FAST_THROTTLE_N")
	)
	(segment
		(start 78.0796 -129.544318)
		(end 78.0796 -130.776218)
		(width 0.127)
		(layer "In2.Cu")
		(net "COMP_FAST_THROTTLE_N")
	)
	(segment
		(start 83.9597 -110.847124)
		(end 80.827626 -113.979198)
		(width 0.127)
		(layer "In2.Cu")
		(net "COMP_FAST_THROTTLE_N")
	)
	(segment
		(start 81.018634 -10.007346)
		(end 81.018634 -33.038034)
		(width 0.127)
		(layer "In2.Cu")
		(net "COMP_FAST_THROTTLE_N")
	)
	(segment
		(start 82.91322 -91.09583)
		(end 82.91322 -99.586288)
		(width 0.127)
		(layer "In2.Cu")
		(net "COMP_FAST_THROTTLE_N")
	)
	(segment
		(start 78.98511 -143.531336)
		(end 78.98511 -148.87321)
		(width 0.127)
		(layer "In2.Cu")
		(net "COMP_FAST_THROTTLE_N")
	)
	(segment
		(start 78.0796 -130.776218)
		(end 77.724 -131.131818)
		(width 0.127)
		(layer "In2.Cu")
		(net "COMP_FAST_THROTTLE_N")
	)
	(segment
		(start 77.629258 -113.979198)
		(end 74.066654 -117.541802)
		(width 0.127)
		(layer "In2.Cu")
		(net "COMP_FAST_THROTTLE_N")
	)
	(segment
		(start 81.4959 -160.6931)
		(end 81.4959 -163.085272)
		(width 0.127)
		(layer "In2.Cu")
		(net "COMP_FAST_THROTTLE_N")
	)
	(segment
		(start 40.314118 -158.2674)
		(end 42.879518 -160.8328)
		(width 0.127)
		(layer "In5.Cu")
		(net "COMP_FAST_THROTTLE_N")
	)
	(segment
		(start 47.014384 -163.096702)
		(end 47.135796 -163.096702)
		(width 0.127)
		(layer "In5.Cu")
		(net "COMP_FAST_THROTTLE_N")
	)
	(segment
		(start 35.648138 -156.82595)
		(end 37.089588 -158.2674)
		(width 0.127)
		(layer "In5.Cu")
		(net "COMP_FAST_THROTTLE_N")
	)
	(segment
		(start 46.4439 -162.288982)
		(end 46.4439 -162.526218)
		(width 0.127)
		(layer "In5.Cu")
		(net "COMP_FAST_THROTTLE_N")
	)
	(segment
		(start 83.45678 -167.92702)
		(end 83.4644 -167.9194)
		(width 0.127)
		(layer "In5.Cu")
		(net "COMP_FAST_THROTTLE_N")
	)
	(segment
		(start 32.2834 -155.9306)
		(end 32.4104 -155.8036)
		(width 0.127)
		(layer "In5.Cu")
		(net "COMP_FAST_THROTTLE_N")
	)
	(segment
		(start 48.783494 -164.7444)
		(end 53.891942 -164.7444)
		(width 0.127)
		(layer "In5.Cu")
		(net "COMP_FAST_THROTTLE_N")
	)
	(segment
		(start 68.3514 -167.7035)
		(end 68.57492 -167.92702)
		(width 0.127)
		(layer "In5.Cu")
		(net "COMP_FAST_THROTTLE_N")
	)
	(segment
		(start 68.57492 -167.92702)
		(end 83.45678 -167.92702)
		(width 0.127)
		(layer "In5.Cu")
		(net "COMP_FAST_THROTTLE_N")
	)
	(segment
		(start 53.891942 -164.7444)
		(end 57.028842 -167.8813)
		(width 0.127)
		(layer "In5.Cu")
		(net "COMP_FAST_THROTTLE_N")
	)
	(segment
		(start 66.250566 -167.8813)
		(end 66.428366 -167.7035)
		(width 0.127)
		(layer "In5.Cu")
		(net "COMP_FAST_THROTTLE_N")
	)
	(segment
		(start 33.101788 -155.8036)
		(end 34.124138 -156.82595)
		(width 0.127)
		(layer "In5.Cu")
		(net "COMP_FAST_THROTTLE_N")
	)
	(segment
		(start 32.4104 -155.8036)
		(end 33.101788 -155.8036)
		(width 0.127)
		(layer "In5.Cu")
		(net "COMP_FAST_THROTTLE_N")
	)
	(segment
		(start 34.124138 -156.82595)
		(end 35.648138 -156.82595)
		(width 0.127)
		(layer "In5.Cu")
		(net "COMP_FAST_THROTTLE_N")
	)
	(segment
		(start 42.879518 -160.8328)
		(end 44.987718 -160.8328)
		(width 0.127)
		(layer "In5.Cu")
		(net "COMP_FAST_THROTTLE_N")
	)
	(segment
		(start 37.089588 -158.2674)
		(end 40.314118 -158.2674)
		(width 0.127)
		(layer "In5.Cu")
		(net "COMP_FAST_THROTTLE_N")
	)
	(segment
		(start 66.428366 -167.7035)
		(end 68.3514 -167.7035)
		(width 0.127)
		(layer "In5.Cu")
		(net "COMP_FAST_THROTTLE_N")
	)
	(segment
		(start 47.135796 -163.096702)
		(end 48.783494 -164.7444)
		(width 0.127)
		(layer "In5.Cu")
		(net "COMP_FAST_THROTTLE_N")
	)
	(segment
		(start 46.4439 -162.526218)
		(end 47.014384 -163.096702)
		(width 0.127)
		(layer "In5.Cu")
		(net "COMP_FAST_THROTTLE_N")
	)
	(segment
		(start 57.028842 -167.8813)
		(end 66.250566 -167.8813)
		(width 0.127)
		(layer "In5.Cu")
		(net "COMP_FAST_THROTTLE_N")
	)
	(segment
		(start 44.987718 -160.8328)
		(end 46.4439 -162.288982)
		(width 0.127)
		(layer "In5.Cu")
		(net "COMP_FAST_THROTTLE_N")
	)
	(segment
		(start 31.725362 -155.9306)
		(end 32.2834 -155.9306)
		(width 0.127)
		(layer "In5.Cu")
		(net "COMP_FAST_THROTTLE_N")
	)
	(segment
		(start 44.099988 -136.59993)
		(end 44.099988 -136.239758)
		(width 0.127)
		(layer "F.Cu")
		(net "BMC_SELF_HW_RST")
	)
	(segment
		(start 70.5104 -171.3484)
		(end 70.5104 -172.7708)
		(width 0.127)
		(layer "F.Cu")
		(net "BMC_SELF_HW_RST")
	)
	(segment
		(start 44.099988 -136.239758)
		(end 43.664124 -135.803894)
		(width 0.127)
		(layer "F.Cu")
		(net "BMC_SELF_HW_RST")
	)
	(via
		(at 64.641476 -134.416292)
		(size 0.508)
		(drill 0.254)
		(layers "F.Cu" "B.Cu")
		(net "BMC_SELF_HW_RST")
	)
	(via
		(at 43.664124 -135.803894)
		(size 0.4572)
		(drill 0.2032)
		(layers "F.Cu" "B.Cu")
		(net "BMC_SELF_HW_RST")
	)
	(via
		(at 70.5104 -172.7708)
		(size 0.508)
		(drill 0.254)
		(layers "F.Cu" "B.Cu")
		(net "BMC_SELF_HW_RST")
	)
	(segment
		(start 64.096646 -138.92403)
		(end 64.096646 -139.204954)
		(width 0.127)
		(layer "In2.Cu")
		(net "BMC_SELF_HW_RST")
	)
	(segment
		(start 64.084454 -149.399752)
		(end 64.90208 -150.217378)
		(width 0.127)
		(layer "In2.Cu")
		(net "BMC_SELF_HW_RST")
	)
	(segment
		(start 64.08293 -139.21867)
		(end 64.08293 -139.835636)
		(width 0.127)
		(layer "In2.Cu")
		(net "BMC_SELF_HW_RST")
	)
	(segment
		(start 68.4149 -160.31718)
		(end 68.4149 -165.5191)
		(width 0.127)
		(layer "In2.Cu")
		(net "BMC_SELF_HW_RST")
	)
	(segment
		(start 70.1294 -172.3898)
		(end 70.5104 -172.7708)
		(width 0.127)
		(layer "In2.Cu")
		(net "BMC_SELF_HW_RST")
	)
	(segment
		(start 63.371984 -146.337274)
		(end 64.084454 -147.049744)
		(width 0.127)
		(layer "In2.Cu")
		(net "BMC_SELF_HW_RST")
	)
	(segment
		(start 65.5828 -137.437876)
		(end 64.096646 -138.92403)
		(width 0.127)
		(layer "In2.Cu")
		(net "BMC_SELF_HW_RST")
	)
	(segment
		(start 66.63944 -154.311096)
		(end 66.63944 -158.54172)
		(width 0.127)
		(layer "In2.Cu")
		(net "BMC_SELF_HW_RST")
	)
	(segment
		(start 64.641476 -134.416292)
		(end 65.5828 -135.357616)
		(width 0.127)
		(layer "In2.Cu")
		(net "BMC_SELF_HW_RST")
	)
	(segment
		(start 64.096646 -139.204954)
		(end 64.08293 -139.21867)
		(width 0.127)
		(layer "In2.Cu")
		(net "BMC_SELF_HW_RST")
	)
	(segment
		(start 70.1294 -167.2336)
		(end 70.1294 -172.3898)
		(width 0.127)
		(layer "In2.Cu")
		(net "BMC_SELF_HW_RST")
	)
	(segment
		(start 68.4149 -165.5191)
		(end 70.1294 -167.2336)
		(width 0.127)
		(layer "In2.Cu")
		(net "BMC_SELF_HW_RST")
	)
	(segment
		(start 67.17284 -153.777696)
		(end 66.63944 -154.311096)
		(width 0.127)
		(layer "In2.Cu")
		(net "BMC_SELF_HW_RST")
	)
	(segment
		(start 66.31178 -150.217378)
		(end 67.17284 -151.078438)
		(width 0.127)
		(layer "In2.Cu")
		(net "BMC_SELF_HW_RST")
	)
	(segment
		(start 63.371984 -140.546582)
		(end 63.371984 -146.337274)
		(width 0.127)
		(layer "In2.Cu")
		(net "BMC_SELF_HW_RST")
	)
	(segment
		(start 65.5828 -135.357616)
		(end 65.5828 -137.437876)
		(width 0.127)
		(layer "In2.Cu")
		(net "BMC_SELF_HW_RST")
	)
	(segment
		(start 64.084454 -147.049744)
		(end 64.084454 -149.399752)
		(width 0.127)
		(layer "In2.Cu")
		(net "BMC_SELF_HW_RST")
	)
	(segment
		(start 64.90208 -150.217378)
		(end 66.31178 -150.217378)
		(width 0.127)
		(layer "In2.Cu")
		(net "BMC_SELF_HW_RST")
	)
	(segment
		(start 66.63944 -158.54172)
		(end 68.4149 -160.31718)
		(width 0.127)
		(layer "In2.Cu")
		(net "BMC_SELF_HW_RST")
	)
	(segment
		(start 67.17284 -151.078438)
		(end 67.17284 -153.777696)
		(width 0.127)
		(layer "In2.Cu")
		(net "BMC_SELF_HW_RST")
	)
	(segment
		(start 64.08293 -139.835636)
		(end 63.371984 -140.546582)
		(width 0.127)
		(layer "In2.Cu")
		(net "BMC_SELF_HW_RST")
	)
	(segment
		(start 58.10758 -135.537194)
		(end 59.152282 -134.492492)
		(width 0.127)
		(layer "In5.Cu")
		(net "BMC_SELF_HW_RST")
	)
	(segment
		(start 64.516762 -134.416292)
		(end 64.641476 -134.416292)
		(width 0.127)
		(layer "In5.Cu")
		(net "BMC_SELF_HW_RST")
	)
	(segment
		(start 43.705018 -135.763)
		(end 51.270662 -135.763)
		(width 0.127)
		(layer "In5.Cu")
		(net "BMC_SELF_HW_RST")
	)
	(segment
		(start 56.246522 -135.537194)
		(end 58.10758 -135.537194)
		(width 0.127)
		(layer "In5.Cu")
		(net "BMC_SELF_HW_RST")
	)
	(segment
		(start 55.982616 -135.8011)
		(end 56.246522 -135.537194)
		(width 0.127)
		(layer "In5.Cu")
		(net "BMC_SELF_HW_RST")
	)
	(segment
		(start 59.152282 -134.492492)
		(end 64.440562 -134.492492)
		(width 0.127)
		(layer "In5.Cu")
		(net "BMC_SELF_HW_RST")
	)
	(segment
		(start 64.440562 -134.492492)
		(end 64.516762 -134.416292)
		(width 0.127)
		(layer "In5.Cu")
		(net "BMC_SELF_HW_RST")
	)
	(segment
		(start 51.308762 -135.8011)
		(end 55.982616 -135.8011)
		(width 0.127)
		(layer "In5.Cu")
		(net "BMC_SELF_HW_RST")
	)
	(segment
		(start 51.270662 -135.763)
		(end 51.308762 -135.8011)
		(width 0.127)
		(layer "In5.Cu")
		(net "BMC_SELF_HW_RST")
	)
	(segment
		(start 43.664124 -135.803894)
		(end 43.705018 -135.763)
		(width 0.127)
		(layer "In5.Cu")
		(net "BMC_SELF_HW_RST")
	)
	(via
		(at 36.815522 -121.927874)
		(size 0.6096)
		(drill 0.3048)
		(layers "F.Cu" "B.Cu")
		(net "BMC_CPU_EN")
	)
	(segment
		(start 36.1569 -121.927874)
		(end 36.072826 -121.8438)
		(width 0.127)
		(layer "B.Cu")
		(net "BMC_CPU_EN")
	)
	(segment
		(start 36.815522 -121.105422)
		(end 36.4998 -120.7897)
		(width 0.127)
		(layer "B.Cu")
		(net "BMC_CPU_EN")
	)
	(segment
		(start 36.815522 -121.927874)
		(end 36.1569 -121.927874)
		(width 0.127)
		(layer "B.Cu")
		(net "BMC_CPU_EN")
	)
	(segment
		(start 36.815522 -121.927874)
		(end 36.815522 -121.105422)
		(width 0.127)
		(layer "B.Cu")
		(net "BMC_CPU_EN")
	)
	(segment
		(start 36.072826 -121.8438)
		(end 35.6743 -121.8438)
		(width 0.127)
		(layer "B.Cu")
		(net "BMC_CPU_EN")
	)
	(via
		(at 37.3634 -122.7836)
		(size 0.6096)
		(drill 0.3048)
		(layers "F.Cu" "B.Cu")
		(net "BMC_CPU_DIS")
	)
	(segment
		(start 37.592 -120.7897)
		(end 37.592 -122.555)
		(width 0.127)
		(layer "B.Cu")
		(net "BMC_CPU_DIS")
	)
	(segment
		(start 35.6743 -122.9106)
		(end 37.2364 -122.9106)
		(width 0.127)
		(layer "B.Cu")
		(net "BMC_CPU_DIS")
	)
	(segment
		(start 37.592 -122.555)
		(end 37.3634 -122.7836)
		(width 0.127)
		(layer "B.Cu")
		(net "BMC_CPU_DIS")
	)
	(segment
		(start 37.2364 -122.9106)
		(end 37.3634 -122.7836)
		(width 0.127)
		(layer "B.Cu")
		(net "BMC_CPU_DIS")
	)
	(segment
		(start 90.630756 -118.9101)
		(end 89.8398 -119.701056)
		(width 0.127)
		(layer "F.Cu")
		(net "UART_IOM_TX")
	)
	(segment
		(start 89.916508 -125.451108)
		(end 89.916508 -123.597416)
		(width 0.127)
		(layer "F.Cu")
		(net "UART_IOM_TX")
	)
	(segment
		(start 90.571828 -20.7518)
		(end 89.799922 -19.979894)
		(width 0.127)
		(layer "F.Cu")
		(net "UART_IOM_TX")
	)
	(segment
		(start 89.8398 -119.701056)
		(end 89.8398 -122.089672)
		(width 0.127)
		(layer "F.Cu")
		(net "UART_IOM_TX")
	)
	(segment
		(start 94.54388 -19.88312)
		(end 94.615 -19.812)
		(width 0.127)
		(layer "F.Cu")
		(net "UART_IOM_TX")
	)
	(segment
		(start 94.54388 -20.7518)
		(end 94.54388 -19.88312)
		(width 0.127)
		(layer "F.Cu")
		(net "UART_IOM_TX")
	)
	(segment
		(start 94.54388 -20.7518)
		(end 90.571828 -20.7518)
		(width 0.127)
		(layer "F.Cu")
		(net "UART_IOM_TX")
	)
	(segment
		(start 94.4118 -115.18265)
		(end 94.4118 -116.094256)
		(width 0.127)
		(layer "F.Cu")
		(net "UART_IOM_TX")
	)
	(segment
		(start 94.4118 -116.094256)
		(end 91.595956 -118.9101)
		(width 0.127)
		(layer "F.Cu")
		(net "UART_IOM_TX")
	)
	(segment
		(start 90.805 -126.355856)
		(end 90.805 -126.3396)
		(width 0.127)
		(layer "F.Cu")
		(net "UART_IOM_TX")
	)
	(segment
		(start 91.18981 -128.08331)
		(end 90.88247 -127.77597)
		(width 0.127)
		(layer "F.Cu")
		(net "UART_IOM_TX")
	)
	(segment
		(start 94.63405 -114.9604)
		(end 94.4118 -115.18265)
		(width 0.127)
		(layer "F.Cu")
		(net "UART_IOM_TX")
	)
	(segment
		(start 90.88247 -127.77597)
		(end 90.88247 -126.433326)
		(width 0.127)
		(layer "F.Cu")
		(net "UART_IOM_TX")
	)
	(segment
		(start 89.916508 -123.597416)
		(end 89.8398 -123.520708)
		(width 0.127)
		(layer "F.Cu")
		(net "UART_IOM_TX")
	)
	(segment
		(start 91.595956 -118.9101)
		(end 90.630756 -118.9101)
		(width 0.127)
		(layer "F.Cu")
		(net "UART_IOM_TX")
	)
	(segment
		(start 90.805 -126.3396)
		(end 89.916508 -125.451108)
		(width 0.127)
		(layer "F.Cu")
		(net "UART_IOM_TX")
	)
	(segment
		(start 90.88247 -126.433326)
		(end 90.805 -126.355856)
		(width 0.127)
		(layer "F.Cu")
		(net "UART_IOM_TX")
	)
	(segment
		(start 92.117164 -128.08331)
		(end 91.18981 -128.08331)
		(width 0.127)
		(layer "F.Cu")
		(net "UART_IOM_TX")
	)
	(segment
		(start 89.8398 -123.520708)
		(end 89.8398 -122.089672)
		(width 0.127)
		(layer "F.Cu")
		(net "UART_IOM_TX")
	)
	(via
		(at 92.117164 -128.08331)
		(size 0.508)
		(drill 0.254)
		(layers "F.Cu" "B.Cu")
		(net "UART_IOM_TX")
	)
	(via
		(at 94.615 -19.812)
		(size 0.508)
		(drill 0.254)
		(layers "F.Cu" "B.Cu")
		(net "UART_IOM_TX")
	)
	(via
		(at 94.63405 -114.9604)
		(size 0.508)
		(drill 0.254)
		(layers "F.Cu" "B.Cu")
		(net "UART_IOM_TX")
	)
	(via
		(at 89.8398 -122.089672)
		(size 0.6604)
		(drill 0.3302)
		(layers "F.Cu" "B.Cu")
		(net "UART_IOM_TX")
	)
	(segment
		(start 92.126054 -128.08331)
		(end 92.117164 -128.08331)
		(width 0.127)
		(layer "B.Cu")
		(net "UART_IOM_TX")
	)
	(segment
		(start 91.8845 -128.324864)
		(end 92.126054 -128.08331)
		(width 0.127)
		(layer "B.Cu")
		(net "UART_IOM_TX")
	)
	(segment
		(start 91.8845 -131.45516)
		(end 91.8845 -128.324864)
		(width 0.127)
		(layer "B.Cu")
		(net "UART_IOM_TX")
	)
	(segment
		(start 87.27313 -25.9842)
		(end 85.489542 -27.767788)
		(width 0.127)
		(layer "In5.Cu")
		(net "UART_IOM_TX")
	)
	(segment
		(start 82.2452 -96.811338)
		(end 83.020662 -97.5868)
		(width 0.127)
		(layer "In5.Cu")
		(net "UART_IOM_TX")
	)
	(segment
		(start 84.578444 -97.0661)
		(end 87.649812 -97.0661)
		(width 0.127)
		(layer "In5.Cu")
		(net "UART_IOM_TX")
	)
	(segment
		(start 85.489542 -27.767788)
		(end 85.489542 -40.391842)
		(width 0.127)
		(layer "In5.Cu")
		(net "UART_IOM_TX")
	)
	(segment
		(start 82.7659 -50.986944)
		(end 82.7659 -59.303412)
		(width 0.127)
		(layer "In5.Cu")
		(net "UART_IOM_TX")
	)
	(segment
		(start 94.361 -103.777288)
		(end 94.361 -114.68735)
		(width 0.127)
		(layer "In5.Cu")
		(net "UART_IOM_TX")
	)
	(segment
		(start 87.649812 -97.0661)
		(end 94.361 -103.777288)
		(width 0.127)
		(layer "In5.Cu")
		(net "UART_IOM_TX")
	)
	(segment
		(start 82.2452 -59.824112)
		(end 82.2452 -96.811338)
		(width 0.127)
		(layer "In5.Cu")
		(net "UART_IOM_TX")
	)
	(segment
		(start 94.361 -114.68735)
		(end 94.63405 -114.9604)
		(width 0.127)
		(layer "In5.Cu")
		(net "UART_IOM_TX")
	)
	(segment
		(start 94.0308 -20.3962)
		(end 94.0308 -23.3934)
		(width 0.127)
		(layer "In5.Cu")
		(net "UART_IOM_TX")
	)
	(segment
		(start 94.0308 -23.3934)
		(end 94.488 -23.8506)
		(width 0.127)
		(layer "In5.Cu")
		(net "UART_IOM_TX")
	)
	(segment
		(start 85.489542 -40.391842)
		(end 82.1944 -43.686984)
		(width 0.127)
		(layer "In5.Cu")
		(net "UART_IOM_TX")
	)
	(segment
		(start 82.1944 -50.415444)
		(end 82.7659 -50.986944)
		(width 0.127)
		(layer "In5.Cu")
		(net "UART_IOM_TX")
	)
	(segment
		(start 94.488 -25.035256)
		(end 93.539056 -25.9842)
		(width 0.127)
		(layer "In5.Cu")
		(net "UART_IOM_TX")
	)
	(segment
		(start 93.539056 -25.9842)
		(end 87.27313 -25.9842)
		(width 0.127)
		(layer "In5.Cu")
		(net "UART_IOM_TX")
	)
	(segment
		(start 94.488 -23.8506)
		(end 94.488 -25.035256)
		(width 0.127)
		(layer "In5.Cu")
		(net "UART_IOM_TX")
	)
	(segment
		(start 83.020662 -97.5868)
		(end 84.057744 -97.5868)
		(width 0.127)
		(layer "In5.Cu")
		(net "UART_IOM_TX")
	)
	(segment
		(start 82.7659 -59.303412)
		(end 82.2452 -59.824112)
		(width 0.127)
		(layer "In5.Cu")
		(net "UART_IOM_TX")
	)
	(segment
		(start 82.1944 -43.686984)
		(end 82.1944 -50.415444)
		(width 0.127)
		(layer "In5.Cu")
		(net "UART_IOM_TX")
	)
	(segment
		(start 94.615 -19.812)
		(end 94.0308 -20.3962)
		(width 0.127)
		(layer "In5.Cu")
		(net "UART_IOM_TX")
	)
	(segment
		(start 84.057744 -97.5868)
		(end 84.578444 -97.0661)
		(width 0.127)
		(layer "In5.Cu")
		(net "UART_IOM_TX")
	)
	(segment
		(start 89.1286 -123.278392)
		(end 89.1286 -119.514112)
		(width 0.127)
		(layer "F.Cu")
		(net "UART_IOM_RX")
	)
	(segment
		(start 93.6498 -21.9202)
		(end 93.1164 -21.3868)
		(width 0.127)
		(layer "F.Cu")
		(net "UART_IOM_RX")
	)
	(segment
		(start 90.393012 -21.3868)
		(end 89.799922 -21.97989)
		(width 0.127)
		(layer "F.Cu")
		(net "UART_IOM_RX")
	)
	(segment
		(start 93.1164 -21.3868)
		(end 90.393012 -21.3868)
		(width 0.127)
		(layer "F.Cu")
		(net "UART_IOM_RX")
	)
	(segment
		(start 89.1286 -123.278392)
		(end 89.1286 -123.803918)
		(width 0.127)
		(layer "F.Cu")
		(net "UART_IOM_RX")
	)
	(segment
		(start 89.1286 -119.514112)
		(end 90.367612 -118.2751)
		(width 0.127)
		(layer "F.Cu")
		(net "UART_IOM_RX")
	)
	(segment
		(start 89.9922 -126.4412)
		(end 89.9922 -127.06223)
		(width 0.127)
		(layer "F.Cu")
		(net "UART_IOM_RX")
	)
	(segment
		(start 89.1286 -123.803918)
		(end 89.281508 -123.956826)
		(width 0.127)
		(layer "F.Cu")
		(net "UART_IOM_RX")
	)
	(segment
		(start 94.984824 -114.1984)
		(end 95.00362 -114.179604)
		(width 0.127)
		(layer "F.Cu")
		(net "UART_IOM_RX")
	)
	(segment
		(start 94.54388 -21.9202)
		(end 93.6498 -21.9202)
		(width 0.127)
		(layer "F.Cu")
		(net "UART_IOM_RX")
	)
	(segment
		(start 91.332812 -118.2751)
		(end 93.6117 -115.996212)
		(width 0.127)
		(layer "F.Cu")
		(net "UART_IOM_RX")
	)
	(segment
		(start 94.54388 -21.9202)
		(end 94.54388 -22.78888)
		(width 0.127)
		(layer "F.Cu")
		(net "UART_IOM_RX")
	)
	(segment
		(start 89.281508 -125.730508)
		(end 89.9922 -126.4412)
		(width 0.127)
		(layer "F.Cu")
		(net "UART_IOM_RX")
	)
	(segment
		(start 89.281508 -123.956826)
		(end 89.281508 -125.730508)
		(width 0.127)
		(layer "F.Cu")
		(net "UART_IOM_RX")
	)
	(segment
		(start 94.724982 -114.457988)
		(end 94.98457 -114.1984)
		(width 0.127)
		(layer "F.Cu")
		(net "UART_IOM_RX")
	)
	(segment
		(start 93.974412 -114.457988)
		(end 94.724982 -114.457988)
		(width 0.127)
		(layer "F.Cu")
		(net "UART_IOM_RX")
	)
	(segment
		(start 94.54388 -22.78888)
		(end 94.615 -22.86)
		(width 0.127)
		(layer "F.Cu")
		(net "UART_IOM_RX")
	)
	(segment
		(start 94.98457 -114.1984)
		(end 94.984824 -114.1984)
		(width 0.127)
		(layer "F.Cu")
		(net "UART_IOM_RX")
	)
	(segment
		(start 93.6117 -115.996212)
		(end 93.6117 -114.8207)
		(width 0.127)
		(layer "F.Cu")
		(net "UART_IOM_RX")
	)
	(segment
		(start 93.6117 -114.8207)
		(end 93.974412 -114.457988)
		(width 0.127)
		(layer "F.Cu")
		(net "UART_IOM_RX")
	)
	(segment
		(start 90.367612 -118.2751)
		(end 91.332812 -118.2751)
		(width 0.127)
		(layer "F.Cu")
		(net "UART_IOM_RX")
	)
	(via
		(at 89.1286 -123.278392)
		(size 0.6604)
		(drill 0.3302)
		(layers "F.Cu" "B.Cu")
		(net "UART_IOM_RX")
	)
	(via
		(at 89.9922 -127.06223)
		(size 0.508)
		(drill 0.254)
		(layers "F.Cu" "B.Cu")
		(net "UART_IOM_RX")
	)
	(via
		(at 95.00362 -114.179604)
		(size 0.508)
		(drill 0.254)
		(layers "F.Cu" "B.Cu")
		(net "UART_IOM_RX")
	)
	(via
		(at 94.615 -22.86)
		(size 0.508)
		(drill 0.254)
		(layers "F.Cu" "B.Cu")
		(net "UART_IOM_RX")
	)
	(segment
		(start 89.187528 -130.451098)
		(end 89.2175 -130.421126)
		(width 0.127)
		(layer "B.Cu")
		(net "UART_IOM_RX")
	)
	(segment
		(start 87.89416 -133.218682)
		(end 87.89416 -131.741418)
		(width 0.127)
		(layer "B.Cu")
		(net "UART_IOM_RX")
	)
	(segment
		(start 89.18448 -130.451098)
		(end 89.187528 -130.451098)
		(width 0.127)
		(layer "B.Cu")
		(net "UART_IOM_RX")
	)
	(segment
		(start 87.89416 -131.741418)
		(end 89.18448 -130.451098)
		(width 0.127)
		(layer "B.Cu")
		(net "UART_IOM_RX")
	)
	(segment
		(start 89.2175 -127.83693)
		(end 89.9922 -127.06223)
		(width 0.127)
		(layer "B.Cu")
		(net "UART_IOM_RX")
	)
	(segment
		(start 89.2175 -130.421126)
		(end 89.2175 -127.83693)
		(width 0.127)
		(layer "B.Cu")
		(net "UART_IOM_RX")
	)
	(segment
		(start 89.894664 -135.2296)
		(end 89.894664 -135.219186)
		(width 0.127)
		(layer "B.Cu")
		(net "UART_IOM_RX")
	)
	(segment
		(start 92.76842 -135.2296)
		(end 89.894664 -135.2296)
		(width 0.127)
		(layer "B.Cu")
		(net "UART_IOM_RX")
	)
	(segment
		(start 89.894664 -135.219186)
		(end 87.89416 -133.218682)
		(width 0.127)
		(layer "B.Cu")
		(net "UART_IOM_RX")
	)
	(segment
		(start 95.123 -25.2984)
		(end 93.3704 -27.051)
		(width 0.127)
		(layer "In5.Cu")
		(net "UART_IOM_RX")
	)
	(segment
		(start 83.4009 -59.70524)
		(end 82.8802 -60.22594)
		(width 0.127)
		(layer "In5.Cu")
		(net "UART_IOM_RX")
	)
	(segment
		(start 94.615 -22.86)
		(end 95.123 -23.368)
		(width 0.127)
		(layer "In5.Cu")
		(net "UART_IOM_RX")
	)
	(segment
		(start 87.912956 -96.4311)
		(end 95.00362 -103.521764)
		(width 0.127)
		(layer "In5.Cu")
		(net "UART_IOM_RX")
	)
	(segment
		(start 95.00362 -103.521764)
		(end 95.00362 -114.179604)
		(width 0.127)
		(layer "In5.Cu")
		(net "UART_IOM_RX")
	)
	(segment
		(start 95.123 -23.368)
		(end 95.123 -25.2984)
		(width 0.127)
		(layer "In5.Cu")
		(net "UART_IOM_RX")
	)
	(segment
		(start 83.7946 -96.9518)
		(end 84.3153 -96.4311)
		(width 0.127)
		(layer "In5.Cu")
		(net "UART_IOM_RX")
	)
	(segment
		(start 82.8802 -96.548194)
		(end 83.283806 -96.9518)
		(width 0.127)
		(layer "In5.Cu")
		(net "UART_IOM_RX")
	)
	(segment
		(start 83.4009 -50.7238)
		(end 83.4009 -59.70524)
		(width 0.127)
		(layer "In5.Cu")
		(net "UART_IOM_RX")
	)
	(segment
		(start 82.8294 -44.167806)
		(end 82.8294 -50.1523)
		(width 0.127)
		(layer "In5.Cu")
		(net "UART_IOM_RX")
	)
	(segment
		(start 93.3704 -27.051)
		(end 89.144856 -27.051)
		(width 0.127)
		(layer "In5.Cu")
		(net "UART_IOM_RX")
	)
	(segment
		(start 89.144856 -27.051)
		(end 87.066374 -29.129482)
		(width 0.127)
		(layer "In5.Cu")
		(net "UART_IOM_RX")
	)
	(segment
		(start 84.3153 -96.4311)
		(end 87.912956 -96.4311)
		(width 0.127)
		(layer "In5.Cu")
		(net "UART_IOM_RX")
	)
	(segment
		(start 83.283806 -96.9518)
		(end 83.7946 -96.9518)
		(width 0.127)
		(layer "In5.Cu")
		(net "UART_IOM_RX")
	)
	(segment
		(start 87.066374 -29.129482)
		(end 87.066374 -39.930832)
		(width 0.127)
		(layer "In5.Cu")
		(net "UART_IOM_RX")
	)
	(segment
		(start 82.8802 -60.22594)
		(end 82.8802 -96.548194)
		(width 0.127)
		(layer "In5.Cu")
		(net "UART_IOM_RX")
	)
	(segment
		(start 87.066374 -39.930832)
		(end 82.8294 -44.167806)
		(width 0.127)
		(layer "In5.Cu")
		(net "UART_IOM_RX")
	)
	(segment
		(start 82.8294 -50.1523)
		(end 83.4009 -50.7238)
		(width 0.127)
		(layer "In5.Cu")
		(net "UART_IOM_RX")
	)
	(segment
		(start 92.2274 -144.399)
		(end 91.6178 -144.399)
		(width 0.127)
		(layer "F.Cu")
		(net "TCA9555_A2")
	)
	(segment
		(start 92.799662 -144.971262)
		(end 92.2274 -144.399)
		(width 0.127)
		(layer "F.Cu")
		(net "TCA9555_A2")
	)
	(segment
		(start 92.952062 -144.971262)
		(end 92.799662 -144.971262)
		(width 0.127)
		(layer "F.Cu")
		(net "TCA9555_A2")
	)
	(segment
		(start 91.087194 -144.929606)
		(end 90.357706 -144.929606)
		(width 0.127)
		(layer "F.Cu")
		(net "TCA9555_A2")
	)
	(segment
		(start 91.6178 -144.399)
		(end 91.087194 -144.929606)
		(width 0.127)
		(layer "F.Cu")
		(net "TCA9555_A2")
	)
	(via
		(at 92.952062 -144.971262)
		(size 0.508)
		(drill 0.254)
		(layers "F.Cu" "B.Cu")
		(net "TCA9555_A2")
	)
	(via
		(at 95.25 -145.5928)
		(size 0.6096)
		(drill 0.3048)
		(layers "F.Cu" "B.Cu")
		(net "TCA9555_A2")
	)
	(segment
		(start 94.876366 -144.92351)
		(end 92.999814 -144.92351)
		(width 0.127)
		(layer "B.Cu")
		(net "TCA9555_A2")
	)
	(segment
		(start 94.9071 -145.9357)
		(end 93.9292 -145.9357)
		(width 0.127)
		(layer "B.Cu")
		(net "TCA9555_A2")
	)
	(segment
		(start 92.9005 -145.022824)
		(end 92.9005 -146.0246)
		(width 0.127)
		(layer "B.Cu")
		(net "TCA9555_A2")
	)
	(segment
		(start 95.25 -145.5928)
		(end 94.9071 -145.9357)
		(width 0.127)
		(layer "B.Cu")
		(net "TCA9555_A2")
	)
	(segment
		(start 92.952062 -144.971262)
		(end 92.9005 -145.022824)
		(width 0.127)
		(layer "B.Cu")
		(net "TCA9555_A2")
	)
	(segment
		(start 92.999814 -144.92351)
		(end 92.952062 -144.971262)
		(width 0.127)
		(layer "B.Cu")
		(net "TCA9555_A2")
	)
	(segment
		(start 95.25 -145.5928)
		(end 95.25 -145.297144)
		(width 0.127)
		(layer "B.Cu")
		(net "TCA9555_A2")
	)
	(segment
		(start 95.25 -145.297144)
		(end 94.876366 -144.92351)
		(width 0.127)
		(layer "B.Cu")
		(net "TCA9555_A2")
	)
	(segment
		(start 88.563196 -145.789396)
		(end 88.782398 -146.008598)
		(width 0.127)
		(layer "F.Cu")
		(net "TCA9555_A1")
	)
	(segment
		(start 88.563196 -145.287746)
		(end 88.563196 -145.789396)
		(width 0.127)
		(layer "F.Cu")
		(net "TCA9555_A1")
	)
	(segment
		(start 88.782398 -146.008598)
		(end 89.089484 -146.008598)
		(width 0.127)
		(layer "F.Cu")
		(net "TCA9555_A1")
	)
	(segment
		(start 88.740742 -145.1102)
		(end 88.563196 -145.287746)
		(width 0.127)
		(layer "F.Cu")
		(net "TCA9555_A1")
	)
	(segment
		(start 89.281 -145.1102)
		(end 88.740742 -145.1102)
		(width 0.127)
		(layer "F.Cu")
		(net "TCA9555_A1")
	)
	(segment
		(start 89.750646 -145.579846)
		(end 89.281 -145.1102)
		(width 0.127)
		(layer "F.Cu")
		(net "TCA9555_A1")
	)
	(segment
		(start 90.357706 -145.579846)
		(end 89.750646 -145.579846)
		(width 0.127)
		(layer "F.Cu")
		(net "TCA9555_A1")
	)
	(via
		(at 88.740742 -145.1102)
		(size 0.6604)
		(drill 0.3302)
		(layers "F.Cu" "B.Cu")
		(net "TCA9555_A1")
	)
	(via
		(at 89.089484 -146.008598)
		(size 0.508)
		(drill 0.254)
		(layers "F.Cu" "B.Cu")
		(net "TCA9555_A1")
	)
	(segment
		(start 89.073482 -146.0246)
		(end 89.089484 -146.008598)
		(width 0.127)
		(layer "B.Cu")
		(net "TCA9555_A1")
	)
	(segment
		(start 88.3031 -146.0246)
		(end 88.3031 -147.124674)
		(width 0.127)
		(layer "B.Cu")
		(net "TCA9555_A1")
	)
	(segment
		(start 88.3031 -146.0246)
		(end 89.073482 -146.0246)
		(width 0.127)
		(layer "B.Cu")
		(net "TCA9555_A1")
	)
	(segment
		(start 95.996506 -144.279366)
		(end 96.94418 -144.279366)
		(width 0.127)
		(layer "F.Cu")
		(net "TCA9555_A0")
	)
	(segment
		(start 98.676206 -141.22019)
		(end 98.676206 -142.134336)
		(width 0.127)
		(layer "F.Cu")
		(net "TCA9555_A0")
	)
	(segment
		(start 98.1329 -142.677642)
		(end 98.1329 -143.3576)
		(width 0.127)
		(layer "F.Cu")
		(net "TCA9555_A0")
	)
	(segment
		(start 97.202498 -144.021048)
		(end 97.508822 -144.021048)
		(width 0.127)
		(layer "F.Cu")
		(net "TCA9555_A0")
	)
	(segment
		(start 98.676206 -142.134336)
		(end 98.429318 -142.381224)
		(width 0.127)
		(layer "F.Cu")
		(net "TCA9555_A0")
	)
	(segment
		(start 98.429318 -142.381224)
		(end 98.1329 -142.677642)
		(width 0.127)
		(layer "F.Cu")
		(net "TCA9555_A0")
	)
	(segment
		(start 98.1329 -143.39697)
		(end 98.1329 -143.3576)
		(width 0.127)
		(layer "F.Cu")
		(net "TCA9555_A0")
	)
	(segment
		(start 97.508822 -144.021048)
		(end 98.1329 -143.39697)
		(width 0.127)
		(layer "F.Cu")
		(net "TCA9555_A0")
	)
	(segment
		(start 96.94418 -144.279366)
		(end 97.202498 -144.021048)
		(width 0.127)
		(layer "F.Cu")
		(net "TCA9555_A0")
	)
	(via
		(at 98.429318 -142.381224)
		(size 0.6604)
		(drill 0.3302)
		(layers "F.Cu" "B.Cu")
		(net "TCA9555_A0")
	)
	(segment
		(start 91.651328 -49.0728)
		(end 92.7735 -49.0728)
		(width 0.508)
		(layer "F.Cu")
		(net "P12V_STBY")
	)
	(segment
		(start 91.537028 -49.1871)
		(end 91.651328 -49.0728)
		(width 0.508)
		(layer "F.Cu")
		(net "P12V_STBY")
	)
	(segment
		(start 39.585646 -176.69891)
		(end 40.099996 -176.69891)
		(width 0.508)
		(layer "F.Cu")
		(net "P12V_STBY")
	)
	(segment
		(start 214.277194 -41.955212)
		(end 213.997794 -41.675812)
		(width 0.508)
		(layer "F.Cu")
		(net "P12V_STBY")
	)
	(segment
		(start 40.099996 -176.69891)
		(end 40.384476 -176.41443)
		(width 0.508)
		(layer "F.Cu")
		(net "P12V_STBY")
	)
	(segment
		(start 215.026494 -41.955212)
		(end 214.277194 -41.955212)
		(width 0.508)
		(layer "F.Cu")
		(net "P12V_STBY")
	)
	(segment
		(start 92.7735 -49.0728)
		(end 92.9132 -49.2125)
		(width 0.508)
		(layer "F.Cu")
		(net "P12V_STBY")
	)
	(via
		(at 132.459222 -10.55243)
		(size 0.7112)
		(drill 0.4064)
		(layers "F.Cu" "B.Cu")
		(net "P12V_STBY")
	)
	(via
		(at 131.240022 -10.55243)
		(size 0.7112)
		(drill 0.4064)
		(layers "F.Cu" "B.Cu")
		(net "P12V_STBY")
	)
	(via
		(at 227.591874 -59.300872)
		(size 0.7112)
		(drill 0.4064)
		(layers "F.Cu" "B.Cu")
		(net "P12V_STBY")
	)
	(via
		(at 227.861114 -93.826838)
		(size 0.7112)
		(drill 0.4064)
		(layers "F.Cu" "B.Cu")
		(net "P12V_STBY")
	)
	(via
		(at 226.321874 -56.760872)
		(size 0.7112)
		(drill 0.4064)
		(layers "F.Cu" "B.Cu")
		(net "P12V_STBY")
	)
	(via
		(at 229.131114 -96.366838)
		(size 0.7112)
		(drill 0.4064)
		(layers "F.Cu" "B.Cu")
		(net "P12V_STBY")
	)
	(via
		(at 149.407118 -18.947384)
		(size 0.7112)
		(drill 0.4064)
		(layers "F.Cu" "B.Cu")
		(net "P12V_STBY")
	)
	(via
		(at 226.321874 -60.570872)
		(size 0.7112)
		(drill 0.4064)
		(layers "F.Cu" "B.Cu")
		(net "P12V_STBY")
	)
	(via
		(at 92.9132 -49.2125)
		(size 0.508)
		(drill 0.254)
		(layers "F.Cu" "B.Cu")
		(net "P12V_STBY")
	)
	(via
		(at 226.321874 -59.300872)
		(size 0.7112)
		(drill 0.4064)
		(layers "F.Cu" "B.Cu")
		(net "P12V_STBY")
	)
	(via
		(at 131.240022 -11.77163)
		(size 0.7112)
		(drill 0.4064)
		(layers "F.Cu" "B.Cu")
		(net "P12V_STBY")
	)
	(via
		(at 228.4476 -59.8678)
		(size 0.6096)
		(drill 0.3048)
		(layers "F.Cu" "B.Cu")
		(net "P12V_STBY")
	)
	(via
		(at 227.591874 -56.760872)
		(size 0.7112)
		(drill 0.4064)
		(layers "F.Cu" "B.Cu")
		(net "P12V_STBY")
	)
	(via
		(at 52.2732 -177.3936)
		(size 0.508)
		(drill 0.254)
		(layers "F.Cu" "B.Cu")
		(net "P12V_STBY")
	)
	(via
		(at 132.459222 -11.77163)
		(size 0.7112)
		(drill 0.4064)
		(layers "F.Cu" "B.Cu")
		(net "P12V_STBY")
	)
	(via
		(at 225.480372 -95.295212)
		(size 0.6096)
		(drill 0.3048)
		(layers "F.Cu" "B.Cu")
		(net "P12V_STBY")
	)
	(via
		(at 129.24917 -10.38987)
		(size 0.6096)
		(drill 0.3048)
		(layers "F.Cu" "B.Cu")
		(net "P12V_STBY")
	)
	(via
		(at 133.73862 -11.11885)
		(size 0.7112)
		(drill 0.4064)
		(layers "F.Cu" "B.Cu")
		(net "P12V_STBY")
	)
	(via
		(at 213.997794 -41.675812)
		(size 0.508)
		(drill 0.254)
		(layers "F.Cu" "B.Cu")
		(net "P12V_STBY")
	)
	(via
		(at 40.384476 -176.41443)
		(size 0.508)
		(drill 0.254)
		(layers "F.Cu" "B.Cu")
		(net "P12V_STBY")
	)
	(via
		(at 229.131114 -95.096838)
		(size 0.7112)
		(drill 0.4064)
		(layers "F.Cu" "B.Cu")
		(net "P12V_STBY")
	)
	(via
		(at 134.627874 -8.146034)
		(size 0.6096)
		(drill 0.3048)
		(layers "F.Cu" "B.Cu")
		(net "P12V_STBY")
	)
	(via
		(at 22.74824 -180.8988)
		(size 0.6096)
		(drill 0.3048)
		(layers "F.Cu" "B.Cu")
		(net "P12V_STBY")
	)
	(via
		(at 21.11375 -182.68696)
		(size 0.7112)
		(drill 0.4064)
		(layers "F.Cu" "B.Cu")
		(net "P12V_STBY")
	)
	(via
		(at 23.902924 -177.719482)
		(size 0.508)
		(drill 0.254)
		(layers "F.Cu" "B.Cu")
		(net "P12V_STBY")
	)
	(via
		(at 226.321874 -58.030872)
		(size 0.7112)
		(drill 0.4064)
		(layers "F.Cu" "B.Cu")
		(net "P12V_STBY")
	)
	(via
		(at 77.567028 -48.304196)
		(size 0.7112)
		(drill 0.4064)
		(layers "F.Cu" "B.Cu")
		(net "P12V_STBY")
	)
	(via
		(at 131.240022 -9.33323)
		(size 0.7112)
		(drill 0.4064)
		(layers "F.Cu" "B.Cu")
		(net "P12V_STBY")
	)
	(via
		(at 131.240022 -8.11403)
		(size 0.7112)
		(drill 0.4064)
		(layers "F.Cu" "B.Cu")
		(net "P12V_STBY")
	)
	(via
		(at 138.254486 -10.067036)
		(size 0.6096)
		(drill 0.3048)
		(layers "F.Cu" "B.Cu")
		(net "P12V_STBY")
	)
	(via
		(at 150.626318 -17.728184)
		(size 0.7112)
		(drill 0.4064)
		(layers "F.Cu" "B.Cu")
		(net "P12V_STBY")
	)
	(via
		(at 227.591874 -60.570872)
		(size 0.7112)
		(drill 0.4064)
		(layers "F.Cu" "B.Cu")
		(net "P12V_STBY")
	)
	(via
		(at 149.407118 -17.728184)
		(size 0.7112)
		(drill 0.4064)
		(layers "F.Cu" "B.Cu")
		(net "P12V_STBY")
	)
	(via
		(at 143.15948 -15.28064)
		(size 0.6096)
		(drill 0.3048)
		(layers "F.Cu" "B.Cu")
		(net "P12V_STBY")
	)
	(via
		(at 227.861114 -96.366838)
		(size 0.7112)
		(drill 0.4064)
		(layers "F.Cu" "B.Cu")
		(net "P12V_STBY")
	)
	(via
		(at 132.459222 -9.33323)
		(size 0.7112)
		(drill 0.4064)
		(layers "F.Cu" "B.Cu")
		(net "P12V_STBY")
	)
	(via
		(at 227.591874 -58.030872)
		(size 0.7112)
		(drill 0.4064)
		(layers "F.Cu" "B.Cu")
		(net "P12V_STBY")
	)
	(via
		(at 77.694028 -49.650396)
		(size 0.7112)
		(drill 0.4064)
		(layers "F.Cu" "B.Cu")
		(net "P12V_STBY")
	)
	(via
		(at 147.106132 -18.595848)
		(size 0.6096)
		(drill 0.3048)
		(layers "F.Cu" "B.Cu")
		(net "P12V_STBY")
	)
	(via
		(at 54.763924 -163.9062)
		(size 0.508)
		(drill 0.254)
		(layers "F.Cu" "B.Cu")
		(net "P12V_STBY")
	)
	(via
		(at 132.459222 -8.11403)
		(size 0.7112)
		(drill 0.4064)
		(layers "F.Cu" "B.Cu")
		(net "P12V_STBY")
	)
	(via
		(at 229.131114 -93.826838)
		(size 0.7112)
		(drill 0.4064)
		(layers "F.Cu" "B.Cu")
		(net "P12V_STBY")
	)
	(via
		(at 21.11375 -183.90616)
		(size 0.7112)
		(drill 0.4064)
		(layers "F.Cu" "B.Cu")
		(net "P12V_STBY")
	)
	(via
		(at 227.861114 -95.096838)
		(size 0.7112)
		(drill 0.4064)
		(layers "F.Cu" "B.Cu")
		(net "P12V_STBY")
	)
	(segment
		(start 21.11375 -181.60365)
		(end 21.11375 -182.68696)
		(width 0.508)
		(layer "B.Cu")
		(net "P12V_STBY")
	)
	(segment
		(start 24.5618 -180.8988)
		(end 22.74824 -180.8988)
		(width 0.508)
		(layer "B.Cu")
		(net "P12V_STBY")
	)
	(segment
		(start 21.8186 -180.8988)
		(end 21.11375 -181.60365)
		(width 0.508)
		(layer "B.Cu")
		(net "P12V_STBY")
	)
	(segment
		(start 54.763924 -163.234624)
		(end 54.6481 -163.1188)
		(width 0.508)
		(layer "B.Cu")
		(net "P12V_STBY")
	)
	(segment
		(start 22.74824 -180.8988)
		(end 21.8186 -180.8988)
		(width 0.508)
		(layer "B.Cu")
		(net "P12V_STBY")
	)
	(segment
		(start 54.763924 -163.9062)
		(end 54.763924 -163.234624)
		(width 0.508)
		(layer "B.Cu")
		(net "P12V_STBY")
	)
	(segment
		(start 54.763924 -174.980092)
		(end 52.350416 -177.3936)
		(width 0.508)
		(layer "In2.Cu")
		(net "P12V_STBY")
	)
	(segment
		(start 54.763924 -163.9062)
		(end 54.763924 -174.980092)
		(width 0.508)
		(layer "In2.Cu")
		(net "P12V_STBY")
	)
	(segment
		(start 52.350416 -177.3936)
		(end 52.2732 -177.3936)
		(width 0.508)
		(layer "In2.Cu")
		(net "P12V_STBY")
	)
	(segment
		(start 28.991814 -174.135034)
		(end 25.407366 -177.719482)
		(width 0.508)
		(layer "In5.Cu")
		(net "P12V_STBY")
	)
	(segment
		(start 43.015408 -176.23409)
		(end 43.015154 -176.233836)
		(width 0.508)
		(layer "In5.Cu")
		(net "P12V_STBY")
	)
	(segment
		(start 36.100258 -174.135034)
		(end 28.991814 -174.135034)
		(width 0.508)
		(layer "In5.Cu")
		(net "P12V_STBY")
	)
	(segment
		(start 40.326056 -176.35601)
		(end 38.321234 -176.35601)
		(width 0.508)
		(layer "In5.Cu")
		(net "P12V_STBY")
	)
	(segment
		(start 50.0634 -175.9966)
		(end 44.782994 -175.9966)
		(width 0.508)
		(layer "In5.Cu")
		(net "P12V_STBY")
	)
	(segment
		(start 42.467276 -176.23409)
		(end 40.564816 -176.23409)
		(width 0.508)
		(layer "In5.Cu")
		(net "P12V_STBY")
	)
	(segment
		(start 38.321234 -176.35601)
		(end 36.100258 -174.135034)
		(width 0.508)
		(layer "In5.Cu")
		(net "P12V_STBY")
	)
	(segment
		(start 25.407366 -177.719482)
		(end 23.902924 -177.719482)
		(width 0.508)
		(layer "In5.Cu")
		(net "P12V_STBY")
	)
	(segment
		(start 44.782994 -175.9966)
		(end 44.545504 -176.23409)
		(width 0.508)
		(layer "In5.Cu")
		(net "P12V_STBY")
	)
	(segment
		(start 52.2732 -177.3936)
		(end 51.4604 -177.3936)
		(width 0.508)
		(layer "In5.Cu")
		(net "P12V_STBY")
	)
	(segment
		(start 51.4604 -177.3936)
		(end 50.0634 -175.9966)
		(width 0.508)
		(layer "In5.Cu")
		(net "P12V_STBY")
	)
	(segment
		(start 40.384476 -176.41443)
		(end 40.326056 -176.35601)
		(width 0.508)
		(layer "In5.Cu")
		(net "P12V_STBY")
	)
	(segment
		(start 42.46753 -176.233836)
		(end 42.467276 -176.23409)
		(width 0.508)
		(layer "In5.Cu")
		(net "P12V_STBY")
	)
	(segment
		(start 40.564816 -176.23409)
		(end 40.384476 -176.41443)
		(width 0.508)
		(layer "In5.Cu")
		(net "P12V_STBY")
	)
	(segment
		(start 43.015154 -176.233836)
		(end 42.46753 -176.233836)
		(width 0.508)
		(layer "In5.Cu")
		(net "P12V_STBY")
	)
	(segment
		(start 44.545504 -176.23409)
		(end 43.015408 -176.23409)
		(width 0.508)
		(layer "In5.Cu")
		(net "P12V_STBY")
	)
	(segment
		(start 117.942868 -12.92987)
		(end 118.121938 -12.7508)
		(width 0.254)
		(layer "F.Cu")
		(net "MB0_VCC")
	)
	(segment
		(start 117.942868 -13.667232)
		(end 116.964206 -13.667232)
		(width 0.254)
		(layer "F.Cu")
		(net "MB0_VCC")
	)
	(segment
		(start 115.897152 -13.848588)
		(end 116.758974 -13.848588)
		(width 0.254)
		(layer "F.Cu")
		(net "MB0_VCC")
	)
	(segment
		(start 117.942868 -13.667232)
		(end 117.942868 -12.92987)
		(width 0.254)
		(layer "F.Cu")
		(net "MB0_VCC")
	)
	(segment
		(start 116.758974 -13.848588)
		(end 116.952268 -13.655294)
		(width 0.254)
		(layer "F.Cu")
		(net "MB0_VCC")
	)
	(segment
		(start 116.964206 -13.667232)
		(end 116.952268 -13.655294)
		(width 0.254)
		(layer "F.Cu")
		(net "MB0_VCC")
	)
	(segment
		(start 118.121938 -12.7508)
		(end 118.121938 -11.4681)
		(width 0.254)
		(layer "F.Cu")
		(net "MB0_VCC")
	)
	(via
		(at 116.952268 -13.655294)
		(size 0.6604)
		(drill 0.3302)
		(layers "F.Cu" "B.Cu")
		(net "MB0_VCC")
	)
	(segment
		(start 112.220248 -12.674854)
		(end 112.220248 -12.69111)
		(width 0.127)
		(layer "F.Cu")
		(net "MB0_VCAP_R")
	)
	(segment
		(start 114.676174 -11.495278)
		(end 113.849404 -11.495278)
		(width 0.127)
		(layer "F.Cu")
		(net "MB0_VCAP_R")
	)
	(segment
		(start 113.37163 -11.495278)
		(end 113.220754 -11.646154)
		(width 0.127)
		(layer "F.Cu")
		(net "MB0_VCAP_R")
	)
	(segment
		(start 112.220248 -12.69111)
		(end 112.638078 -12.69111)
		(width 0.127)
		(layer "F.Cu")
		(net "MB0_VCAP_R")
	)
	(segment
		(start 113.849404 -11.495278)
		(end 113.37163 -11.495278)
		(width 0.127)
		(layer "F.Cu")
		(net "MB0_VCAP_R")
	)
	(segment
		(start 112.646206 -11.646154)
		(end 112.646206 -12.682982)
		(width 0.127)
		(layer "F.Cu")
		(net "MB0_VCAP_R")
	)
	(segment
		(start 113.308638 -12.69111)
		(end 113.597182 -12.402566)
		(width 0.127)
		(layer "F.Cu")
		(net "MB0_VCAP_R")
	)
	(segment
		(start 116.3955 -10.241534)
		(end 115.929918 -10.241534)
		(width 0.127)
		(layer "F.Cu")
		(net "MB0_VCAP_R")
	)
	(segment
		(start 112.638078 -12.69111)
		(end 113.308638 -12.69111)
		(width 0.127)
		(layer "F.Cu")
		(net "MB0_VCAP_R")
	)
	(segment
		(start 112.646206 -12.682982)
		(end 112.638078 -12.69111)
		(width 0.127)
		(layer "F.Cu")
		(net "MB0_VCAP_R")
	)
	(segment
		(start 111.51997 -11.974576)
		(end 112.220248 -12.674854)
		(width 0.127)
		(layer "F.Cu")
		(net "MB0_VCAP_R")
	)
	(segment
		(start 113.220754 -11.646154)
		(end 112.646206 -11.646154)
		(width 0.127)
		(layer "F.Cu")
		(net "MB0_VCAP_R")
	)
	(segment
		(start 115.929918 -10.241534)
		(end 114.676174 -11.495278)
		(width 0.127)
		(layer "F.Cu")
		(net "MB0_VCAP_R")
	)
	(via
		(at 113.849404 -11.495278)
		(size 0.6604)
		(drill 0.3302)
		(layers "F.Cu" "B.Cu")
		(net "MB0_VCAP_R")
	)
	(via
		(at 113.597182 -12.402566)
		(size 0.508)
		(drill 0.254)
		(layers "F.Cu" "B.Cu")
		(net "MB0_VCAP_R")
	)
	(segment
		(start 113.597182 -12.402566)
		(end 112.300512 -12.402566)
		(width 0.127)
		(layer "B.Cu")
		(net "MB0_VCAP_R")
	)
	(segment
		(start 111.2393 -11.341354)
		(end 111.2393 -9.6012)
		(width 0.127)
		(layer "B.Cu")
		(net "MB0_VCAP_R")
	)
	(segment
		(start 112.300512 -12.402566)
		(end 111.2393 -11.341354)
		(width 0.127)
		(layer "B.Cu")
		(net "MB0_VCAP_R")
	)
	(segment
		(start 114.3508 -8.741664)
		(end 114.82197 -8.741664)
		(width 0.127)
		(layer "F.Cu")
		(net "MB0_TIME_R")
	)
	(segment
		(start 113.320576 -8.741664)
		(end 114.3508 -8.741664)
		(width 0.127)
		(layer "F.Cu")
		(net "MB0_TIME_R")
	)
	(segment
		(start 114.830098 -8.733536)
		(end 115.341908 -8.733536)
		(width 0.127)
		(layer "F.Cu")
		(net "MB0_TIME_R")
	)
	(segment
		(start 114.82197 -8.741664)
		(end 114.830098 -8.733536)
		(width 0.127)
		(layer "F.Cu")
		(net "MB0_TIME_R")
	)
	(segment
		(start 115.341908 -8.733536)
		(end 115.350036 -8.741664)
		(width 0.127)
		(layer "F.Cu")
		(net "MB0_TIME_R")
	)
	(segment
		(start 113.30559 -8.726678)
		(end 113.320576 -8.741664)
		(width 0.127)
		(layer "F.Cu")
		(net "MB0_TIME_R")
	)
	(segment
		(start 115.350036 -8.741664)
		(end 116.3955 -8.741664)
		(width 0.127)
		(layer "F.Cu")
		(net "MB0_TIME_R")
	)
	(via
		(at 114.3508 -8.741664)
		(size 0.6604)
		(drill 0.3302)
		(layers "F.Cu" "B.Cu")
		(net "MB0_TIME_R")
	)
	(segment
		(start 125.100842 -14.548104)
		(end 125.282452 -14.366494)
		(width 0.127)
		(layer "F.Cu")
		(net "MB0_TEMP_E")
	)
	(segment
		(start 125.210062 -13.167614)
		(end 125.282452 -13.240004)
		(width 0.127)
		(layer "F.Cu")
		(net "MB0_TEMP_E")
	)
	(segment
		(start 124.273056 -13.167614)
		(end 125.210062 -13.167614)
		(width 0.127)
		(layer "F.Cu")
		(net "MB0_TEMP_E")
	)
	(segment
		(start 124.251212 -14.548104)
		(end 125.100842 -14.548104)
		(width 0.127)
		(layer "F.Cu")
		(net "MB0_TEMP_E")
	)
	(segment
		(start 125.282452 -14.366494)
		(end 125.282452 -13.240004)
		(width 0.127)
		(layer "F.Cu")
		(net "MB0_TEMP_E")
	)
	(via
		(at 125.282452 -13.240004)
		(size 0.6604)
		(drill 0.3302)
		(layers "F.Cu" "B.Cu")
		(net "MB0_TEMP_E")
	)
	(segment
		(start 122.675904 -16.072866)
		(end 122.770138 -16.1671)
		(width 0.127)
		(layer "F.Cu")
		(net "MB0_TEMP_C")
	)
	(segment
		(start 123.119642 -16.516604)
		(end 122.770138 -16.1671)
		(width 0.127)
		(layer "F.Cu")
		(net "MB0_TEMP_C")
	)
	(segment
		(start 126.156212 -15.532354)
		(end 125.235462 -15.532354)
		(width 0.127)
		(layer "F.Cu")
		(net "MB0_TEMP_C")
	)
	(segment
		(start 125.235462 -15.532354)
		(end 124.251212 -16.516604)
		(width 0.127)
		(layer "F.Cu")
		(net "MB0_TEMP_C")
	)
	(segment
		(start 124.251212 -16.516604)
		(end 123.119642 -16.516604)
		(width 0.127)
		(layer "F.Cu")
		(net "MB0_TEMP_C")
	)
	(segment
		(start 122.675904 -15.128748)
		(end 122.675904 -16.072866)
		(width 0.127)
		(layer "F.Cu")
		(net "MB0_TEMP_C")
	)
	(via
		(at 122.770138 -16.1671)
		(size 0.6604)
		(drill 0.3302)
		(layers "F.Cu" "B.Cu")
		(net "MB0_TEMP_C")
	)
	(segment
		(start 121.201434 -13.501878)
		(end 121.201434 -13.085318)
		(width 0.127)
		(layer "F.Cu")
		(net "MB0_TEMP")
	)
	(segment
		(start 120.62206 -11.5443)
		(end 120.62206 -11.93546)
		(width 0.127)
		(layer "F.Cu")
		(net "MB0_TEMP")
	)
	(segment
		(start 121.786904 -15.128748)
		(end 121.786904 -14.167612)
		(width 0.127)
		(layer "F.Cu")
		(net "MB0_TEMP")
	)
	(segment
		(start 121.786904 -14.167612)
		(end 121.786904 -14.087348)
		(width 0.127)
		(layer "F.Cu")
		(net "MB0_TEMP")
	)
	(segment
		(start 120.62206 -11.93546)
		(end 121.201434 -12.514834)
		(width 0.127)
		(layer "F.Cu")
		(net "MB0_TEMP")
	)
	(segment
		(start 121.786904 -14.087348)
		(end 121.201434 -13.501878)
		(width 0.127)
		(layer "F.Cu")
		(net "MB0_TEMP")
	)
	(segment
		(start 121.201434 -12.514834)
		(end 121.201434 -13.085318)
		(width 0.127)
		(layer "F.Cu")
		(net "MB0_TEMP")
	)
	(via
		(at 121.201434 -13.085318)
		(size 0.6604)
		(drill 0.3302)
		(layers "F.Cu" "B.Cu")
		(net "MB0_TEMP")
	)
	(segment
		(start 113.853722 -5.577078)
		(end 113.29289 -5.577078)
		(width 0.127)
		(layer "F.Cu")
		(net "MB0_SPISS_PD")
	)
	(segment
		(start 115.1636 -4.8514)
		(end 116.139468 -4.8514)
		(width 0.127)
		(layer "F.Cu")
		(net "MB0_SPISS_PD")
	)
	(segment
		(start 116.139468 -4.8514)
		(end 117.12194 -5.833872)
		(width 0.127)
		(layer "F.Cu")
		(net "MB0_SPISS_PD")
	)
	(segment
		(start 115.1636 -4.8514)
		(end 114.5794 -4.8514)
		(width 0.127)
		(layer "F.Cu")
		(net "MB0_SPISS_PD")
	)
	(segment
		(start 114.5794 -4.8514)
		(end 113.853722 -5.577078)
		(width 0.127)
		(layer "F.Cu")
		(net "MB0_SPISS_PD")
	)
	(segment
		(start 117.12194 -5.833872)
		(end 117.12194 -6.4389)
		(width 0.127)
		(layer "F.Cu")
		(net "MB0_SPISS_PD")
	)
	(via
		(at 115.1636 -4.8514)
		(size 0.6604)
		(drill 0.3302)
		(layers "F.Cu" "B.Cu")
		(net "MB0_SPISS_PD")
	)
	(segment
		(start 121.4247 -7.24154)
		(end 122.05716 -7.24154)
		(width 0.127)
		(layer "F.Cu")
		(net "MB0_RETRY_R")
	)
	(segment
		(start 123.7615 -6.985)
		(end 124.3965 -7.62)
		(width 0.127)
		(layer "F.Cu")
		(net "MB0_RETRY_R")
	)
	(segment
		(start 122.433334 -7.233666)
		(end 122.682 -6.985)
		(width 0.127)
		(layer "F.Cu")
		(net "MB0_RETRY_R")
	)
	(segment
		(start 122.682 -6.985)
		(end 123.2662 -6.985)
		(width 0.127)
		(layer "F.Cu")
		(net "MB0_RETRY_R")
	)
	(segment
		(start 122.05716 -7.24154)
		(end 122.065034 -7.233666)
		(width 0.127)
		(layer "F.Cu")
		(net "MB0_RETRY_R")
	)
	(segment
		(start 123.2662 -6.985)
		(end 123.7615 -6.985)
		(width 0.127)
		(layer "F.Cu")
		(net "MB0_RETRY_R")
	)
	(segment
		(start 122.065034 -7.233666)
		(end 122.433334 -7.233666)
		(width 0.127)
		(layer "F.Cu")
		(net "MB0_RETRY_R")
	)
	(via
		(at 123.2662 -6.985)
		(size 0.6604)
		(drill 0.3302)
		(layers "F.Cu" "B.Cu")
		(net "MB0_RETRY_R")
	)
	(segment
		(start 111.584232 -14.262862)
		(end 111.955326 -14.262862)
		(width 0.127)
		(layer "F.Cu")
		(net "MB0_PSET_R")
	)
	(segment
		(start 114.92484 -12.730734)
		(end 114.511328 -12.730734)
		(width 0.127)
		(layer "F.Cu")
		(net "MB0_PSET_R")
	)
	(segment
		(start 111.517684 -14.196314)
		(end 111.584232 -14.262862)
		(width 0.127)
		(layer "F.Cu")
		(net "MB0_PSET_R")
	)
	(segment
		(start 111.517684 -13.1572)
		(end 111.517684 -14.196314)
		(width 0.127)
		(layer "F.Cu")
		(net "MB0_PSET_R")
	)
	(segment
		(start 114.21491 -12.730734)
		(end 113.645442 -13.300202)
		(width 0.127)
		(layer "F.Cu")
		(net "MB0_PSET_R")
	)
	(segment
		(start 116.3193 -11.336274)
		(end 114.92484 -12.730734)
		(width 0.127)
		(layer "F.Cu")
		(net "MB0_PSET_R")
	)
	(segment
		(start 116.3193 -10.74166)
		(end 116.3193 -11.336274)
		(width 0.127)
		(layer "F.Cu")
		(net "MB0_PSET_R")
	)
	(segment
		(start 111.955326 -14.262862)
		(end 112.638078 -13.58011)
		(width 0.127)
		(layer "F.Cu")
		(net "MB0_PSET_R")
	)
	(segment
		(start 114.511328 -12.730734)
		(end 114.21491 -12.730734)
		(width 0.127)
		(layer "F.Cu")
		(net "MB0_PSET_R")
	)
	(segment
		(start 112.917986 -13.300202)
		(end 112.638078 -13.58011)
		(width 0.127)
		(layer "F.Cu")
		(net "MB0_PSET_R")
	)
	(segment
		(start 113.645442 -13.300202)
		(end 112.917986 -13.300202)
		(width 0.127)
		(layer "F.Cu")
		(net "MB0_PSET_R")
	)
	(via
		(at 114.511328 -12.730734)
		(size 0.6604)
		(drill 0.3302)
		(layers "F.Cu" "B.Cu")
		(net "MB0_PSET_R")
	)
	(segment
		(start 122.01906 -9.241536)
		(end 121.3485 -9.241536)
		(width 0.127)
		(layer "F.Cu")
		(net "MB0_P12V_PWGIN_R")
	)
	(segment
		(start 124.3965 -10.668)
		(end 123.593352 -10.668)
		(width 0.127)
		(layer "F.Cu")
		(net "MB0_P12V_PWGIN_R")
	)
	(segment
		(start 123.577858 -10.652506)
		(end 123.479306 -10.652506)
		(width 0.127)
		(layer "F.Cu")
		(net "MB0_P12V_PWGIN_R")
	)
	(segment
		(start 122.069606 -9.242806)
		(end 122.02033 -9.242806)
		(width 0.127)
		(layer "F.Cu")
		(net "MB0_P12V_PWGIN_R")
	)
	(segment
		(start 123.479306 -10.652506)
		(end 122.069606 -9.242806)
		(width 0.127)
		(layer "F.Cu")
		(net "MB0_P12V_PWGIN_R")
	)
	(segment
		(start 123.593352 -10.668)
		(end 123.577858 -10.652506)
		(width 0.127)
		(layer "F.Cu")
		(net "MB0_P12V_PWGIN_R")
	)
	(segment
		(start 122.02033 -9.242806)
		(end 122.01906 -9.241536)
		(width 0.127)
		(layer "F.Cu")
		(net "MB0_P12V_PWGIN_R")
	)
	(via
		(at 124.199396 -11.32332)
		(size 0.6096)
		(drill 0.3048)
		(layers "F.Cu" "B.Cu")
		(net "MB0_P12V_PWGIN_R")
	)
	(via
		(at 123.577858 -10.652506)
		(size 0.508)
		(drill 0.254)
		(layers "F.Cu" "B.Cu")
		(net "MB0_P12V_PWGIN_R")
	)
	(segment
		(start 124.199396 -11.32332)
		(end 123.69292 -11.32332)
		(width 0.127)
		(layer "B.Cu")
		(net "MB0_P12V_PWGIN_R")
	)
	(segment
		(start 123.69292 -11.32332)
		(end 123.577858 -11.208258)
		(width 0.127)
		(layer "B.Cu")
		(net "MB0_P12V_PWGIN_R")
	)
	(segment
		(start 124.199396 -11.32332)
		(end 124.91593 -11.32332)
		(width 0.127)
		(layer "B.Cu")
		(net "MB0_P12V_PWGIN_R")
	)
	(segment
		(start 123.577858 -11.208258)
		(end 123.577858 -10.652506)
		(width 0.127)
		(layer "B.Cu")
		(net "MB0_P12V_PWGIN_R")
	)
	(segment
		(start 124.91593 -11.32332)
		(end 125.417072 -10.822178)
		(width 0.127)
		(layer "B.Cu")
		(net "MB0_P12V_PWGIN_R")
	)
	(via
		(at 141.3002 -11.975592)
		(size 0.6604)
		(drill 0.3302)
		(layers "F.Cu" "B.Cu")
		(net "MB0_P12V_MAIN_R")
	)
	(segment
		(start 114.868452 -9.39546)
		(end 114.88674 -9.39546)
		(width 0.127)
		(layer "F.Cu")
		(net "MB0_ISTART_R")
	)
	(segment
		(start 114.574574 -9.689338)
		(end 114.868452 -9.39546)
		(width 0.127)
		(layer "F.Cu")
		(net "MB0_ISTART_R")
	)
	(segment
		(start 114.415316 -9.689338)
		(end 113.300764 -9.689338)
		(width 0.127)
		(layer "F.Cu")
		(net "MB0_ISTART_R")
	)
	(segment
		(start 114.88674 -9.39546)
		(end 115.040664 -9.241536)
		(width 0.127)
		(layer "F.Cu")
		(net "MB0_ISTART_R")
	)
	(segment
		(start 115.040664 -9.241536)
		(end 116.3955 -9.241536)
		(width 0.127)
		(layer "F.Cu")
		(net "MB0_ISTART_R")
	)
	(segment
		(start 114.415316 -9.689338)
		(end 114.574574 -9.689338)
		(width 0.127)
		(layer "F.Cu")
		(net "MB0_ISTART_R")
	)
	(via
		(at 114.415316 -9.689338)
		(size 0.508)
		(drill 0.254)
		(layers "F.Cu" "B.Cu")
		(net "MB0_ISTART_R")
	)
	(via
		(at 112.742726 -10.94613)
		(size 0.6096)
		(drill 0.3048)
		(layers "F.Cu" "B.Cu")
		(net "MB0_ISTART_R")
	)
	(segment
		(start 112.1283 -10.803128)
		(end 112.268762 -10.94359)
		(width 0.127)
		(layer "B.Cu")
		(net "MB0_ISTART_R")
	)
	(segment
		(start 112.742726 -10.94613)
		(end 112.745266 -10.94359)
		(width 0.127)
		(layer "B.Cu")
		(net "MB0_ISTART_R")
	)
	(segment
		(start 114.415316 -9.689338)
		(end 114.301778 -9.5758)
		(width 0.127)
		(layer "B.Cu")
		(net "MB0_ISTART_R")
	)
	(segment
		(start 112.268762 -10.94359)
		(end 112.740186 -10.94359)
		(width 0.127)
		(layer "B.Cu")
		(net "MB0_ISTART_R")
	)
	(segment
		(start 112.740186 -10.94359)
		(end 112.742726 -10.94613)
		(width 0.127)
		(layer "B.Cu")
		(net "MB0_ISTART_R")
	)
	(segment
		(start 112.745266 -10.94359)
		(end 113.230406 -10.94359)
		(width 0.127)
		(layer "B.Cu")
		(net "MB0_ISTART_R")
	)
	(segment
		(start 114.301778 -9.5758)
		(end 113.386362 -9.5758)
		(width 0.127)
		(layer "B.Cu")
		(net "MB0_ISTART_R")
	)
	(segment
		(start 113.386362 -10.787634)
		(end 113.386362 -9.5758)
		(width 0.127)
		(layer "B.Cu")
		(net "MB0_ISTART_R")
	)
	(segment
		(start 112.1283 -9.6012)
		(end 112.1283 -10.803128)
		(width 0.127)
		(layer "B.Cu")
		(net "MB0_ISTART_R")
	)
	(segment
		(start 113.230406 -10.94359)
		(end 113.386362 -10.787634)
		(width 0.127)
		(layer "B.Cu")
		(net "MB0_ISTART_R")
	)
	(segment
		(start 114.483642 -10.757154)
		(end 114.612674 -10.628122)
		(width 0.127)
		(layer "F.Cu")
		(net "MB0_ISET_R")
	)
	(segment
		(start 111.520478 -10.791952)
		(end 112.075214 -10.791952)
		(width 0.127)
		(layer "F.Cu")
		(net "MB0_ISET_R")
	)
	(segment
		(start 114.612674 -10.628122)
		(end 115.499134 -9.741662)
		(width 0.127)
		(layer "F.Cu")
		(net "MB0_ISET_R")
	)
	(segment
		(start 111.15929 -10.430764)
		(end 111.520478 -10.791952)
		(width 0.127)
		(layer "F.Cu")
		(net "MB0_ISET_R")
	)
	(segment
		(start 111.15929 -9.666478)
		(end 111.15929 -10.430764)
		(width 0.127)
		(layer "F.Cu")
		(net "MB0_ISET_R")
	)
	(segment
		(start 112.646206 -10.757154)
		(end 114.483642 -10.757154)
		(width 0.127)
		(layer "F.Cu")
		(net "MB0_ISET_R")
	)
	(segment
		(start 112.075214 -10.791952)
		(end 112.110012 -10.757154)
		(width 0.127)
		(layer "F.Cu")
		(net "MB0_ISET_R")
	)
	(segment
		(start 115.499134 -9.741662)
		(end 116.3955 -9.741662)
		(width 0.127)
		(layer "F.Cu")
		(net "MB0_ISET_R")
	)
	(segment
		(start 112.110012 -10.757154)
		(end 112.646206 -10.757154)
		(width 0.127)
		(layer "F.Cu")
		(net "MB0_ISET_R")
	)
	(via
		(at 114.612674 -10.628122)
		(size 0.6604)
		(drill 0.3302)
		(layers "F.Cu" "B.Cu")
		(net "MB0_ISET_R")
	)
	(segment
		(start 118.622064 -6.5151)
		(end 118.622064 -5.18922)
		(width 0.127)
		(layer "F.Cu")
		(net "MB0_HS_ENABLE")
	)
	(via
		(at 117.1829 -7.5692)
		(size 0.6096)
		(drill 0.3048)
		(layers "F.Cu" "B.Cu")
		(net "MB0_HS_ENABLE")
	)
	(via
		(at 118.622064 -5.18922)
		(size 0.508)
		(drill 0.254)
		(layers "F.Cu" "B.Cu")
		(net "MB0_HS_ENABLE")
	)
	(segment
		(start 117.84584 -6.60146)
		(end 117.8941 -6.5532)
		(width 0.127)
		(layer "B.Cu")
		(net "MB0_HS_ENABLE")
	)
	(segment
		(start 116.74094 -8.01116)
		(end 117.1829 -7.5692)
		(width 0.127)
		(layer "B.Cu")
		(net "MB0_HS_ENABLE")
	)
	(segment
		(start 118.622064 -5.18922)
		(end 118.622064 -5.579364)
		(width 0.127)
		(layer "B.Cu")
		(net "MB0_HS_ENABLE")
	)
	(segment
		(start 117.27434 -6.60146)
		(end 117.84584 -6.60146)
		(width 0.127)
		(layer "B.Cu")
		(net "MB0_HS_ENABLE")
	)
	(segment
		(start 117.27434 -7.47776)
		(end 117.1829 -7.5692)
		(width 0.127)
		(layer "B.Cu")
		(net "MB0_HS_ENABLE")
	)
	(segment
		(start 118.726966 -5.684266)
		(end 118.726966 -6.5532)
		(width 0.127)
		(layer "B.Cu")
		(net "MB0_HS_ENABLE")
	)
	(segment
		(start 116.74094 -8.53186)
		(end 116.74094 -8.01116)
		(width 0.127)
		(layer "B.Cu")
		(net "MB0_HS_ENABLE")
	)
	(segment
		(start 117.8941 -6.5532)
		(end 118.726966 -6.5532)
		(width 0.127)
		(layer "B.Cu")
		(net "MB0_HS_ENABLE")
	)
	(segment
		(start 117.27434 -6.60146)
		(end 117.27434 -7.47776)
		(width 0.127)
		(layer "B.Cu")
		(net "MB0_HS_ENABLE")
	)
	(segment
		(start 118.622064 -5.579364)
		(end 118.726966 -5.684266)
		(width 0.127)
		(layer "B.Cu")
		(net "MB0_HS_ENABLE")
	)
	(segment
		(start 124.2441 -9.8044)
		(end 124.3965 -9.652)
		(width 0.127)
		(layer "F.Cu")
		(net "MB0_CM_VOUT_R")
	)
	(segment
		(start 123.5456 -9.779)
		(end 123.571 -9.8044)
		(width 0.127)
		(layer "F.Cu")
		(net "MB0_CM_VOUT_R")
	)
	(segment
		(start 123.33859 -8.86206)
		(end 123.5456 -9.06907)
		(width 0.127)
		(layer "F.Cu")
		(net "MB0_CM_VOUT_R")
	)
	(segment
		(start 123.5456 -9.06907)
		(end 123.5456 -9.779)
		(width 0.127)
		(layer "F.Cu")
		(net "MB0_CM_VOUT_R")
	)
	(segment
		(start 123.33859 -8.86206)
		(end 122.410728 -8.86206)
		(width 0.127)
		(layer "F.Cu")
		(net "MB0_CM_VOUT_R")
	)
	(segment
		(start 122.410728 -8.86206)
		(end 122.290332 -8.741664)
		(width 0.127)
		(layer "F.Cu")
		(net "MB0_CM_VOUT_R")
	)
	(segment
		(start 123.571 -9.8044)
		(end 124.2441 -9.8044)
		(width 0.127)
		(layer "F.Cu")
		(net "MB0_CM_VOUT_R")
	)
	(segment
		(start 122.290332 -8.741664)
		(end 121.3485 -8.741664)
		(width 0.127)
		(layer "F.Cu")
		(net "MB0_CM_VOUT_R")
	)
	(via
		(at 123.33859 -8.86206)
		(size 0.6604)
		(drill 0.3302)
		(layers "F.Cu" "B.Cu")
		(net "MB0_CM_VOUT_R")
	)
	(via
		(at 123.5456 -9.779)
		(size 0.508)
		(drill 0.254)
		(layers "F.Cu" "B.Cu")
		(net "MB0_CM_VOUT_R")
	)
	(segment
		(start 124.51334 -9.622282)
		(end 124.36094 -9.774682)
		(width 0.127)
		(layer "B.Cu")
		(net "MB0_CM_VOUT_R")
	)
	(segment
		(start 123.549918 -9.774682)
		(end 123.5456 -9.779)
		(width 0.127)
		(layer "B.Cu")
		(net "MB0_CM_VOUT_R")
	)
	(segment
		(start 124.36094 -9.774682)
		(end 123.549918 -9.774682)
		(width 0.127)
		(layer "B.Cu")
		(net "MB0_CM_VOUT_R")
	)
	(segment
		(start 117.622066 -12.311888)
		(end 117.622066 -11.4681)
		(width 0.127)
		(layer "F.Cu")
		(net "MB0_CM_UV_R")
	)
	(segment
		(start 117.442488 -12.491466)
		(end 117.622066 -12.311888)
		(width 0.127)
		(layer "F.Cu")
		(net "MB0_CM_UV_R")
	)
	(via
		(at 130.937 -14.986)
		(size 0.508)
		(drill 0.254)
		(layers "F.Cu" "B.Cu")
		(net "MB0_CM_UV_R")
	)
	(via
		(at 127.6096 -16.3576)
		(size 0.6096)
		(drill 0.3048)
		(layers "F.Cu" "B.Cu")
		(net "MB0_CM_UV_R")
	)
	(via
		(at 117.442488 -12.491466)
		(size 0.508)
		(drill 0.254)
		(layers "F.Cu" "B.Cu")
		(net "MB0_CM_UV_R")
	)
	(segment
		(start 127.762 -16.51)
		(end 127.6096 -16.3576)
		(width 0.127)
		(layer "B.Cu")
		(net "MB0_CM_UV_R")
	)
	(segment
		(start 127.6096 -16.1544)
		(end 128.651 -15.113)
		(width 0.127)
		(layer "B.Cu")
		(net "MB0_CM_UV_R")
	)
	(segment
		(start 127.6096 -16.3576)
		(end 127.6096 -16.1544)
		(width 0.127)
		(layer "B.Cu")
		(net "MB0_CM_UV_R")
	)
	(segment
		(start 129.921 -14.7955)
		(end 129.6035 -15.113)
		(width 0.127)
		(layer "B.Cu")
		(net "MB0_CM_UV_R")
	)
	(segment
		(start 130.7465 -14.7955)
		(end 129.921 -14.7955)
		(width 0.127)
		(layer "B.Cu")
		(net "MB0_CM_UV_R")
	)
	(segment
		(start 130.937 -14.986)
		(end 130.7465 -14.7955)
		(width 0.127)
		(layer "B.Cu")
		(net "MB0_CM_UV_R")
	)
	(segment
		(start 129.6035 -15.113)
		(end 128.651 -15.113)
		(width 0.127)
		(layer "B.Cu")
		(net "MB0_CM_UV_R")
	)
	(segment
		(start 128.8415 -16.51)
		(end 127.762 -16.51)
		(width 0.127)
		(layer "B.Cu")
		(net "MB0_CM_UV_R")
	)
	(segment
		(start 119.737378 -14.2494)
		(end 130.2004 -14.2494)
		(width 0.127)
		(layer "In2.Cu")
		(net "MB0_CM_UV_R")
	)
	(segment
		(start 117.442488 -12.491466)
		(end 117.979444 -12.491466)
		(width 0.127)
		(layer "In2.Cu")
		(net "MB0_CM_UV_R")
	)
	(segment
		(start 130.2004 -14.2494)
		(end 130.937 -14.986)
		(width 0.127)
		(layer "In2.Cu")
		(net "MB0_CM_UV_R")
	)
	(segment
		(start 117.979444 -12.491466)
		(end 119.737378 -14.2494)
		(width 0.127)
		(layer "In2.Cu")
		(net "MB0_CM_UV_R")
	)
	(segment
		(start 121.5898 -15.9512)
		(end 121.5898 -16.40332)
		(width 0.127)
		(layer "F.Cu")
		(net "MB0_CM_SENSE_R1_P")
	)
	(segment
		(start 121.02592 -16.9672)
		(end 119.0752 -16.9672)
		(width 0.127)
		(layer "F.Cu")
		(net "MB0_CM_SENSE_R1_P")
	)
	(segment
		(start 121.190766 -16.802354)
		(end 121.02592 -16.9672)
		(width 0.127)
		(layer "F.Cu")
		(net "MB0_CM_SENSE_R1_P")
	)
	(segment
		(start 134.962138 -13.805154)
		(end 136.396222 -13.805154)
		(width 0.127)
		(layer "F.Cu")
		(net "MB0_CM_SENSE_R1_P")
	)
	(segment
		(start 119.0752 -16.9672)
		(end 118.9736 -16.8656)
		(width 0.127)
		(layer "F.Cu")
		(net "MB0_CM_SENSE_R1_P")
	)
	(segment
		(start 134.1882 -14.896592)
		(end 134.8867 -14.198092)
		(width 0.127)
		(layer "F.Cu")
		(net "MB0_CM_SENSE_R1_P")
	)
	(segment
		(start 118.9736 -16.8656)
		(end 118.9736 -16.4465)
		(width 0.127)
		(layer "F.Cu")
		(net "MB0_CM_SENSE_R1_P")
	)
	(segment
		(start 134.8867 -14.198092)
		(end 134.8867 -13.880592)
		(width 0.127)
		(layer "F.Cu")
		(net "MB0_CM_SENSE_R1_P")
	)
	(segment
		(start 121.5898 -16.40332)
		(end 121.190766 -16.802354)
		(width 0.127)
		(layer "F.Cu")
		(net "MB0_CM_SENSE_R1_P")
	)
	(segment
		(start 134.8867 -13.880592)
		(end 134.962138 -13.805154)
		(width 0.127)
		(layer "F.Cu")
		(net "MB0_CM_SENSE_R1_P")
	)
	(via
		(at 134.1882 -14.896592)
		(size 0.508)
		(drill 0.254)
		(layers "F.Cu" "B.Cu")
		(net "MB0_CM_SENSE_R1_P")
	)
	(via
		(at 121.190766 -16.802354)
		(size 0.6604)
		(drill 0.3302)
		(layers "F.Cu" "B.Cu")
		(net "MB0_CM_SENSE_R1_P")
	)
	(via
		(at 121.5898 -15.9512)
		(size 0.508)
		(drill 0.254)
		(layers "F.Cu" "B.Cu")
		(net "MB0_CM_SENSE_R1_P")
	)
	(segment
		(start 129.977388 -16.7259)
		(end 129.202688 -15.9512)
		(width 0.127)
		(layer "In2.Cu")
		(net "MB0_CM_SENSE_R1_P")
	)
	(segment
		(start 132.358892 -16.7259)
		(end 129.977388 -16.7259)
		(width 0.127)
		(layer "In2.Cu")
		(net "MB0_CM_SENSE_R1_P")
	)
	(segment
		(start 134.1882 -14.896592)
		(end 132.358892 -16.7259)
		(width 0.127)
		(layer "In2.Cu")
		(net "MB0_CM_SENSE_R1_P")
	)
	(segment
		(start 129.202688 -15.9512)
		(end 121.5898 -15.9512)
		(width 0.127)
		(layer "In2.Cu")
		(net "MB0_CM_SENSE_R1_P")
	)
	(segment
		(start 134.885938 -12.737592)
		(end 134.8867 -12.737592)
		(width 0.127)
		(layer "F.Cu")
		(net "MB0_CM_SENSE_R1_N")
	)
	(segment
		(start 135.3566 -12.737592)
		(end 135.916162 -12.17803)
		(width 0.127)
		(layer "F.Cu")
		(net "MB0_CM_SENSE_R1_N")
	)
	(segment
		(start 120.9294 -15.7988)
		(end 120.9294 -15.367)
		(width 0.127)
		(layer "F.Cu")
		(net "MB0_CM_SENSE_R1_N")
	)
	(segment
		(start 120.3071 -16.4211)
		(end 120.9294 -15.7988)
		(width 0.127)
		(layer "F.Cu")
		(net "MB0_CM_SENSE_R1_N")
	)
	(segment
		(start 134.8867 -12.737592)
		(end 135.3566 -12.737592)
		(width 0.127)
		(layer "F.Cu")
		(net "MB0_CM_SENSE_R1_N")
	)
	(segment
		(start 120.0658 -16.4211)
		(end 120.3071 -16.4211)
		(width 0.127)
		(layer "F.Cu")
		(net "MB0_CM_SENSE_R1_N")
	)
	(segment
		(start 134.8867 -12.737592)
		(end 134.8867 -11.937492)
		(width 0.127)
		(layer "F.Cu")
		(net "MB0_CM_SENSE_R1_N")
	)
	(segment
		(start 135.916162 -12.17803)
		(end 136.396222 -12.17803)
		(width 0.127)
		(layer "F.Cu")
		(net "MB0_CM_SENSE_R1_N")
	)
	(via
		(at 120.9294 -15.367)
		(size 0.508)
		(drill 0.254)
		(layers "F.Cu" "B.Cu")
		(net "MB0_CM_SENSE_R1_N")
	)
	(via
		(at 134.8867 -11.937492)
		(size 0.508)
		(drill 0.254)
		(layers "F.Cu" "B.Cu")
		(net "MB0_CM_SENSE_R1_N")
	)
	(segment
		(start 130.187954 -16.2179)
		(end 129.337054 -15.367)
		(width 0.127)
		(layer "In2.Cu")
		(net "MB0_CM_SENSE_R1_N")
	)
	(segment
		(start 129.337054 -15.367)
		(end 120.9294 -15.367)
		(width 0.127)
		(layer "In2.Cu")
		(net "MB0_CM_SENSE_R1_N")
	)
	(segment
		(start 134.8867 -11.937492)
		(end 134.8867 -13.35024)
		(width 0.127)
		(layer "In2.Cu")
		(net "MB0_CM_SENSE_R1_N")
	)
	(segment
		(start 134.8867 -13.35024)
		(end 132.01904 -16.2179)
		(width 0.127)
		(layer "In2.Cu")
		(net "MB0_CM_SENSE_R1_N")
	)
	(segment
		(start 132.01904 -16.2179)
		(end 130.187954 -16.2179)
		(width 0.127)
		(layer "In2.Cu")
		(net "MB0_CM_SENSE_R1_N")
	)
	(segment
		(start 118.9736 -15.5575)
		(end 118.9736 -15.1384)
		(width 0.127)
		(layer "F.Cu")
		(net "MB0_CM_SENSE_P")
	)
	(segment
		(start 118.9736 -15.1384)
		(end 119.0752 -15.0368)
		(width 0.127)
		(layer "F.Cu")
		(net "MB0_CM_SENSE_P")
	)
	(segment
		(start 118.622064 -12.754102)
		(end 118.622064 -11.4681)
		(width 0.127)
		(layer "F.Cu")
		(net "MB0_CM_SENSE_P")
	)
	(segment
		(start 119.0752 -15.0368)
		(end 119.0752 -14.478)
		(width 0.127)
		(layer "F.Cu")
		(net "MB0_CM_SENSE_P")
	)
	(segment
		(start 118.693438 -13.076682)
		(end 118.693438 -12.825476)
		(width 0.127)
		(layer "F.Cu")
		(net "MB0_CM_SENSE_P")
	)
	(segment
		(start 119.0752 -14.478)
		(end 119.0752 -13.476732)
		(width 0.127)
		(layer "F.Cu")
		(net "MB0_CM_SENSE_P")
	)
	(segment
		(start 119.084344 -13.467588)
		(end 118.693438 -13.076682)
		(width 0.127)
		(layer "F.Cu")
		(net "MB0_CM_SENSE_P")
	)
	(segment
		(start 118.693438 -12.825476)
		(end 118.622064 -12.754102)
		(width 0.127)
		(layer "F.Cu")
		(net "MB0_CM_SENSE_P")
	)
	(segment
		(start 119.0752 -13.476732)
		(end 119.084344 -13.467588)
		(width 0.127)
		(layer "F.Cu")
		(net "MB0_CM_SENSE_P")
	)
	(via
		(at 119.0752 -14.478)
		(size 0.6604)
		(drill 0.3302)
		(layers "F.Cu" "B.Cu")
		(net "MB0_CM_SENSE_P")
	)
	(segment
		(start 119.973344 -13.467588)
		(end 120.4976 -13.991844)
		(width 0.127)
		(layer "F.Cu")
		(net "MB0_CM_SENSE_N")
	)
	(segment
		(start 120.4976 -15.0368)
		(end 120.0658 -15.4686)
		(width 0.127)
		(layer "F.Cu")
		(net "MB0_CM_SENSE_N")
	)
	(segment
		(start 120.6119 -12.3825)
		(end 120.121934 -11.892534)
		(width 0.127)
		(layer "F.Cu")
		(net "MB0_CM_SENSE_N")
	)
	(segment
		(start 120.121934 -11.892534)
		(end 120.121934 -11.4681)
		(width 0.127)
		(layer "F.Cu")
		(net "MB0_CM_SENSE_N")
	)
	(segment
		(start 120.6119 -12.829032)
		(end 120.6119 -12.3825)
		(width 0.127)
		(layer "F.Cu")
		(net "MB0_CM_SENSE_N")
	)
	(segment
		(start 120.0658 -15.4686)
		(end 120.0658 -15.5321)
		(width 0.127)
		(layer "F.Cu")
		(net "MB0_CM_SENSE_N")
	)
	(segment
		(start 119.973344 -13.467588)
		(end 120.6119 -12.829032)
		(width 0.127)
		(layer "F.Cu")
		(net "MB0_CM_SENSE_N")
	)
	(segment
		(start 120.4976 -14.3764)
		(end 120.4976 -15.0368)
		(width 0.127)
		(layer "F.Cu")
		(net "MB0_CM_SENSE_N")
	)
	(segment
		(start 120.4976 -13.991844)
		(end 120.4976 -14.3764)
		(width 0.127)
		(layer "F.Cu")
		(net "MB0_CM_SENSE_N")
	)
	(via
		(at 120.4976 -14.3764)
		(size 0.6604)
		(drill 0.3302)
		(layers "F.Cu" "B.Cu")
		(net "MB0_CM_SENSE_N")
	)
	(segment
		(start 117.12194 -11.91006)
		(end 117.12194 -11.5443)
		(width 0.127)
		(layer "F.Cu")
		(net "MB0_CM_OV_R")
	)
	(segment
		(start 117.007386 -12.024614)
		(end 117.12194 -11.91006)
		(width 0.127)
		(layer "F.Cu")
		(net "MB0_CM_OV_R")
	)
	(segment
		(start 116.342414 -12.024614)
		(end 117.007386 -12.024614)
		(width 0.127)
		(layer "F.Cu")
		(net "MB0_CM_OV_R")
	)
	(via
		(at 127.5842 -14.7828)
		(size 0.508)
		(drill 0.254)
		(layers "F.Cu" "B.Cu")
		(net "MB0_CM_OV_R")
	)
	(via
		(at 124.1552 -15.7734)
		(size 0.6096)
		(drill 0.3048)
		(layers "F.Cu" "B.Cu")
		(net "MB0_CM_OV_R")
	)
	(via
		(at 116.342414 -12.024614)
		(size 0.508)
		(drill 0.254)
		(layers "F.Cu" "B.Cu")
		(net "MB0_CM_OV_R")
	)
	(segment
		(start 124.33427 -16.2179)
		(end 124.1552 -16.03883)
		(width 0.127)
		(layer "B.Cu")
		(net "MB0_CM_OV_R")
	)
	(segment
		(start 126.5301 -14.93012)
		(end 127.43688 -14.93012)
		(width 0.127)
		(layer "B.Cu")
		(net "MB0_CM_OV_R")
	)
	(segment
		(start 124.1552 -15.312898)
		(end 124.355098 -15.113)
		(width 0.127)
		(layer "B.Cu")
		(net "MB0_CM_OV_R")
	)
	(segment
		(start 124.355098 -15.113)
		(end 125.349 -15.113)
		(width 0.127)
		(layer "B.Cu")
		(net "MB0_CM_OV_R")
	)
	(segment
		(start 124.1552 -15.7734)
		(end 124.1552 -15.312898)
		(width 0.127)
		(layer "B.Cu")
		(net "MB0_CM_OV_R")
	)
	(segment
		(start 126.1745 -15.113)
		(end 126.35738 -14.93012)
		(width 0.127)
		(layer "B.Cu")
		(net "MB0_CM_OV_R")
	)
	(segment
		(start 125.349 -15.113)
		(end 126.1745 -15.113)
		(width 0.127)
		(layer "B.Cu")
		(net "MB0_CM_OV_R")
	)
	(segment
		(start 125.349 -16.2179)
		(end 124.33427 -16.2179)
		(width 0.127)
		(layer "B.Cu")
		(net "MB0_CM_OV_R")
	)
	(segment
		(start 124.1552 -16.03883)
		(end 124.1552 -15.7734)
		(width 0.127)
		(layer "B.Cu")
		(net "MB0_CM_OV_R")
	)
	(segment
		(start 127.43688 -14.93012)
		(end 127.5842 -14.7828)
		(width 0.127)
		(layer "B.Cu")
		(net "MB0_CM_OV_R")
	)
	(segment
		(start 126.35738 -14.93012)
		(end 126.5301 -14.93012)
		(width 0.127)
		(layer "B.Cu")
		(net "MB0_CM_OV_R")
	)
	(segment
		(start 117.124734 -13.0175)
		(end 117.786912 -13.0175)
		(width 0.127)
		(layer "In2.Cu")
		(net "MB0_CM_OV_R")
	)
	(segment
		(start 119.552212 -14.7828)
		(end 127.5842 -14.7828)
		(width 0.127)
		(layer "In2.Cu")
		(net "MB0_CM_OV_R")
	)
	(segment
		(start 116.342414 -12.024614)
		(end 116.3574 -12.0396)
		(width 0.127)
		(layer "In2.Cu")
		(net "MB0_CM_OV_R")
	)
	(segment
		(start 117.786912 -13.0175)
		(end 119.552212 -14.7828)
		(width 0.127)
		(layer "In2.Cu")
		(net "MB0_CM_OV_R")
	)
	(segment
		(start 116.3574 -12.250166)
		(end 117.124734 -13.0175)
		(width 0.127)
		(layer "In2.Cu")
		(net "MB0_CM_OV_R")
	)
	(segment
		(start 116.3574 -12.0396)
		(end 116.3574 -12.250166)
		(width 0.127)
		(layer "In2.Cu")
		(net "MB0_CM_OV_R")
	)
	(via
		(at 130.895598 -5.32003)
		(size 0.6604)
		(drill 0.3302)
		(layers "F.Cu" "B.Cu")
		(net "MB0_CM_GATE_R")
	)
	(segment
		(start 127.978916 -10.691622)
		(end 127.978916 -11.468862)
		(width 0.508)
		(layer "F.Cu")
		(net "MB0_CM_GATE")
	)
	(segment
		(start 121.4247 -11.720576)
		(end 121.4247 -10.74166)
		(width 0.254)
		(layer "F.Cu")
		(net "MB0_CM_GATE")
	)
	(segment
		(start 121.67616 -11.972036)
		(end 121.4247 -11.720576)
		(width 0.254)
		(layer "F.Cu")
		(net "MB0_CM_GATE")
	)
	(segment
		(start 127.978916 -11.468862)
		(end 128.430782 -11.920728)
		(width 0.508)
		(layer "F.Cu")
		(net "MB0_CM_GATE")
	)
	(via
		(at 121.67616 -11.972036)
		(size 0.508)
		(drill 0.254)
		(layers "F.Cu" "B.Cu")
		(net "MB0_CM_GATE")
	)
	(via
		(at 128.430782 -11.920728)
		(size 0.508)
		(drill 0.254)
		(layers "F.Cu" "B.Cu")
		(net "MB0_CM_GATE")
	)
	(segment
		(start 121.67616 -11.972036)
		(end 122.289062 -11.359134)
		(width 0.508)
		(layer "In2.Cu")
		(net "MB0_CM_GATE")
	)
	(segment
		(start 126.037594 -10.91946)
		(end 127.429514 -10.91946)
		(width 0.508)
		(layer "In2.Cu")
		(net "MB0_CM_GATE")
	)
	(segment
		(start 127.429514 -10.91946)
		(end 128.430782 -11.920728)
		(width 0.508)
		(layer "In2.Cu")
		(net "MB0_CM_GATE")
	)
	(segment
		(start 122.289062 -11.359134)
		(end 125.59792 -11.359134)
		(width 0.508)
		(layer "In2.Cu")
		(net "MB0_CM_GATE")
	)
	(segment
		(start 125.59792 -11.359134)
		(end 126.037594 -10.91946)
		(width 0.508)
		(layer "In2.Cu")
		(net "MB0_CM_GATE")
	)
	(segment
		(start 114.7572 -6.096)
		(end 115.90274 -7.24154)
		(width 0.127)
		(layer "F.Cu")
		(net "MB0_CM_ADR2_R")
	)
	(segment
		(start 113.675922 -6.643878)
		(end 114.2238 -6.096)
		(width 0.127)
		(layer "F.Cu")
		(net "MB0_CM_ADR2_R")
	)
	(segment
		(start 115.90274 -7.24154)
		(end 116.3193 -7.24154)
		(width 0.127)
		(layer "F.Cu")
		(net "MB0_CM_ADR2_R")
	)
	(segment
		(start 113.31829 -6.643878)
		(end 113.675922 -6.643878)
		(width 0.127)
		(layer "F.Cu")
		(net "MB0_CM_ADR2_R")
	)
	(segment
		(start 114.2238 -6.096)
		(end 114.5286 -6.096)
		(width 0.127)
		(layer "F.Cu")
		(net "MB0_CM_ADR2_R")
	)
	(segment
		(start 114.5286 -6.096)
		(end 114.7572 -6.096)
		(width 0.127)
		(layer "F.Cu")
		(net "MB0_CM_ADR2_R")
	)
	(via
		(at 114.5286 -6.096)
		(size 0.6604)
		(drill 0.3302)
		(layers "F.Cu" "B.Cu")
		(net "MB0_CM_ADR2_R")
	)
	(segment
		(start 114.5286 -7.366)
		(end 114.243866 -7.366)
		(width 0.127)
		(layer "F.Cu")
		(net "MB0_CM_ADR1_R")
	)
	(segment
		(start 114.243866 -7.366)
		(end 113.8682 -7.741666)
		(width 0.127)
		(layer "F.Cu")
		(net "MB0_CM_ADR1_R")
	)
	(segment
		(start 113.8682 -7.741666)
		(end 113.323878 -7.741666)
		(width 0.127)
		(layer "F.Cu")
		(net "MB0_CM_ADR1_R")
	)
	(segment
		(start 115.092734 -7.366)
		(end 115.4684 -7.741666)
		(width 0.127)
		(layer "F.Cu")
		(net "MB0_CM_ADR1_R")
	)
	(segment
		(start 114.5286 -7.366)
		(end 115.092734 -7.366)
		(width 0.127)
		(layer "F.Cu")
		(net "MB0_CM_ADR1_R")
	)
	(segment
		(start 115.4684 -7.741666)
		(end 116.3955 -7.741666)
		(width 0.127)
		(layer "F.Cu")
		(net "MB0_CM_ADR1_R")
	)
	(segment
		(start 113.323878 -7.741666)
		(end 113.31829 -7.736078)
		(width 0.127)
		(layer "F.Cu")
		(net "MB0_CM_ADR1_R")
	)
	(via
		(at 114.5286 -7.366)
		(size 0.6604)
		(drill 0.3302)
		(layers "F.Cu" "B.Cu")
		(net "MB0_CM_ADR1_R")
	)
	(via
		(at 133.266688 -4.578604)
		(size 0.6604)
		(drill 0.3302)
		(layers "F.Cu" "B.Cu")
		(net "MB0_12V_CTRL_GATE1")
	)
	(segment
		(start 89.503504 -146.500088)
		(end 89.773506 -146.230086)
		(width 0.127)
		(layer "F.Cu")
		(net "IO_EXP0_RESET#_FLT")
	)
	(segment
		(start 87.4395 -146.823938)
		(end 87.76335 -146.500088)
		(width 0.127)
		(layer "F.Cu")
		(net "IO_EXP0_RESET#_FLT")
	)
	(segment
		(start 88.252554 -146.500088)
		(end 89.503504 -146.500088)
		(width 0.127)
		(layer "F.Cu")
		(net "IO_EXP0_RESET#_FLT")
	)
	(segment
		(start 87.76335 -146.500088)
		(end 88.252554 -146.500088)
		(width 0.127)
		(layer "F.Cu")
		(net "IO_EXP0_RESET#_FLT")
	)
	(segment
		(start 89.773506 -146.230086)
		(end 90.357706 -146.230086)
		(width 0.127)
		(layer "F.Cu")
		(net "IO_EXP0_RESET#_FLT")
	)
	(segment
		(start 87.4395 -147.574)
		(end 87.4395 -146.823938)
		(width 0.127)
		(layer "F.Cu")
		(net "IO_EXP0_RESET#_FLT")
	)
	(via
		(at 88.252554 -146.500088)
		(size 0.6604)
		(drill 0.3302)
		(layers "F.Cu" "B.Cu")
		(net "IO_EXP0_RESET#_FLT")
	)
	(segment
		(start 97.6122 -139.2809)
		(end 97.1169 -139.2809)
		(width 0.127)
		(layer "F.Cu")
		(net "DEBUG_RST_BTN_N")
	)
	(segment
		(start 96.913446 -139.077446)
		(end 95.996506 -139.077446)
		(width 0.127)
		(layer "F.Cu")
		(net "DEBUG_RST_BTN_N")
	)
	(segment
		(start 40.500046 -137.800334)
		(end 40.899588 -138.199876)
		(width 0.127)
		(layer "F.Cu")
		(net "DEBUG_RST_BTN_N")
	)
	(segment
		(start 97.1169 -139.2809)
		(end 96.913446 -139.077446)
		(width 0.127)
		(layer "F.Cu")
		(net "DEBUG_RST_BTN_N")
	)
	(segment
		(start 97.6376 -139.2555)
		(end 97.6122 -139.2809)
		(width 0.127)
		(layer "F.Cu")
		(net "DEBUG_RST_BTN_N")
	)
	(segment
		(start 40.899588 -138.199876)
		(end 40.899842 -138.199876)
		(width 0.127)
		(layer "F.Cu")
		(net "DEBUG_RST_BTN_N")
	)
	(segment
		(start 97.6376 -138.47953)
		(end 97.6376 -139.2555)
		(width 0.127)
		(layer "F.Cu")
		(net "DEBUG_RST_BTN_N")
	)
	(via
		(at 57.52465 -122.0216)
		(size 0.508)
		(drill 0.254)
		(layers "F.Cu" "B.Cu")
		(net "DEBUG_RST_BTN_N")
	)
	(via
		(at 97.4598 -127.2032)
		(size 0.6096)
		(drill 0.3048)
		(layers "F.Cu" "B.Cu")
		(net "DEBUG_RST_BTN_N")
	)
	(via
		(at 40.500046 -137.800334)
		(size 0.4572)
		(drill 0.2032)
		(layers "F.Cu" "B.Cu")
		(net "DEBUG_RST_BTN_N")
	)
	(via
		(at 97.6376 -138.47953)
		(size 0.508)
		(drill 0.254)
		(layers "F.Cu" "B.Cu")
		(net "DEBUG_RST_BTN_N")
	)
	(via
		(at 39.55034 -123.2408)
		(size 0.508)
		(drill 0.254)
		(layers "F.Cu" "B.Cu")
		(net "DEBUG_RST_BTN_N")
	)
	(via
		(at 96.844104 -119.152924)
		(size 0.508)
		(drill 0.254)
		(layers "F.Cu" "B.Cu")
		(net "DEBUG_RST_BTN_N")
	)
	(segment
		(start 96.732598 -120.167908)
		(end 96.732598 -121.8438)
		(width 0.127)
		(layer "B.Cu")
		(net "DEBUG_RST_BTN_N")
	)
	(segment
		(start 97.6376 -138.47953)
		(end 98.0059 -138.11123)
		(width 0.127)
		(layer "B.Cu")
		(net "DEBUG_RST_BTN_N")
	)
	(segment
		(start 95.711518 -124.760228)
		(end 96.732598 -125.781308)
		(width 0.127)
		(layer "B.Cu")
		(net "DEBUG_RST_BTN_N")
	)
	(segment
		(start 96.732598 -126.475998)
		(end 97.4598 -127.2032)
		(width 0.127)
		(layer "B.Cu")
		(net "DEBUG_RST_BTN_N")
	)
	(segment
		(start 96.844104 -119.152924)
		(end 96.86798 -119.152924)
		(width 0.127)
		(layer "B.Cu")
		(net "DEBUG_RST_BTN_N")
	)
	(segment
		(start 98.0059 -128.423416)
		(end 97.4598 -127.877316)
		(width 0.127)
		(layer "B.Cu")
		(net "DEBUG_RST_BTN_N")
	)
	(segment
		(start 58.03265 -122.5296)
		(end 57.52465 -122.0216)
		(width 0.127)
		(layer "B.Cu")
		(net "DEBUG_RST_BTN_N")
	)
	(segment
		(start 95.711518 -122.86488)
		(end 95.711518 -124.760228)
		(width 0.127)
		(layer "B.Cu")
		(net "DEBUG_RST_BTN_N")
	)
	(segment
		(start 58.03265 -122.974354)
		(end 58.03265 -122.5296)
		(width 0.127)
		(layer "B.Cu")
		(net "DEBUG_RST_BTN_N")
	)
	(segment
		(start 97.4598 -127.877316)
		(end 97.4598 -127.2032)
		(width 0.127)
		(layer "B.Cu")
		(net "DEBUG_RST_BTN_N")
	)
	(segment
		(start 96.732598 -121.8438)
		(end 95.711518 -122.86488)
		(width 0.127)
		(layer "B.Cu")
		(net "DEBUG_RST_BTN_N")
	)
	(segment
		(start 96.732598 -125.781308)
		(end 96.732598 -126.475998)
		(width 0.127)
		(layer "B.Cu")
		(net "DEBUG_RST_BTN_N")
	)
	(segment
		(start 96.86798 -119.152924)
		(end 96.86798 -120.032526)
		(width 0.127)
		(layer "B.Cu")
		(net "DEBUG_RST_BTN_N")
	)
	(segment
		(start 96.86798 -120.032526)
		(end 96.732598 -120.167908)
		(width 0.127)
		(layer "B.Cu")
		(net "DEBUG_RST_BTN_N")
	)
	(segment
		(start 98.0059 -138.11123)
		(end 98.0059 -128.423416)
		(width 0.127)
		(layer "B.Cu")
		(net "DEBUG_RST_BTN_N")
	)
	(segment
		(start 39.55034 -123.2408)
		(end 38.7858 -124.00534)
		(width 0.127)
		(layer "In2.Cu")
		(net "DEBUG_RST_BTN_N")
	)
	(segment
		(start 38.7858 -124.00534)
		(end 38.7858 -130.556)
		(width 0.127)
		(layer "In2.Cu")
		(net "DEBUG_RST_BTN_N")
	)
	(segment
		(start 40.500046 -132.270246)
		(end 40.500046 -137.800334)
		(width 0.127)
		(layer "In2.Cu")
		(net "DEBUG_RST_BTN_N")
	)
	(segment
		(start 38.7858 -130.556)
		(end 40.500046 -132.270246)
		(width 0.127)
		(layer "In2.Cu")
		(net "DEBUG_RST_BTN_N")
	)
	(segment
		(start 43.595798 -124.56668)
		(end 42.329354 -124.56668)
		(width 0.127)
		(layer "In5.Cu")
		(net "DEBUG_RST_BTN_N")
	)
	(segment
		(start 45.829982 -123.850654)
		(end 45.04817 -124.632466)
		(width 0.127)
		(layer "In5.Cu")
		(net "DEBUG_RST_BTN_N")
	)
	(segment
		(start 57.52465 -122.0216)
		(end 57.750964 -121.795286)
		(width 0.127)
		(layer "In5.Cu")
		(net "DEBUG_RST_BTN_N")
	)
	(segment
		(start 60.394088 -122.4153)
		(end 66.701924 -122.4153)
		(width 0.127)
		(layer "In5.Cu")
		(net "DEBUG_RST_BTN_N")
	)
	(segment
		(start 47.00143 -124.632466)
		(end 46.219618 -123.850654)
		(width 0.127)
		(layer "In5.Cu")
		(net "DEBUG_RST_BTN_N")
	)
	(segment
		(start 94.677738 -118.9482)
		(end 96.663256 -118.9482)
		(width 0.127)
		(layer "In5.Cu")
		(net "DEBUG_RST_BTN_N")
	)
	(segment
		(start 82.132424 -125.2474)
		(end 88.838024 -118.5418)
		(width 0.127)
		(layer "In5.Cu")
		(net "DEBUG_RST_BTN_N")
	)
	(segment
		(start 94.271338 -118.5418)
		(end 94.677738 -118.9482)
		(width 0.127)
		(layer "In5.Cu")
		(net "DEBUG_RST_BTN_N")
	)
	(segment
		(start 67.527424 -121.5898)
		(end 74.179176 -121.5898)
		(width 0.127)
		(layer "In5.Cu")
		(net "DEBUG_RST_BTN_N")
	)
	(segment
		(start 53.392832 -122.110246)
		(end 50.870612 -124.632466)
		(width 0.127)
		(layer "In5.Cu")
		(net "DEBUG_RST_BTN_N")
	)
	(segment
		(start 74.179176 -121.5898)
		(end 77.836776 -125.2474)
		(width 0.127)
		(layer "In5.Cu")
		(net "DEBUG_RST_BTN_N")
	)
	(segment
		(start 57.436004 -122.110246)
		(end 53.392832 -122.110246)
		(width 0.127)
		(layer "In5.Cu")
		(net "DEBUG_RST_BTN_N")
	)
	(segment
		(start 77.836776 -125.2474)
		(end 82.132424 -125.2474)
		(width 0.127)
		(layer "In5.Cu")
		(net "DEBUG_RST_BTN_N")
	)
	(segment
		(start 96.86798 -119.152924)
		(end 96.844104 -119.152924)
		(width 0.127)
		(layer "In5.Cu")
		(net "DEBUG_RST_BTN_N")
	)
	(segment
		(start 45.04817 -124.632466)
		(end 43.661584 -124.632466)
		(width 0.127)
		(layer "In5.Cu")
		(net "DEBUG_RST_BTN_N")
	)
	(segment
		(start 43.661584 -124.632466)
		(end 43.595798 -124.56668)
		(width 0.127)
		(layer "In5.Cu")
		(net "DEBUG_RST_BTN_N")
	)
	(segment
		(start 57.52465 -122.0216)
		(end 57.436004 -122.110246)
		(width 0.127)
		(layer "In5.Cu")
		(net "DEBUG_RST_BTN_N")
	)
	(segment
		(start 96.663256 -118.9482)
		(end 96.86798 -119.152924)
		(width 0.127)
		(layer "In5.Cu")
		(net "DEBUG_RST_BTN_N")
	)
	(segment
		(start 42.329354 -124.56668)
		(end 41.003474 -123.2408)
		(width 0.127)
		(layer "In5.Cu")
		(net "DEBUG_RST_BTN_N")
	)
	(segment
		(start 46.219618 -123.850654)
		(end 45.829982 -123.850654)
		(width 0.127)
		(layer "In5.Cu")
		(net "DEBUG_RST_BTN_N")
	)
	(segment
		(start 88.838024 -118.5418)
		(end 94.271338 -118.5418)
		(width 0.127)
		(layer "In5.Cu")
		(net "DEBUG_RST_BTN_N")
	)
	(segment
		(start 41.003474 -123.2408)
		(end 39.55034 -123.2408)
		(width 0.127)
		(layer "In5.Cu")
		(net "DEBUG_RST_BTN_N")
	)
	(segment
		(start 59.774074 -121.795286)
		(end 60.394088 -122.4153)
		(width 0.127)
		(layer "In5.Cu")
		(net "DEBUG_RST_BTN_N")
	)
	(segment
		(start 57.750964 -121.795286)
		(end 59.774074 -121.795286)
		(width 0.127)
		(layer "In5.Cu")
		(net "DEBUG_RST_BTN_N")
	)
	(segment
		(start 50.870612 -124.632466)
		(end 47.00143 -124.632466)
		(width 0.127)
		(layer "In5.Cu")
		(net "DEBUG_RST_BTN_N")
	)
	(segment
		(start 66.701924 -122.4153)
		(end 67.527424 -121.5898)
		(width 0.127)
		(layer "In5.Cu")
		(net "DEBUG_RST_BTN_N")
	)
	(segment
		(start 121.3485 -9.741662)
		(end 120.612662 -9.741662)
		(width 0.254)
		(layer "F.Cu")
		(net "AGND_CURRENT_MON")
	)
	(segment
		(start 114.20602 -14.01572)
		(end 114.373152 -13.848588)
		(width 0.508)
		(layer "F.Cu")
		(net "AGND_CURRENT_MON")
	)
	(segment
		(start 120.612662 -9.741662)
		(end 119.888 -9.017)
		(width 0.254)
		(layer "F.Cu")
		(net "AGND_CURRENT_MON")
	)
	(segment
		(start 113.484152 -14.01572)
		(end 114.20602 -14.01572)
		(width 0.508)
		(layer "F.Cu")
		(net "AGND_CURRENT_MON")
	)
	(via
		(at 117.856 -9.017)
		(size 0.5588)
		(drill 0.3048)
		(layers "F.Cu" "B.Cu")
		(net "AGND_CURRENT_MON")
	)
	(via
		(at 111.379 -6.477)
		(size 0.7112)
		(drill 0.4064)
		(layers "F.Cu" "B.Cu")
		(net "AGND_CURRENT_MON")
	)
	(via
		(at 126.272798 -10.78357)
		(size 0.6604)
		(drill 0.3302)
		(layers "F.Cu" "B.Cu")
		(net "AGND_CURRENT_MON")
	)
	(via
		(at 119.888 -9.017)
		(size 0.5588)
		(drill 0.3048)
		(layers "F.Cu" "B.Cu")
		(net "AGND_CURRENT_MON")
	)
	(via
		(at 110.49 -7.366)
		(size 0.7112)
		(drill 0.4064)
		(layers "F.Cu" "B.Cu")
		(net "AGND_CURRENT_MON")
	)
	(via
		(at 126.904242 -12.579096)
		(size 0.508)
		(drill 0.254)
		(layers "F.Cu" "B.Cu")
		(net "AGND_CURRENT_MON")
	)
	(via
		(at 118.872 -8.001)
		(size 0.5588)
		(drill 0.3048)
		(layers "F.Cu" "B.Cu")
		(net "AGND_CURRENT_MON")
	)
	(via
		(at 118.872 -10.033)
		(size 0.5588)
		(drill 0.3048)
		(layers "F.Cu" "B.Cu")
		(net "AGND_CURRENT_MON")
	)
	(via
		(at 126.929134 -11.709908)
		(size 0.508)
		(drill 0.254)
		(layers "F.Cu" "B.Cu")
		(net "AGND_CURRENT_MON")
	)
	(via
		(at 113.484152 -14.01572)
		(size 0.508)
		(drill 0.254)
		(layers "F.Cu" "B.Cu")
		(net "AGND_CURRENT_MON")
	)
	(via
		(at 111.379 -8.255)
		(size 0.7112)
		(drill 0.4064)
		(layers "F.Cu" "B.Cu")
		(net "AGND_CURRENT_MON")
	)
	(via
		(at 118.872 -8.9916)
		(size 0.5588)
		(drill 0.3048)
		(layers "F.Cu" "B.Cu")
		(net "AGND_CURRENT_MON")
	)
	(segment
		(start 111.5822 -8.0518)
		(end 111.379 -8.255)
		(width 0.508)
		(layer "B.Cu")
		(net "AGND_CURRENT_MON")
	)
	(segment
		(start 113.386362 -8.0518)
		(end 111.5822 -8.0518)
		(width 0.508)
		(layer "B.Cu")
		(net "AGND_CURRENT_MON")
	)
	(segment
		(start 119.1514 -12.5984)
		(end 119.121936 -12.568936)
		(width 0.127)
		(layer "F.Cu")
		(net "ADM1278_HS_P")
	)
	(segment
		(start 119.121936 -12.568936)
		(end 119.121936 -11.4681)
		(width 0.127)
		(layer "F.Cu")
		(net "ADM1278_HS_P")
	)
	(segment
		(start 132.9817 -13.880592)
		(end 132.918454 -13.817346)
		(width 0.127)
		(layer "F.Cu")
		(net "ADM1278_HS_P")
	)
	(segment
		(start 119.1514 -12.7)
		(end 119.1514 -12.5984)
		(width 0.127)
		(layer "F.Cu")
		(net "ADM1278_HS_P")
	)
	(segment
		(start 131.050538 -14.151356)
		(end 131.00939 -14.110208)
		(width 0.127)
		(layer "F.Cu")
		(net "ADM1278_HS_P")
	)
	(segment
		(start 133.9977 -13.880592)
		(end 132.9817 -13.880592)
		(width 0.127)
		(layer "F.Cu")
		(net "ADM1278_HS_P")
	)
	(segment
		(start 119.126 -12.7254)
		(end 119.1514 -12.7)
		(width 0.127)
		(layer "F.Cu")
		(net "ADM1278_HS_P")
	)
	(segment
		(start 132.584444 -14.151356)
		(end 131.957318 -14.151356)
		(width 0.127)
		(layer "F.Cu")
		(net "ADM1278_HS_P")
	)
	(segment
		(start 131.957318 -14.151356)
		(end 131.050538 -14.151356)
		(width 0.127)
		(layer "F.Cu")
		(net "ADM1278_HS_P")
	)
	(segment
		(start 132.918454 -13.817346)
		(end 132.584444 -14.151356)
		(width 0.127)
		(layer "F.Cu")
		(net "ADM1278_HS_P")
	)
	(via
		(at 119.126 -12.7254)
		(size 0.508)
		(drill 0.254)
		(layers "F.Cu" "B.Cu")
		(net "ADM1278_HS_P")
	)
	(via
		(at 131.00939 -14.110208)
		(size 0.508)
		(drill 0.254)
		(layers "F.Cu" "B.Cu")
		(net "ADM1278_HS_P")
	)
	(via
		(at 131.957318 -14.151356)
		(size 0.6604)
		(drill 0.3302)
		(layers "F.Cu" "B.Cu")
		(net "ADM1278_HS_P")
	)
	(segment
		(start 120.142 -13.7414)
		(end 130.640582 -13.7414)
		(width 0.127)
		(layer "In2.Cu")
		(net "ADM1278_HS_P")
	)
	(segment
		(start 119.126 -12.7254)
		(end 120.142 -13.7414)
		(width 0.127)
		(layer "In2.Cu")
		(net "ADM1278_HS_P")
	)
	(segment
		(start 130.640582 -13.7414)
		(end 131.00939 -14.110208)
		(width 0.127)
		(layer "In2.Cu")
		(net "ADM1278_HS_P")
	)
	(segment
		(start 120.0912 -12.7)
		(end 119.622062 -12.230862)
		(width 0.127)
		(layer "F.Cu")
		(net "ADM1278_HS_N")
	)
	(segment
		(start 133.806438 -12.928092)
		(end 132.9182 -12.928092)
		(width 0.127)
		(layer "F.Cu")
		(net "ADM1278_HS_N")
	)
	(segment
		(start 132.9182 -12.928092)
		(end 132.918454 -12.928346)
		(width 0.127)
		(layer "F.Cu")
		(net "ADM1278_HS_N")
	)
	(segment
		(start 130.9878 -12.928346)
		(end 131.951222 -12.928346)
		(width 0.127)
		(layer "F.Cu")
		(net "ADM1278_HS_N")
	)
	(segment
		(start 119.622062 -12.230862)
		(end 119.622062 -11.4681)
		(width 0.127)
		(layer "F.Cu")
		(net "ADM1278_HS_N")
	)
	(segment
		(start 132.918454 -12.928346)
		(end 131.951222 -12.928346)
		(width 0.127)
		(layer "F.Cu")
		(net "ADM1278_HS_N")
	)
	(segment
		(start 133.996938 -12.737592)
		(end 133.806438 -12.928092)
		(width 0.127)
		(layer "F.Cu")
		(net "ADM1278_HS_N")
	)
	(via
		(at 120.0912 -12.7)
		(size 0.508)
		(drill 0.254)
		(layers "F.Cu" "B.Cu")
		(net "ADM1278_HS_N")
	)
	(via
		(at 131.951222 -12.928346)
		(size 0.6604)
		(drill 0.3302)
		(layers "F.Cu" "B.Cu")
		(net "ADM1278_HS_N")
	)
	(via
		(at 130.9878 -12.928346)
		(size 0.508)
		(drill 0.254)
		(layers "F.Cu" "B.Cu")
		(net "ADM1278_HS_N")
	)
	(segment
		(start 130.9878 -12.928346)
		(end 130.622294 -12.928346)
		(width 0.127)
		(layer "In2.Cu")
		(net "ADM1278_HS_N")
	)
	(segment
		(start 130.622294 -12.928346)
		(end 130.36804 -13.1826)
		(width 0.127)
		(layer "In2.Cu")
		(net "ADM1278_HS_N")
	)
	(segment
		(start 123.822206 -13.1826)
		(end 123.34748 -12.707874)
		(width 0.127)
		(layer "In2.Cu")
		(net "ADM1278_HS_N")
	)
	(segment
		(start 130.36804 -13.1826)
		(end 123.822206 -13.1826)
		(width 0.127)
		(layer "In2.Cu")
		(net "ADM1278_HS_N")
	)
	(segment
		(start 123.34748 -12.707874)
		(end 120.099074 -12.707874)
		(width 0.127)
		(layer "In2.Cu")
		(net "ADM1278_HS_N")
	)
	(segment
		(start 120.099074 -12.707874)
		(end 120.0912 -12.7)
		(width 0.127)
		(layer "In2.Cu")
		(net "ADM1278_HS_N")
	)
	(segment
		(start 98.24212 -159.65932)
		(end 98.853244 -159.65932)
		(width 0.127)
		(layer "F.Cu")
		(net "VBUS_DET")
	)
	(segment
		(start 97.0788 -158.496)
		(end 96.9264 -158.496)
		(width 0.127)
		(layer "F.Cu")
		(net "VBUS_DET")
	)
	(segment
		(start 97.5868 -159.004)
		(end 98.24212 -159.65932)
		(width 0.127)
		(layer "F.Cu")
		(net "VBUS_DET")
	)
	(segment
		(start 97.5868 -159.004)
		(end 97.0788 -158.496)
		(width 0.127)
		(layer "F.Cu")
		(net "VBUS_DET")
	)
	(segment
		(start 96.9264 -158.496)
		(end 96.035876 -157.605476)
		(width 0.127)
		(layer "F.Cu")
		(net "VBUS_DET")
	)
	(segment
		(start 96.035876 -157.605476)
		(end 95.710756 -157.605476)
		(width 0.127)
		(layer "F.Cu")
		(net "VBUS_DET")
	)
	(via
		(at 97.5868 -159.004)
		(size 0.6604)
		(drill 0.3302)
		(layers "F.Cu" "B.Cu")
		(net "VBUS_DET")
	)
	(segment
		(start 98.8441 -162.0266)
		(end 98.8441 -160.9979)
		(width 0.127)
		(layer "F.Cu")
		(net "USB_SUSP_IND")
	)
	(segment
		(start 97.6884 -160.2486)
		(end 98.0948 -160.2486)
		(width 0.127)
		(layer "F.Cu")
		(net "USB_SUSP_IND")
	)
	(segment
		(start 96.00438 -158.56458)
		(end 97.6884 -160.2486)
		(width 0.127)
		(layer "F.Cu")
		(net "USB_SUSP_IND")
	)
	(segment
		(start 98.8441 -160.9979)
		(end 98.7298 -160.8836)
		(width 0.127)
		(layer "F.Cu")
		(net "USB_SUSP_IND")
	)
	(segment
		(start 94.751652 -158.56458)
		(end 96.00438 -158.56458)
		(width 0.127)
		(layer "F.Cu")
		(net "USB_SUSP_IND")
	)
	(segment
		(start 98.0948 -160.2486)
		(end 98.7298 -160.8836)
		(width 0.127)
		(layer "F.Cu")
		(net "USB_SUSP_IND")
	)
	(via
		(at 98.7298 -160.8836)
		(size 0.6604)
		(drill 0.3302)
		(layers "F.Cu" "B.Cu")
		(net "USB_SUSP_IND")
	)
	(segment
		(start 95.621856 -157.105604)
		(end 96.534986 -157.105604)
		(width 0.127)
		(layer "F.Cu")
		(net "USB_RESET_N")
	)
	(segment
		(start 97.361502 -157.93212)
		(end 97.484692 -158.05531)
		(width 0.127)
		(layer "F.Cu")
		(net "USB_RESET_N")
	)
	(segment
		(start 96.534986 -157.105604)
		(end 97.361502 -157.93212)
		(width 0.127)
		(layer "F.Cu")
		(net "USB_RESET_N")
	)
	(segment
		(start 97.484692 -158.05531)
		(end 98.839274 -158.05531)
		(width 0.127)
		(layer "F.Cu")
		(net "USB_RESET_N")
	)
	(via
		(at 97.361502 -157.93212)
		(size 0.508)
		(drill 0.254)
		(layers "F.Cu" "B.Cu")
		(net "USB_RESET_N")
	)
	(segment
		(start 95.743776 -158.1277)
		(end 95.939356 -157.93212)
		(width 0.127)
		(layer "B.Cu")
		(net "USB_RESET_N")
	)
	(segment
		(start 95.939356 -157.93212)
		(end 97.361502 -157.93212)
		(width 0.127)
		(layer "B.Cu")
		(net "USB_RESET_N")
	)
	(segment
		(start 94.8436 -158.1277)
		(end 95.743776 -158.1277)
		(width 0.127)
		(layer "B.Cu")
		(net "USB_RESET_N")
	)
	(segment
		(start 98.9457 -152.7302)
		(end 98.3234 -152.7302)
		(width 0.127)
		(layer "F.Cu")
		(net "USB_OCS_N4")
	)
	(segment
		(start 96.448118 -154.605482)
		(end 95.621856 -154.605482)
		(width 0.127)
		(layer "F.Cu")
		(net "USB_OCS_N4")
	)
	(segment
		(start 98.3234 -152.7302)
		(end 97.409 -153.6446)
		(width 0.127)
		(layer "F.Cu")
		(net "USB_OCS_N4")
	)
	(segment
		(start 97.409 -153.6446)
		(end 96.448118 -154.605482)
		(width 0.127)
		(layer "F.Cu")
		(net "USB_OCS_N4")
	)
	(via
		(at 97.409 -153.6446)
		(size 0.6604)
		(drill 0.3302)
		(layers "F.Cu" "B.Cu")
		(net "USB_OCS_N4")
	)
	(segment
		(start 97.54235 -151.00935)
		(end 98.9203 -149.6314)
		(width 0.127)
		(layer "F.Cu")
		(net "USB_OCS_N3")
	)
	(segment
		(start 95.710756 -153.605484)
		(end 95.710756 -152.840944)
		(width 0.127)
		(layer "F.Cu")
		(net "USB_OCS_N3")
	)
	(segment
		(start 95.710756 -152.840944)
		(end 97.54235 -151.00935)
		(width 0.127)
		(layer "F.Cu")
		(net "USB_OCS_N3")
	)
	(via
		(at 97.54235 -151.00935)
		(size 0.6604)
		(drill 0.3302)
		(layers "F.Cu" "B.Cu")
		(net "USB_OCS_N3")
	)
	(segment
		(start 94.25178 -151.892)
		(end 94.25178 -152.73528)
		(width 0.127)
		(layer "F.Cu")
		(net "USB_OCS_N2")
	)
	(segment
		(start 95.25 -151.0538)
		(end 95.08998 -151.0538)
		(width 0.127)
		(layer "F.Cu")
		(net "USB_OCS_N2")
	)
	(segment
		(start 95.7834 -150.5204)
		(end 95.25 -151.0538)
		(width 0.127)
		(layer "F.Cu")
		(net "USB_OCS_N2")
	)
	(segment
		(start 97.282 -148.463)
		(end 96.2914 -149.4536)
		(width 0.127)
		(layer "F.Cu")
		(net "USB_OCS_N2")
	)
	(segment
		(start 97.282 -148.2979)
		(end 97.282 -148.463)
		(width 0.127)
		(layer "F.Cu")
		(net "USB_OCS_N2")
	)
	(segment
		(start 95.08998 -151.0538)
		(end 94.25178 -151.892)
		(width 0.127)
		(layer "F.Cu")
		(net "USB_OCS_N2")
	)
	(segment
		(start 95.7834 -149.9616)
		(end 95.7834 -150.5204)
		(width 0.127)
		(layer "F.Cu")
		(net "USB_OCS_N2")
	)
	(segment
		(start 96.2914 -149.4536)
		(end 95.7834 -149.9616)
		(width 0.127)
		(layer "F.Cu")
		(net "USB_OCS_N2")
	)
	(via
		(at 96.2914 -149.4536)
		(size 0.6604)
		(drill 0.3302)
		(layers "F.Cu" "B.Cu")
		(net "USB_OCS_N2")
	)
	(segment
		(start 92.992956 -161.52368)
		(end 92.992956 -162.37458)
		(width 0.127)
		(layer "F.Cu")
		(net "USB_HUB_XTAL_OUT")
	)
	(segment
		(start 93.132656 -162.51428)
		(end 93.132656 -163.212526)
		(width 0.127)
		(layer "F.Cu")
		(net "USB_HUB_XTAL_OUT")
	)
	(segment
		(start 93.132656 -163.212526)
		(end 92.865956 -163.479226)
		(width 0.127)
		(layer "F.Cu")
		(net "USB_HUB_XTAL_OUT")
	)
	(segment
		(start 93.171518 -165.564058)
		(end 93.795342 -165.564058)
		(width 0.127)
		(layer "F.Cu")
		(net "USB_HUB_XTAL_OUT")
	)
	(segment
		(start 92.992956 -162.37458)
		(end 93.132656 -162.51428)
		(width 0.127)
		(layer "F.Cu")
		(net "USB_HUB_XTAL_OUT")
	)
	(segment
		(start 92.865956 -163.479226)
		(end 92.865956 -165.258496)
		(width 0.127)
		(layer "F.Cu")
		(net "USB_HUB_XTAL_OUT")
	)
	(segment
		(start 92.865956 -165.258496)
		(end 93.171518 -165.564058)
		(width 0.127)
		(layer "F.Cu")
		(net "USB_HUB_XTAL_OUT")
	)
	(segment
		(start 92.992956 -160.963356)
		(end 92.992956 -161.52368)
		(width 0.127)
		(layer "F.Cu")
		(net "USB_HUB_XTAL_OUT")
	)
	(segment
		(start 92.751656 -160.722056)
		(end 92.992956 -160.963356)
		(width 0.127)
		(layer "F.Cu")
		(net "USB_HUB_XTAL_OUT")
	)
	(segment
		(start 92.751656 -158.47568)
		(end 92.751656 -160.722056)
		(width 0.127)
		(layer "F.Cu")
		(net "USB_HUB_XTAL_OUT")
	)
	(segment
		(start 92.084144 -163.419536)
		(end 92.084144 -162.52952)
		(width 0.127)
		(layer "F.Cu")
		(net "USB_HUB_XTAL_IN")
	)
	(segment
		(start 92.103956 -161.52368)
		(end 92.25153 -161.376106)
		(width 0.127)
		(layer "F.Cu")
		(net "USB_HUB_XTAL_IN")
	)
	(segment
		(start 92.084144 -162.52952)
		(end 92.103956 -162.509708)
		(width 0.127)
		(layer "F.Cu")
		(net "USB_HUB_XTAL_IN")
	)
	(segment
		(start 92.103956 -162.509708)
		(end 92.103956 -161.52368)
		(width 0.127)
		(layer "F.Cu")
		(net "USB_HUB_XTAL_IN")
	)
	(segment
		(start 91.452446 -164.051234)
		(end 92.084144 -163.419536)
		(width 0.127)
		(layer "F.Cu")
		(net "USB_HUB_XTAL_IN")
	)
	(segment
		(start 92.25153 -161.376106)
		(end 92.25153 -158.47568)
		(width 0.127)
		(layer "F.Cu")
		(net "USB_HUB_XTAL_IN")
	)
	(segment
		(start 98.7933 -151.8412)
		(end 98.9457 -151.6888)
		(width 0.127)
		(layer "F.Cu")
		(net "USB_EN_4")
	)
	(segment
		(start 98.9457 -151.6888)
		(end 98.9457 -150.6982)
		(width 0.127)
		(layer "F.Cu")
		(net "USB_EN_4")
	)
	(segment
		(start 96.369378 -154.105356)
		(end 95.621856 -154.105356)
		(width 0.127)
		(layer "F.Cu")
		(net "USB_EN_4")
	)
	(segment
		(start 98.9457 -150.6982)
		(end 98.9203 -150.6728)
		(width 0.127)
		(layer "F.Cu")
		(net "USB_EN_4")
	)
	(segment
		(start 96.606106 -153.868628)
		(end 96.369378 -154.105356)
		(width 0.127)
		(layer "F.Cu")
		(net "USB_EN_4")
	)
	(segment
		(start 96.606106 -152.872694)
		(end 96.606106 -153.868628)
		(width 0.127)
		(layer "F.Cu")
		(net "USB_EN_4")
	)
	(segment
		(start 97.6376 -151.8412)
		(end 98.7933 -151.8412)
		(width 0.127)
		(layer "F.Cu")
		(net "USB_EN_4")
	)
	(segment
		(start 97.3836 -152.0952)
		(end 96.606106 -152.872694)
		(width 0.127)
		(layer "F.Cu")
		(net "USB_EN_4")
	)
	(segment
		(start 97.3836 -152.0952)
		(end 97.6376 -151.8412)
		(width 0.127)
		(layer "F.Cu")
		(net "USB_EN_4")
	)
	(via
		(at 97.3836 -152.0952)
		(size 0.6604)
		(drill 0.3302)
		(layers "F.Cu" "B.Cu")
		(net "USB_EN_4")
	)
	(segment
		(start 96.1136 -151.0792)
		(end 96.6978 -151.0792)
		(width 0.127)
		(layer "F.Cu")
		(net "USB_EN_3")
	)
	(segment
		(start 96.6978 -151.0792)
		(end 97.409 -150.368)
		(width 0.127)
		(layer "F.Cu")
		(net "USB_EN_3")
	)
	(segment
		(start 98.35388 -148.61032)
		(end 98.929444 -148.61032)
		(width 0.127)
		(layer "F.Cu")
		(net "USB_EN_3")
	)
	(segment
		(start 94.751652 -152.091136)
		(end 95.763588 -151.0792)
		(width 0.127)
		(layer "F.Cu")
		(net "USB_EN_3")
	)
	(segment
		(start 97.409 -150.368)
		(end 97.409 -149.5552)
		(width 0.127)
		(layer "F.Cu")
		(net "USB_EN_3")
	)
	(segment
		(start 97.409 -149.5552)
		(end 98.35388 -148.61032)
		(width 0.127)
		(layer "F.Cu")
		(net "USB_EN_3")
	)
	(segment
		(start 95.763588 -151.0792)
		(end 96.1136 -151.0792)
		(width 0.127)
		(layer "F.Cu")
		(net "USB_EN_3")
	)
	(segment
		(start 94.751652 -152.64638)
		(end 94.751652 -152.091136)
		(width 0.127)
		(layer "F.Cu")
		(net "USB_EN_3")
	)
	(via
		(at 96.1136 -151.0792)
		(size 0.508)
		(drill 0.254)
		(layers "F.Cu" "B.Cu")
		(net "USB_EN_3")
	)
	(via
		(at 97.409 -149.5552)
		(size 0.6604)
		(drill 0.3302)
		(layers "F.Cu" "B.Cu")
		(net "USB_EN_3")
	)
	(segment
		(start 96.52 -151.9809)
		(end 96.52 -151.4856)
		(width 0.127)
		(layer "B.Cu")
		(net "USB_EN_3")
	)
	(segment
		(start 96.52 -151.4856)
		(end 96.1136 -151.0792)
		(width 0.127)
		(layer "B.Cu")
		(net "USB_EN_3")
	)
	(segment
		(start 93.751654 -151.642572)
		(end 93.751654 -152.73528)
		(width 0.127)
		(layer "F.Cu")
		(net "USB_EN_2")
	)
	(segment
		(start 95.128588 -150.265638)
		(end 95.128588 -149.079712)
		(width 0.127)
		(layer "F.Cu")
		(net "USB_EN_2")
	)
	(segment
		(start 95.128588 -150.265638)
		(end 93.751654 -151.642572)
		(width 0.127)
		(layer "F.Cu")
		(net "USB_EN_2")
	)
	(segment
		(start 96.2152 -148.2979)
		(end 95.9104 -148.2979)
		(width 0.127)
		(layer "F.Cu")
		(net "USB_EN_2")
	)
	(segment
		(start 95.9104 -148.2979)
		(end 95.1484 -149.0599)
		(width 0.127)
		(layer "F.Cu")
		(net "USB_EN_2")
	)
	(segment
		(start 95.128588 -149.079712)
		(end 95.1484 -149.0599)
		(width 0.127)
		(layer "F.Cu")
		(net "USB_EN_2")
	)
	(via
		(at 95.128588 -150.265638)
		(size 0.6604)
		(drill 0.3302)
		(layers "F.Cu" "B.Cu")
		(net "USB_EN_2")
	)
	(segment
		(start 92.202 -28.067)
		(end 92.202 -28.51404)
		(width 0.127)
		(layer "F.Cu")
		(net "USB_EN_1")
	)
	(segment
		(start 88.859106 -149.607524)
		(end 89.212674 -149.253956)
		(width 0.127)
		(layer "F.Cu")
		(net "USB_EN_1")
	)
	(segment
		(start 86.5886 -70.509384)
		(end 84.806028 -68.726812)
		(width 0.127)
		(layer "F.Cu")
		(net "USB_EN_1")
	)
	(segment
		(start 89.589864 -150.91029)
		(end 89.120218 -150.91029)
		(width 0.127)
		(layer "F.Cu")
		(net "USB_EN_1")
	)
	(segment
		(start 89.212674 -149.253956)
		(end 89.52992 -149.253956)
		(width 0.127)
		(layer "F.Cu")
		(net "USB_EN_1")
	)
	(segment
		(start 88.392 -98.6282)
		(end 86.5886 -96.8248)
		(width 0.127)
		(layer "F.Cu")
		(net "USB_EN_1")
	)
	(segment
		(start 89.903554 -150.5966)
		(end 89.589864 -150.91029)
		(width 0.127)
		(layer "F.Cu")
		(net "USB_EN_1")
	)
	(segment
		(start 90.7288 -150.5966)
		(end 91.072208 -150.5966)
		(width 0.127)
		(layer "F.Cu")
		(net "USB_EN_1")
	)
	(segment
		(start 86.5886 -96.8248)
		(end 86.5886 -70.509384)
		(width 0.127)
		(layer "F.Cu")
		(net "USB_EN_1")
	)
	(segment
		(start 88.392 -99.388676)
		(end 88.392 -98.6282)
		(width 0.127)
		(layer "F.Cu")
		(net "USB_EN_1")
	)
	(segment
		(start 89.120218 -150.91029)
		(end 88.859106 -150.649178)
		(width 0.127)
		(layer "F.Cu")
		(net "USB_EN_1")
	)
	(segment
		(start 90.7288 -150.5966)
		(end 89.903554 -150.5966)
		(width 0.127)
		(layer "F.Cu")
		(net "USB_EN_1")
	)
	(segment
		(start 91.072208 -150.5966)
		(end 91.751658 -151.27605)
		(width 0.127)
		(layer "F.Cu")
		(net "USB_EN_1")
	)
	(segment
		(start 88.859106 -150.649178)
		(end 88.859106 -149.607524)
		(width 0.127)
		(layer "F.Cu")
		(net "USB_EN_1")
	)
	(segment
		(start 88.393524 -99.3902)
		(end 88.392 -99.388676)
		(width 0.127)
		(layer "F.Cu")
		(net "USB_EN_1")
	)
	(segment
		(start 91.751658 -151.27605)
		(end 91.751658 -152.73528)
		(width 0.127)
		(layer "F.Cu")
		(net "USB_EN_1")
	)
	(segment
		(start 90.297 -27.686)
		(end 91.821 -27.686)
		(width 0.127)
		(layer "F.Cu")
		(net "USB_EN_1")
	)
	(segment
		(start 91.821 -27.686)
		(end 92.202 -28.067)
		(width 0.127)
		(layer "F.Cu")
		(net "USB_EN_1")
	)
	(via
		(at 89.589864 -150.91029)
		(size 0.508)
		(drill 0.254)
		(layers "F.Cu" "B.Cu")
		(net "USB_EN_1")
	)
	(via
		(at 91.2876 -114.7064)
		(size 0.508)
		(drill 0.254)
		(layers "F.Cu" "B.Cu")
		(net "USB_EN_1")
	)
	(via
		(at 90.7288 -150.5966)
		(size 0.6604)
		(drill 0.3302)
		(layers "F.Cu" "B.Cu")
		(net "USB_EN_1")
	)
	(via
		(at 88.393524 -99.3902)
		(size 0.508)
		(drill 0.254)
		(layers "F.Cu" "B.Cu")
		(net "USB_EN_1")
	)
	(via
		(at 84.806028 -68.726812)
		(size 0.508)
		(drill 0.254)
		(layers "F.Cu" "B.Cu")
		(net "USB_EN_1")
	)
	(via
		(at 90.297 -27.686)
		(size 0.508)
		(drill 0.254)
		(layers "F.Cu" "B.Cu")
		(net "USB_EN_1")
	)
	(segment
		(start 90.678 -149.9235)
		(end 89.69121 -150.91029)
		(width 0.127)
		(layer "B.Cu")
		(net "USB_EN_1")
	)
	(segment
		(start 89.69121 -150.91029)
		(end 89.589864 -150.91029)
		(width 0.127)
		(layer "B.Cu")
		(net "USB_EN_1")
	)
	(segment
		(start 90.9701 -126.481078)
		(end 91.2114 -126.239778)
		(width 0.127)
		(layer "In2.Cu")
		(net "USB_EN_1")
	)
	(segment
		(start 89.789 -144.747488)
		(end 91.127834 -143.408654)
		(width 0.127)
		(layer "In2.Cu")
		(net "USB_EN_1")
	)
	(segment
		(start 89.057988 -150.378414)
		(end 89.057988 -146.8755)
		(width 0.127)
		(layer "In2.Cu")
		(net "USB_EN_1")
	)
	(segment
		(start 89.589864 -150.91029)
		(end 89.057988 -150.378414)
		(width 0.127)
		(layer "In2.Cu")
		(net "USB_EN_1")
	)
	(segment
		(start 91.127834 -131.36372)
		(end 90.9701 -131.205986)
		(width 0.127)
		(layer "In2.Cu")
		(net "USB_EN_1")
	)
	(segment
		(start 89.789 -146.144488)
		(end 89.789 -144.747488)
		(width 0.127)
		(layer "In2.Cu")
		(net "USB_EN_1")
	)
	(segment
		(start 91.127834 -143.408654)
		(end 91.127834 -131.36372)
		(width 0.127)
		(layer "In2.Cu")
		(net "USB_EN_1")
	)
	(segment
		(start 91.3384 -114.7572)
		(end 91.2876 -114.7064)
		(width 0.127)
		(layer "In2.Cu")
		(net "USB_EN_1")
	)
	(segment
		(start 91.3384 -120.1674)
		(end 91.3384 -114.7572)
		(width 0.127)
		(layer "In2.Cu")
		(net "USB_EN_1")
	)
	(segment
		(start 91.2114 -126.239778)
		(end 91.2114 -120.2944)
		(width 0.127)
		(layer "In2.Cu")
		(net "USB_EN_1")
	)
	(segment
		(start 89.057988 -146.8755)
		(end 89.789 -146.144488)
		(width 0.127)
		(layer "In2.Cu")
		(net "USB_EN_1")
	)
	(segment
		(start 91.2114 -120.2944)
		(end 91.3384 -120.1674)
		(width 0.127)
		(layer "In2.Cu")
		(net "USB_EN_1")
	)
	(segment
		(start 90.9701 -131.205986)
		(end 90.9701 -126.481078)
		(width 0.127)
		(layer "In2.Cu")
		(net "USB_EN_1")
	)
	(segment
		(start 88.393524 -99.3902)
		(end 88.392 -99.391724)
		(width 0.127)
		(layer "In5.Cu")
		(net "USB_EN_1")
	)
	(segment
		(start 92.964 -104.653588)
		(end 92.964 -114.915442)
		(width 0.127)
		(layer "In5.Cu")
		(net "USB_EN_1")
	)
	(segment
		(start 88.082374 -40.367458)
		(end 83.8454 -44.604432)
		(width 0.127)
		(layer "In5.Cu")
		(net "USB_EN_1")
	)
	(segment
		(start 84.432394 -50.318162)
		(end 84.432394 -60.259468)
		(width 0.127)
		(layer "In5.Cu")
		(net "USB_EN_1")
	)
	(segment
		(start 91.730068 -115.148868)
		(end 91.2876 -114.7064)
		(width 0.127)
		(layer "In5.Cu")
		(net "USB_EN_1")
	)
	(segment
		(start 89.23147 -29.64053)
		(end 88.082374 -30.789626)
		(width 0.127)
		(layer "In5.Cu")
		(net "USB_EN_1")
	)
	(segment
		(start 83.8454 -49.731168)
		(end 84.432394 -50.318162)
		(width 0.127)
		(layer "In5.Cu")
		(net "USB_EN_1")
	)
	(segment
		(start 88.392 -99.391724)
		(end 88.392 -100.081588)
		(width 0.127)
		(layer "In5.Cu")
		(net "USB_EN_1")
	)
	(segment
		(start 83.8454 -44.604432)
		(end 83.8454 -49.731168)
		(width 0.127)
		(layer "In5.Cu")
		(net "USB_EN_1")
	)
	(segment
		(start 89.23147 -28.75153)
		(end 89.23147 -29.64053)
		(width 0.127)
		(layer "In5.Cu")
		(net "USB_EN_1")
	)
	(segment
		(start 88.082374 -30.789626)
		(end 88.082374 -40.367458)
		(width 0.127)
		(layer "In5.Cu")
		(net "USB_EN_1")
	)
	(segment
		(start 92.964 -114.915442)
		(end 92.730574 -115.148868)
		(width 0.127)
		(layer "In5.Cu")
		(net "USB_EN_1")
	)
	(segment
		(start 92.730574 -115.148868)
		(end 91.730068 -115.148868)
		(width 0.127)
		(layer "In5.Cu")
		(net "USB_EN_1")
	)
	(segment
		(start 83.8962 -67.816984)
		(end 84.806028 -68.726812)
		(width 0.127)
		(layer "In5.Cu")
		(net "USB_EN_1")
	)
	(segment
		(start 84.432394 -60.259468)
		(end 83.8962 -60.795662)
		(width 0.127)
		(layer "In5.Cu")
		(net "USB_EN_1")
	)
	(segment
		(start 90.297 -27.686)
		(end 89.23147 -28.75153)
		(width 0.127)
		(layer "In5.Cu")
		(net "USB_EN_1")
	)
	(segment
		(start 88.392 -100.081588)
		(end 92.964 -104.653588)
		(width 0.127)
		(layer "In5.Cu")
		(net "USB_EN_1")
	)
	(segment
		(start 83.8962 -60.795662)
		(end 83.8962 -67.816984)
		(width 0.127)
		(layer "In5.Cu")
		(net "USB_EN_1")
	)
	(segment
		(start 183.9468 -101.18852)
		(end 182.771796 -102.363524)
		(width 0.127)
		(layer "F.Cu")
		(net "TEMP_1_ALERT")
	)
	(segment
		(start 182.771796 -102.363524)
		(end 182.771796 -103.32339)
		(width 0.127)
		(layer "F.Cu")
		(net "TEMP_1_ALERT")
	)
	(segment
		(start 185.1406 -108.4072)
		(end 186.3725 -108.4072)
		(width 0.127)
		(layer "F.Cu")
		(net "TEMP_1_A2")
	)
	(segment
		(start 183.422036 -107.43311)
		(end 183.422036 -108.034836)
		(width 0.127)
		(layer "F.Cu")
		(net "TEMP_1_A2")
	)
	(segment
		(start 183.422036 -108.034836)
		(end 183.7944 -108.4072)
		(width 0.127)
		(layer "F.Cu")
		(net "TEMP_1_A2")
	)
	(segment
		(start 186.3725 -108.4072)
		(end 186.3725 -109.474)
		(width 0.127)
		(layer "F.Cu")
		(net "TEMP_1_A2")
	)
	(segment
		(start 183.7944 -108.4072)
		(end 185.1406 -108.4072)
		(width 0.127)
		(layer "F.Cu")
		(net "TEMP_1_A2")
	)
	(via
		(at 185.1406 -108.4072)
		(size 0.6604)
		(drill 0.3302)
		(layers "F.Cu" "B.Cu")
		(net "TEMP_1_A2")
	)
	(segment
		(start 53.299614 -146.59991)
		(end 53.299614 -146.599656)
		(width 0.127)
		(layer "F.Cu")
		(net "RMII_BMC_MDIO_R")
	)
	(segment
		(start 53.299614 -146.599656)
		(end 52.899818 -146.19986)
		(width 0.127)
		(layer "F.Cu")
		(net "RMII_BMC_MDIO_R")
	)
	(via
		(at 53.299614 -146.59991)
		(size 0.4572)
		(drill 0.2032)
		(layers "F.Cu" "B.Cu")
		(net "RMII_BMC_MDIO_R")
	)
	(segment
		(start 52.905914 -145.118074)
		(end 52.905914 -145.963386)
		(width 0.127)
		(layer "B.Cu")
		(net "RMII_BMC_MDIO_R")
	)
	(segment
		(start 52.905914 -145.963386)
		(end 53.0987 -146.156172)
		(width 0.127)
		(layer "B.Cu")
		(net "RMII_BMC_MDIO_R")
	)
	(segment
		(start 53.0987 -146.156172)
		(end 53.0987 -146.398996)
		(width 0.127)
		(layer "B.Cu")
		(net "RMII_BMC_MDIO_R")
	)
	(segment
		(start 52.78628 -144.99844)
		(end 52.905914 -145.118074)
		(width 0.127)
		(layer "B.Cu")
		(net "RMII_BMC_MDIO_R")
	)
	(segment
		(start 53.0987 -146.398996)
		(end 53.299614 -146.59991)
		(width 0.127)
		(layer "B.Cu")
		(net "RMII_BMC_MDIO_R")
	)
	(segment
		(start 53.699918 -147.800314)
		(end 53.699918 -147.80006)
		(width 0.127)
		(layer "F.Cu")
		(net "RMII_BMC_MDC_R")
	)
	(segment
		(start 54.099714 -148.20011)
		(end 53.699918 -147.800314)
		(width 0.127)
		(layer "F.Cu")
		(net "RMII_BMC_MDC_R")
	)
	(via
		(at 54.099714 -148.20011)
		(size 0.4572)
		(drill 0.2032)
		(layers "F.Cu" "B.Cu")
		(net "RMII_BMC_MDC_R")
	)
	(segment
		(start 52.905914 -147.563332)
		(end 53.136292 -147.79371)
		(width 0.127)
		(layer "B.Cu")
		(net "RMII_BMC_MDC_R")
	)
	(segment
		(start 53.136292 -147.79371)
		(end 53.693314 -147.79371)
		(width 0.127)
		(layer "B.Cu")
		(net "RMII_BMC_MDC_R")
	)
	(segment
		(start 52.5526 -146.5834)
		(end 52.905914 -146.936714)
		(width 0.127)
		(layer "B.Cu")
		(net "RMII_BMC_MDC_R")
	)
	(segment
		(start 53.693314 -147.79371)
		(end 54.099714 -148.20011)
		(width 0.127)
		(layer "B.Cu")
		(net "RMII_BMC_MDC_R")
	)
	(segment
		(start 52.905914 -146.936714)
		(end 52.905914 -147.563332)
		(width 0.127)
		(layer "B.Cu")
		(net "RMII_BMC_MDC_R")
	)
	(segment
		(start 90.079576 -159.5755)
		(end 91.0717 -159.5755)
		(width 0.127)
		(layer "F.Cu")
		(net "RBIAS")
	)
	(segment
		(start 88.31072 -161.598356)
		(end 88.31072 -161.344356)
		(width 0.127)
		(layer "F.Cu")
		(net "RBIAS")
	)
	(segment
		(start 91.251532 -159.395668)
		(end 91.251532 -158.47568)
		(width 0.127)
		(layer "F.Cu")
		(net "RBIAS")
	)
	(segment
		(start 88.31072 -161.344356)
		(end 90.079576 -159.5755)
		(width 0.127)
		(layer "F.Cu")
		(net "RBIAS")
	)
	(segment
		(start 91.0717 -159.5755)
		(end 91.251532 -159.395668)
		(width 0.127)
		(layer "F.Cu")
		(net "RBIAS")
	)
	(segment
		(start 215.625172 -54.854856)
		(end 215.625172 -55.629556)
		(width 0.254)
		(layer "F.Cu")
		(net "PWRGD_P5V_STBY")
	)
	(segment
		(start 219.383864 -46.131988)
		(end 219.383864 -45.138848)
		(width 0.254)
		(layer "F.Cu")
		(net "PWRGD_P5V_STBY")
	)
	(segment
		(start 41.719246 -176.69891)
		(end 42.546016 -176.69891)
		(width 0.254)
		(layer "F.Cu")
		(net "PWRGD_P5V_STBY")
	)
	(segment
		(start 42.546016 -176.69891)
		(end 42.741342 -176.894236)
		(width 0.254)
		(layer "F.Cu")
		(net "PWRGD_P5V_STBY")
	)
	(segment
		(start 219.034868 -44.220892)
		(end 217.077036 -42.26306)
		(width 0.254)
		(layer "F.Cu")
		(net "PWRGD_P5V_STBY")
	)
	(segment
		(start 219.383864 -45.138848)
		(end 219.034868 -44.789852)
		(width 0.254)
		(layer "F.Cu")
		(net "PWRGD_P5V_STBY")
	)
	(segment
		(start 218.089988 -41.291256)
		(end 217.072718 -41.291256)
		(width 0.254)
		(layer "F.Cu")
		(net "PWRGD_P5V_STBY")
	)
	(segment
		(start 75.1078 -110.7948)
		(end 73.4822 -112.4204)
		(width 0.254)
		(layer "F.Cu")
		(net "PWRGD_P5V_STBY")
	)
	(segment
		(start 217.072718 -41.291256)
		(end 217.067384 -41.29659)
		(width 0.254)
		(layer "F.Cu")
		(net "PWRGD_P5V_STBY")
	)
	(segment
		(start 75.1078 -108.8136)
		(end 75.1078 -110.7948)
		(width 0.254)
		(layer "F.Cu")
		(net "PWRGD_P5V_STBY")
	)
	(segment
		(start 217.077036 -42.26306)
		(end 217.067384 -42.253408)
		(width 0.254)
		(layer "F.Cu")
		(net "PWRGD_P5V_STBY")
	)
	(segment
		(start 73.4822 -112.4204)
		(end 68.2498 -112.4204)
		(width 0.254)
		(layer "F.Cu")
		(net "PWRGD_P5V_STBY")
	)
	(segment
		(start 215.625172 -55.629556)
		(end 215.612472 -55.642256)
		(width 0.254)
		(layer "F.Cu")
		(net "PWRGD_P5V_STBY")
	)
	(segment
		(start 217.067384 -42.253408)
		(end 217.067384 -41.29659)
		(width 0.254)
		(layer "F.Cu")
		(net "PWRGD_P5V_STBY")
	)
	(segment
		(start 68.2498 -112.4204)
		(end 67.4116 -113.2586)
		(width 0.254)
		(layer "F.Cu")
		(net "PWRGD_P5V_STBY")
	)
	(segment
		(start 219.034868 -44.789852)
		(end 219.034868 -44.220892)
		(width 0.254)
		(layer "F.Cu")
		(net "PWRGD_P5V_STBY")
	)
	(segment
		(start 67.4116 -113.2586)
		(end 67.4116 -113.3094)
		(width 0.254)
		(layer "F.Cu")
		(net "PWRGD_P5V_STBY")
	)
	(via
		(at 75.1078 -108.8136)
		(size 0.508)
		(drill 0.254)
		(layers "F.Cu" "B.Cu")
		(net "PWRGD_P5V_STBY")
	)
	(via
		(at 67.82943 -176.753774)
		(size 0.508)
		(drill 0.254)
		(layers "F.Cu" "B.Cu")
		(net "PWRGD_P5V_STBY")
	)
	(via
		(at 215.612472 -55.642256)
		(size 0.508)
		(drill 0.254)
		(layers "F.Cu" "B.Cu")
		(net "PWRGD_P5V_STBY")
	)
	(via
		(at 63.337694 -176.0474)
		(size 0.6096)
		(drill 0.3048)
		(layers "F.Cu" "B.Cu")
		(net "PWRGD_P5V_STBY")
	)
	(via
		(at 217.077036 -42.26306)
		(size 0.508)
		(drill 0.254)
		(layers "F.Cu" "B.Cu")
		(net "PWRGD_P5V_STBY")
	)
	(via
		(at 67.4116 -113.3094)
		(size 0.5588)
		(drill 0.3048)
		(layers "F.Cu" "B.Cu")
		(net "PWRGD_P5V_STBY")
	)
	(via
		(at 42.741342 -176.894236)
		(size 0.508)
		(drill 0.254)
		(layers "F.Cu" "B.Cu")
		(net "PWRGD_P5V_STBY")
	)
	(segment
		(start 67.123056 -176.0474)
		(end 63.337694 -176.0474)
		(width 0.254)
		(layer "B.Cu")
		(net "PWRGD_P5V_STBY")
	)
	(segment
		(start 216.701116 -43.335956)
		(end 216.701116 -42.63898)
		(width 0.254)
		(layer "B.Cu")
		(net "PWRGD_P5V_STBY")
	)
	(segment
		(start 63.337694 -176.0474)
		(end 57.862724 -176.0474)
		(width 0.254)
		(layer "B.Cu")
		(net "PWRGD_P5V_STBY")
	)
	(segment
		(start 57.743344 -175.92802)
		(end 45.32376 -175.92802)
		(width 0.254)
		(layer "B.Cu")
		(net "PWRGD_P5V_STBY")
	)
	(segment
		(start 43.410378 -176.2252)
		(end 42.741342 -176.894236)
		(width 0.254)
		(layer "B.Cu")
		(net "PWRGD_P5V_STBY")
	)
	(segment
		(start 67.82943 -176.753774)
		(end 67.123056 -176.0474)
		(width 0.254)
		(layer "B.Cu")
		(net "PWRGD_P5V_STBY")
	)
	(segment
		(start 45.02658 -176.2252)
		(end 43.410378 -176.2252)
		(width 0.254)
		(layer "B.Cu")
		(net "PWRGD_P5V_STBY")
	)
	(segment
		(start 214.139272 -54.169056)
		(end 214.139272 -45.8978)
		(width 0.254)
		(layer "B.Cu")
		(net "PWRGD_P5V_STBY")
	)
	(segment
		(start 45.32376 -175.92802)
		(end 45.02658 -176.2252)
		(width 0.254)
		(layer "B.Cu")
		(net "PWRGD_P5V_STBY")
	)
	(segment
		(start 57.862724 -176.0474)
		(end 57.743344 -175.92802)
		(width 0.254)
		(layer "B.Cu")
		(net "PWRGD_P5V_STBY")
	)
	(segment
		(start 215.612472 -55.642256)
		(end 214.139272 -54.169056)
		(width 0.254)
		(layer "B.Cu")
		(net "PWRGD_P5V_STBY")
	)
	(segment
		(start 214.139272 -45.8978)
		(end 216.701116 -43.335956)
		(width 0.254)
		(layer "B.Cu")
		(net "PWRGD_P5V_STBY")
	)
	(segment
		(start 216.701116 -42.63898)
		(end 217.077036 -42.26306)
		(width 0.254)
		(layer "B.Cu")
		(net "PWRGD_P5V_STBY")
	)
	(segment
		(start 64.062864 -145.854166)
		(end 64.804798 -146.5961)
		(width 0.254)
		(layer "In2.Cu")
		(net "PWRGD_P5V_STBY")
	)
	(segment
		(start 66.2559 -137.573004)
		(end 64.668146 -139.160758)
		(width 0.254)
		(layer "In2.Cu")
		(net "PWRGD_P5V_STBY")
	)
	(segment
		(start 67.82943 -176.54397)
		(end 67.82943 -176.753774)
		(width 0.254)
		(layer "In2.Cu")
		(net "PWRGD_P5V_STBY")
	)
	(segment
		(start 200.30186 -9.161018)
		(end 197.668642 -6.5278)
		(width 0.254)
		(layer "In2.Cu")
		(net "PWRGD_P5V_STBY")
	)
	(segment
		(start 69.424042 -160.508442)
		(end 69.424042 -165.486842)
		(width 0.254)
		(layer "In2.Cu")
		(net "PWRGD_P5V_STBY")
	)
	(segment
		(start 64.668146 -141.177518)
		(end 64.062864 -141.7828)
		(width 0.254)
		(layer "In2.Cu")
		(net "PWRGD_P5V_STBY")
	)
	(segment
		(start 215.206072 -14.738096)
		(end 209.628994 -9.161018)
		(width 0.254)
		(layer "In2.Cu")
		(net "PWRGD_P5V_STBY")
	)
	(segment
		(start 74.7014 -64.7192)
		(end 76.6826 -66.7004)
		(width 0.254)
		(layer "In2.Cu")
		(net "PWRGD_P5V_STBY")
	)
	(segment
		(start 71.2978 -173.0756)
		(end 67.82943 -176.54397)
		(width 0.254)
		(layer "In2.Cu")
		(net "PWRGD_P5V_STBY")
	)
	(segment
		(start 64.804798 -146.5961)
		(end 65.232026 -146.5961)
		(width 0.254)
		(layer "In2.Cu")
		(net "PWRGD_P5V_STBY")
	)
	(segment
		(start 146.851624 -2.224024)
		(end 95.280988 -2.224024)
		(width 0.254)
		(layer "In2.Cu")
		(net "PWRGD_P5V_STBY")
	)
	(segment
		(start 67.4116 -113.951512)
		(end 66.932556 -114.430556)
		(width 0.254)
		(layer "In2.Cu")
		(net "PWRGD_P5V_STBY")
	)
	(segment
		(start 95.280988 -2.224024)
		(end 92.324936 -5.180076)
		(width 0.254)
		(layer "In2.Cu")
		(net "PWRGD_P5V_STBY")
	)
	(segment
		(start 65.232026 -146.5961)
		(end 67.16395 -148.528024)
		(width 0.254)
		(layer "In2.Cu")
		(net "PWRGD_P5V_STBY")
	)
	(segment
		(start 70.866 -170.00982)
		(end 71.2978 -170.44162)
		(width 0.254)
		(layer "In2.Cu")
		(net "PWRGD_P5V_STBY")
	)
	(segment
		(start 92.324936 -5.180076)
		(end 82.663538 -5.180076)
		(width 0.254)
		(layer "In2.Cu")
		(net "PWRGD_P5V_STBY")
	)
	(segment
		(start 75.6412 -37.4396)
		(end 75.6412 -47.204884)
		(width 0.254)
		(layer "In2.Cu")
		(net "PWRGD_P5V_STBY")
	)
	(segment
		(start 67.426332 -154.950414)
		(end 67.426332 -158.510732)
		(width 0.254)
		(layer "In2.Cu")
		(net "PWRGD_P5V_STBY")
	)
	(segment
		(start 67.818 -154.558746)
		(end 67.426332 -154.950414)
		(width 0.254)
		(layer "In2.Cu")
		(net "PWRGD_P5V_STBY")
	)
	(segment
		(start 70.866 -166.937944)
		(end 70.866 -170.00982)
		(width 0.254)
		(layer "In2.Cu")
		(net "PWRGD_P5V_STBY")
	)
	(segment
		(start 147.8915 -3.2639)
		(end 146.851624 -2.224024)
		(width 0.254)
		(layer "In2.Cu")
		(net "PWRGD_P5V_STBY")
	)
	(segment
		(start 177.5968 -6.5278)
		(end 174.3329 -3.2639)
		(width 0.254)
		(layer "In2.Cu")
		(net "PWRGD_P5V_STBY")
	)
	(segment
		(start 174.3329 -3.2639)
		(end 147.8915 -3.2639)
		(width 0.254)
		(layer "In2.Cu")
		(net "PWRGD_P5V_STBY")
	)
	(segment
		(start 67.16395 -148.528024)
		(end 67.16395 -150.226268)
		(width 0.254)
		(layer "In2.Cu")
		(net "PWRGD_P5V_STBY")
	)
	(segment
		(start 67.818 -150.880318)
		(end 67.818 -154.558746)
		(width 0.254)
		(layer "In2.Cu")
		(net "PWRGD_P5V_STBY")
	)
	(segment
		(start 66.932556 -114.430556)
		(end 66.0908 -115.272566)
		(width 0.254)
		(layer "In2.Cu")
		(net "PWRGD_P5V_STBY")
	)
	(segment
		(start 69.4817 -165.5445)
		(end 69.4817 -165.553644)
		(width 0.254)
		(layer "In2.Cu")
		(net "PWRGD_P5V_STBY")
	)
	(segment
		(start 64.062864 -141.7828)
		(end 64.062864 -145.854166)
		(width 0.254)
		(layer "In2.Cu")
		(net "PWRGD_P5V_STBY")
	)
	(segment
		(start 75.1078 -108.5342)
		(end 75.1078 -108.8136)
		(width 0.254)
		(layer "In2.Cu")
		(net "PWRGD_P5V_STBY")
	)
	(segment
		(start 82.663538 -5.180076)
		(end 79.119222 -8.724392)
		(width 0.254)
		(layer "In2.Cu")
		(net "PWRGD_P5V_STBY")
	)
	(segment
		(start 66.0908 -115.272566)
		(end 66.0908 -120.559576)
		(width 0.254)
		(layer "In2.Cu")
		(net "PWRGD_P5V_STBY")
	)
	(segment
		(start 79.119222 -9.77646)
		(end 79.119476 -9.776714)
		(width 0.254)
		(layer "In2.Cu")
		(net "PWRGD_P5V_STBY")
	)
	(segment
		(start 215.612472 -55.642256)
		(end 215.206072 -55.235856)
		(width 0.254)
		(layer "In2.Cu")
		(net "PWRGD_P5V_STBY")
	)
	(segment
		(start 76.6826 -94.1324)
		(end 74.692002 -96.122998)
		(width 0.254)
		(layer "In2.Cu")
		(net "PWRGD_P5V_STBY")
	)
	(segment
		(start 79.119476 -9.776714)
		(end 79.119476 -33.961324)
		(width 0.254)
		(layer "In2.Cu")
		(net "PWRGD_P5V_STBY")
	)
	(segment
		(start 69.4817 -165.553644)
		(end 70.866 -166.937944)
		(width 0.254)
		(layer "In2.Cu")
		(net "PWRGD_P5V_STBY")
	)
	(segment
		(start 79.119222 -8.724392)
		(end 79.119222 -9.77646)
		(width 0.254)
		(layer "In2.Cu")
		(net "PWRGD_P5V_STBY")
	)
	(segment
		(start 64.668146 -139.160758)
		(end 64.668146 -141.177518)
		(width 0.254)
		(layer "In2.Cu")
		(net "PWRGD_P5V_STBY")
	)
	(segment
		(start 69.424042 -165.486842)
		(end 69.4817 -165.5445)
		(width 0.254)
		(layer "In2.Cu")
		(net "PWRGD_P5V_STBY")
	)
	(segment
		(start 79.119476 -33.961324)
		(end 75.6412 -37.4396)
		(width 0.254)
		(layer "In2.Cu")
		(net "PWRGD_P5V_STBY")
	)
	(segment
		(start 65.940686 -127.020574)
		(end 66.2559 -127.335788)
		(width 0.254)
		(layer "In2.Cu")
		(net "PWRGD_P5V_STBY")
	)
	(segment
		(start 74.692002 -108.118402)
		(end 75.1078 -108.5342)
		(width 0.254)
		(layer "In2.Cu")
		(net "PWRGD_P5V_STBY")
	)
	(segment
		(start 71.2978 -170.44162)
		(end 71.2978 -173.0756)
		(width 0.254)
		(layer "In2.Cu")
		(net "PWRGD_P5V_STBY")
	)
	(segment
		(start 67.426332 -158.510732)
		(end 69.424042 -160.508442)
		(width 0.254)
		(layer "In2.Cu")
		(net "PWRGD_P5V_STBY")
	)
	(segment
		(start 75.6412 -47.204884)
		(end 74.7014 -48.144684)
		(width 0.254)
		(layer "In2.Cu")
		(net "PWRGD_P5V_STBY")
	)
	(segment
		(start 65.940686 -120.70969)
		(end 65.940686 -127.020574)
		(width 0.254)
		(layer "In2.Cu")
		(net "PWRGD_P5V_STBY")
	)
	(segment
		(start 215.206072 -55.235856)
		(end 215.206072 -14.738096)
		(width 0.254)
		(layer "In2.Cu")
		(net "PWRGD_P5V_STBY")
	)
	(segment
		(start 66.2559 -127.335788)
		(end 66.2559 -137.573004)
		(width 0.254)
		(layer "In2.Cu")
		(net "PWRGD_P5V_STBY")
	)
	(segment
		(start 209.628994 -9.161018)
		(end 200.30186 -9.161018)
		(width 0.254)
		(layer "In2.Cu")
		(net "PWRGD_P5V_STBY")
	)
	(segment
		(start 67.4116 -113.3094)
		(end 67.4116 -113.951512)
		(width 0.254)
		(layer "In2.Cu")
		(net "PWRGD_P5V_STBY")
	)
	(segment
		(start 67.16395 -150.226268)
		(end 67.818 -150.880318)
		(width 0.254)
		(layer "In2.Cu")
		(net "PWRGD_P5V_STBY")
	)
	(segment
		(start 66.0908 -120.559576)
		(end 65.940686 -120.70969)
		(width 0.254)
		(layer "In2.Cu")
		(net "PWRGD_P5V_STBY")
	)
	(segment
		(start 74.692002 -96.122998)
		(end 74.692002 -108.118402)
		(width 0.254)
		(layer "In2.Cu")
		(net "PWRGD_P5V_STBY")
	)
	(segment
		(start 76.6826 -66.7004)
		(end 76.6826 -94.1324)
		(width 0.254)
		(layer "In2.Cu")
		(net "PWRGD_P5V_STBY")
	)
	(segment
		(start 74.7014 -48.144684)
		(end 74.7014 -64.7192)
		(width 0.254)
		(layer "In2.Cu")
		(net "PWRGD_P5V_STBY")
	)
	(segment
		(start 197.668642 -6.5278)
		(end 177.5968 -6.5278)
		(width 0.254)
		(layer "In2.Cu")
		(net "PWRGD_P5V_STBY")
	)
	(segment
		(start 69.07276 -183.78678)
		(end 68.13042 -183.78678)
		(width 0.254)
		(layer "F.Cu")
		(net "PWRGD_P3V3_STBY")
	)
	(segment
		(start 40.220646 -179.56911)
		(end 39.1922 -179.56911)
		(width 0.254)
		(layer "F.Cu")
		(net "PWRGD_P3V3_STBY")
	)
	(segment
		(start 90.8812 -179.5018)
		(end 86.852506 -179.5018)
		(width 0.254)
		(layer "F.Cu")
		(net "PWRGD_P3V3_STBY")
	)
	(segment
		(start 41.219882 -179.56911)
		(end 40.220646 -179.56911)
		(width 0.254)
		(layer "F.Cu")
		(net "PWRGD_P3V3_STBY")
	)
	(segment
		(start 86.183216 -180.17109)
		(end 84.836 -181.518306)
		(width 0.254)
		(layer "F.Cu")
		(net "PWRGD_P3V3_STBY")
	)
	(segment
		(start 37.75075 -180.070506)
		(end 36.744148 -180.070506)
		(width 0.254)
		(layer "F.Cu")
		(net "PWRGD_P3V3_STBY")
	)
	(segment
		(start 27.901646 -178.17211)
		(end 27.08529 -178.17211)
		(width 0.254)
		(layer "F.Cu")
		(net "PWRGD_P3V3_STBY")
	)
	(segment
		(start 38.252146 -179.56911)
		(end 37.75075 -180.070506)
		(width 0.254)
		(layer "F.Cu")
		(net "PWRGD_P3V3_STBY")
	)
	(segment
		(start 84.836 -181.518306)
		(end 84.836 -181.51856)
		(width 0.254)
		(layer "F.Cu")
		(net "PWRGD_P3V3_STBY")
	)
	(segment
		(start 86.852506 -179.5018)
		(end 86.183216 -180.17109)
		(width 0.254)
		(layer "F.Cu")
		(net "PWRGD_P3V3_STBY")
	)
	(segment
		(start 39.1922 -179.56911)
		(end 38.252146 -179.56911)
		(width 0.254)
		(layer "F.Cu")
		(net "PWRGD_P3V3_STBY")
	)
	(segment
		(start 41.23944 -179.549552)
		(end 41.219882 -179.56911)
		(width 0.254)
		(layer "F.Cu")
		(net "PWRGD_P3V3_STBY")
	)
	(via
		(at 86.183216 -180.17109)
		(size 0.6604)
		(drill 0.3302)
		(layers "F.Cu" "B.Cu")
		(net "PWRGD_P3V3_STBY")
	)
	(via
		(at 84.836 -181.51856)
		(size 0.508)
		(drill 0.254)
		(layers "F.Cu" "B.Cu")
		(net "PWRGD_P3V3_STBY")
	)
	(via
		(at 27.08529 -178.17211)
		(size 0.508)
		(drill 0.254)
		(layers "F.Cu" "B.Cu")
		(net "PWRGD_P3V3_STBY")
	)
	(via
		(at 41.23944 -179.549552)
		(size 0.508)
		(drill 0.254)
		(layers "F.Cu" "B.Cu")
		(net "PWRGD_P3V3_STBY")
	)
	(via
		(at 79.5782 -131.7752)
		(size 0.508)
		(drill 0.254)
		(layers "F.Cu" "B.Cu")
		(net "PWRGD_P3V3_STBY")
	)
	(via
		(at 68.13042 -183.78678)
		(size 0.508)
		(drill 0.254)
		(layers "F.Cu" "B.Cu")
		(net "PWRGD_P3V3_STBY")
	)
	(segment
		(start 82.0039 -131.2799)
		(end 82.0039 -130.92684)
		(width 0.254)
		(layer "B.Cu")
		(net "PWRGD_P3V3_STBY")
	)
	(segment
		(start 81.5086 -131.7752)
		(end 82.0039 -131.2799)
		(width 0.254)
		(layer "B.Cu")
		(net "PWRGD_P3V3_STBY")
	)
	(segment
		(start 79.5782 -131.7752)
		(end 81.5086 -131.7752)
		(width 0.254)
		(layer "B.Cu")
		(net "PWRGD_P3V3_STBY")
	)
	(segment
		(start 85.070696 -181.283864)
		(end 85.070696 -169.576496)
		(width 0.254)
		(layer "In2.Cu")
		(net "PWRGD_P3V3_STBY")
	)
	(segment
		(start 84.836 -181.51856)
		(end 85.070696 -181.283864)
		(width 0.254)
		(layer "In2.Cu")
		(net "PWRGD_P3V3_STBY")
	)
	(segment
		(start 80.748886 -137.810748)
		(end 80.0608 -137.122662)
		(width 0.254)
		(layer "In2.Cu")
		(net "PWRGD_P3V3_STBY")
	)
	(segment
		(start 79.665068 -148.74494)
		(end 79.55661 -148.636482)
		(width 0.254)
		(layer "In2.Cu")
		(net "PWRGD_P3V3_STBY")
	)
	(segment
		(start 80.0608 -137.122662)
		(end 80.0608 -134.0358)
		(width 0.254)
		(layer "In2.Cu")
		(net "PWRGD_P3V3_STBY")
	)
	(segment
		(start 80.0608 -134.0358)
		(end 79.5782 -133.5532)
		(width 0.254)
		(layer "In2.Cu")
		(net "PWRGD_P3V3_STBY")
	)
	(segment
		(start 85.070696 -169.576496)
		(end 84.7852 -169.291)
		(width 0.254)
		(layer "In2.Cu")
		(net "PWRGD_P3V3_STBY")
	)
	(segment
		(start 84.7852 -169.291)
		(end 84.7852 -165.566344)
		(width 0.254)
		(layer "In2.Cu")
		(net "PWRGD_P3V3_STBY")
	)
	(segment
		(start 79.6925 -150.741888)
		(end 79.665068 -150.714456)
		(width 0.254)
		(layer "In2.Cu")
		(net "PWRGD_P3V3_STBY")
	)
	(segment
		(start 82.0674 -160.4264)
		(end 79.6925 -158.0515)
		(width 0.254)
		(layer "In2.Cu")
		(net "PWRGD_P3V3_STBY")
	)
	(segment
		(start 79.665068 -150.714456)
		(end 79.665068 -148.74494)
		(width 0.254)
		(layer "In2.Cu")
		(net "PWRGD_P3V3_STBY")
	)
	(segment
		(start 82.0674 -162.848544)
		(end 82.0674 -160.4264)
		(width 0.254)
		(layer "In2.Cu")
		(net "PWRGD_P3V3_STBY")
	)
	(segment
		(start 79.55661 -143.768064)
		(end 80.748886 -142.575788)
		(width 0.254)
		(layer "In2.Cu")
		(net "PWRGD_P3V3_STBY")
	)
	(segment
		(start 84.7852 -165.566344)
		(end 82.0674 -162.848544)
		(width 0.254)
		(layer "In2.Cu")
		(net "PWRGD_P3V3_STBY")
	)
	(segment
		(start 80.748886 -142.575788)
		(end 80.748886 -137.810748)
		(width 0.254)
		(layer "In2.Cu")
		(net "PWRGD_P3V3_STBY")
	)
	(segment
		(start 79.6925 -158.0515)
		(end 79.6925 -150.741888)
		(width 0.254)
		(layer "In2.Cu")
		(net "PWRGD_P3V3_STBY")
	)
	(segment
		(start 79.55661 -148.636482)
		(end 79.55661 -143.768064)
		(width 0.254)
		(layer "In2.Cu")
		(net "PWRGD_P3V3_STBY")
	)
	(segment
		(start 79.5782 -133.5532)
		(end 79.5782 -131.7752)
		(width 0.254)
		(layer "In2.Cu")
		(net "PWRGD_P3V3_STBY")
	)
	(segment
		(start 27.887168 -178.17211)
		(end 27.08529 -178.17211)
		(width 0.254)
		(layer "In5.Cu")
		(net "PWRGD_P3V3_STBY")
	)
	(segment
		(start 61.069728 -179.544472)
		(end 63.364872 -179.544472)
		(width 0.254)
		(layer "In5.Cu")
		(net "PWRGD_P3V3_STBY")
	)
	(segment
		(start 79.771494 -182.7784)
		(end 83.57616 -182.7784)
		(width 0.254)
		(layer "In5.Cu")
		(net "PWRGD_P3V3_STBY")
	)
	(segment
		(start 63.364872 -179.544472)
		(end 67.60718 -183.78678)
		(width 0.254)
		(layer "In5.Cu")
		(net "PWRGD_P3V3_STBY")
	)
	(segment
		(start 38.885622 -177.950622)
		(end 35.902392 -177.950622)
		(width 0.254)
		(layer "In5.Cu")
		(net "PWRGD_P3V3_STBY")
	)
	(segment
		(start 34.973006 -177.021236)
		(end 29.038042 -177.021236)
		(width 0.254)
		(layer "In5.Cu")
		(net "PWRGD_P3V3_STBY")
	)
	(segment
		(start 41.23944 -179.549552)
		(end 44.56176 -179.549552)
		(width 0.254)
		(layer "In5.Cu")
		(net "PWRGD_P3V3_STBY")
	)
	(segment
		(start 40.484552 -179.549552)
		(end 38.885622 -177.950622)
		(width 0.254)
		(layer "In5.Cu")
		(net "PWRGD_P3V3_STBY")
	)
	(segment
		(start 44.56176 -179.549552)
		(end 44.596558 -179.58435)
		(width 0.254)
		(layer "In5.Cu")
		(net "PWRGD_P3V3_STBY")
	)
	(segment
		(start 44.596558 -179.58435)
		(end 45.038518 -179.58435)
		(width 0.254)
		(layer "In5.Cu")
		(net "PWRGD_P3V3_STBY")
	)
	(segment
		(start 41.23944 -179.549552)
		(end 40.484552 -179.549552)
		(width 0.254)
		(layer "In5.Cu")
		(net "PWRGD_P3V3_STBY")
	)
	(segment
		(start 35.902392 -177.950622)
		(end 34.973006 -177.021236)
		(width 0.254)
		(layer "In5.Cu")
		(net "PWRGD_P3V3_STBY")
	)
	(segment
		(start 29.038042 -177.021236)
		(end 27.887168 -178.17211)
		(width 0.254)
		(layer "In5.Cu")
		(net "PWRGD_P3V3_STBY")
	)
	(segment
		(start 47.393352 -179.549552)
		(end 47.8282 -179.9844)
		(width 0.254)
		(layer "In5.Cu")
		(net "PWRGD_P3V3_STBY")
	)
	(segment
		(start 60.6298 -179.9844)
		(end 61.069728 -179.544472)
		(width 0.254)
		(layer "In5.Cu")
		(net "PWRGD_P3V3_STBY")
	)
	(segment
		(start 83.57616 -182.7784)
		(end 84.836 -181.51856)
		(width 0.254)
		(layer "In5.Cu")
		(net "PWRGD_P3V3_STBY")
	)
	(segment
		(start 74.252328 -183.78678)
		(end 75.546966 -182.492142)
		(width 0.254)
		(layer "In5.Cu")
		(net "PWRGD_P3V3_STBY")
	)
	(segment
		(start 68.13042 -183.78678)
		(end 74.252328 -183.78678)
		(width 0.254)
		(layer "In5.Cu")
		(net "PWRGD_P3V3_STBY")
	)
	(segment
		(start 67.60718 -183.78678)
		(end 68.13042 -183.78678)
		(width 0.254)
		(layer "In5.Cu")
		(net "PWRGD_P3V3_STBY")
	)
	(segment
		(start 45.038518 -179.58435)
		(end 45.073316 -179.549552)
		(width 0.254)
		(layer "In5.Cu")
		(net "PWRGD_P3V3_STBY")
	)
	(segment
		(start 45.073316 -179.549552)
		(end 47.393352 -179.549552)
		(width 0.254)
		(layer "In5.Cu")
		(net "PWRGD_P3V3_STBY")
	)
	(segment
		(start 47.8282 -179.9844)
		(end 60.6298 -179.9844)
		(width 0.254)
		(layer "In5.Cu")
		(net "PWRGD_P3V3_STBY")
	)
	(segment
		(start 79.485236 -182.492142)
		(end 79.771494 -182.7784)
		(width 0.254)
		(layer "In5.Cu")
		(net "PWRGD_P3V3_STBY")
	)
	(segment
		(start 75.546966 -182.492142)
		(end 79.485236 -182.492142)
		(width 0.254)
		(layer "In5.Cu")
		(net "PWRGD_P3V3_STBY")
	)
	(segment
		(start 40.921432 -113.6396)
		(end 40.676322 -113.39449)
		(width 0.254)
		(layer "F.Cu")
		(net "PWRGD_P1V8_STBY")
	)
	(segment
		(start 148.019516 -10.304018)
		(end 148.019516 -9.4615)
		(width 0.254)
		(layer "F.Cu")
		(net "PWRGD_P1V8_STBY")
	)
	(segment
		(start 68.875402 -113.3221)
		(end 68.075302 -114.1222)
		(width 0.254)
		(layer "F.Cu")
		(net "PWRGD_P1V8_STBY")
	)
	(segment
		(start 55.0164 -113.6396)
		(end 40.921432 -113.6396)
		(width 0.254)
		(layer "F.Cu")
		(net "PWRGD_P1V8_STBY")
	)
	(segment
		(start 70.47357 -113.3221)
		(end 68.875402 -113.3221)
		(width 0.254)
		(layer "F.Cu")
		(net "PWRGD_P1V8_STBY")
	)
	(segment
		(start 59.7662 -114.1222)
		(end 58.9534 -114.935)
		(width 0.254)
		(layer "F.Cu")
		(net "PWRGD_P1V8_STBY")
	)
	(segment
		(start 152.615138 -8.612378)
		(end 152.615138 -8.865362)
		(width 0.254)
		(layer "F.Cu")
		(net "PWRGD_P1V8_STBY")
	)
	(segment
		(start 58.9534 -114.935)
		(end 56.3118 -114.935)
		(width 0.254)
		(layer "F.Cu")
		(net "PWRGD_P1V8_STBY")
	)
	(segment
		(start 153.174954 -9.425178)
		(end 153.174954 -9.870694)
		(width 0.254)
		(layer "F.Cu")
		(net "PWRGD_P1V8_STBY")
	)
	(segment
		(start 5.109972 -169.42562)
		(end 7.358634 -171.674282)
		(width 0.254)
		(layer "F.Cu")
		(net "PWRGD_P1V8_STBY")
	)
	(segment
		(start 5.109972 -125.202696)
		(end 5.109972 -169.42562)
		(width 0.254)
		(layer "F.Cu")
		(net "PWRGD_P1V8_STBY")
	)
	(segment
		(start 68.075302 -114.1222)
		(end 59.7662 -114.1222)
		(width 0.254)
		(layer "F.Cu")
		(net "PWRGD_P1V8_STBY")
	)
	(segment
		(start 148.019516 -9.4615)
		(end 148.030438 -9.450578)
		(width 0.254)
		(layer "F.Cu")
		(net "PWRGD_P1V8_STBY")
	)
	(segment
		(start 40.676322 -113.39449)
		(end 16.918178 -113.39449)
		(width 0.254)
		(layer "F.Cu")
		(net "PWRGD_P1V8_STBY")
	)
	(segment
		(start 148.030438 -8.078978)
		(end 148.030438 -9.450578)
		(width 0.254)
		(layer "F.Cu")
		(net "PWRGD_P1V8_STBY")
	)
	(segment
		(start 152.615138 -8.865362)
		(end 153.174954 -9.425178)
		(width 0.254)
		(layer "F.Cu")
		(net "PWRGD_P1V8_STBY")
	)
	(segment
		(start 56.3118 -114.935)
		(end 55.0164 -113.6396)
		(width 0.254)
		(layer "F.Cu")
		(net "PWRGD_P1V8_STBY")
	)
	(segment
		(start 148.019516 -10.304018)
		(end 147.790916 -10.532618)
		(width 0.254)
		(layer "F.Cu")
		(net "PWRGD_P1V8_STBY")
	)
	(segment
		(start 10.084816 -172.6565)
		(end 8.340852 -172.6565)
		(width 0.254)
		(layer "F.Cu")
		(net "PWRGD_P1V8_STBY")
	)
	(segment
		(start 16.918178 -113.39449)
		(end 5.109972 -125.202696)
		(width 0.254)
		(layer "F.Cu")
		(net "PWRGD_P1V8_STBY")
	)
	(segment
		(start 8.340852 -172.6565)
		(end 7.358634 -171.674282)
		(width 0.254)
		(layer "F.Cu")
		(net "PWRGD_P1V8_STBY")
	)
	(via
		(at 148.030438 -8.078978)
		(size 0.508)
		(drill 0.254)
		(layers "F.Cu" "B.Cu")
		(net "PWRGD_P1V8_STBY")
	)
	(via
		(at 7.358634 -171.674282)
		(size 0.6604)
		(drill 0.3302)
		(layers "F.Cu" "B.Cu")
		(net "PWRGD_P1V8_STBY")
	)
	(via
		(at 70.47357 -113.3221)
		(size 0.508)
		(drill 0.254)
		(layers "F.Cu" "B.Cu")
		(net "PWRGD_P1V8_STBY")
	)
	(via
		(at 152.615138 -8.612378)
		(size 0.508)
		(drill 0.254)
		(layers "F.Cu" "B.Cu")
		(net "PWRGD_P1V8_STBY")
	)
	(segment
		(start 152.615138 -8.612378)
		(end 148.563838 -8.612378)
		(width 0.254)
		(layer "B.Cu")
		(net "PWRGD_P1V8_STBY")
	)
	(segment
		(start 148.563838 -8.612378)
		(end 148.030438 -8.078978)
		(width 0.254)
		(layer "B.Cu")
		(net "PWRGD_P1V8_STBY")
	)
	(segment
		(start 144.45361 -3.5433)
		(end 148.030438 -7.120128)
		(width 0.254)
		(layer "In2.Cu")
		(net "PWRGD_P1V8_STBY")
	)
	(segment
		(start 78.55458 -95.780098)
		(end 78.55458 -93.89237)
		(width 0.254)
		(layer "In2.Cu")
		(net "PWRGD_P1V8_STBY")
	)
	(segment
		(start 72.22871 -113.043716)
		(end 72.228964 -113.043462)
		(width 0.254)
		(layer "In2.Cu")
		(net "PWRGD_P1V8_STBY")
	)
	(segment
		(start 77.81925 -65.135506)
		(end 77.607668 -65.135506)
		(width 0.254)
		(layer "In2.Cu")
		(net "PWRGD_P1V8_STBY")
	)
	(segment
		(start 77.150976 -47.491396)
		(end 79.167736 -47.491396)
		(width 0.254)
		(layer "In2.Cu")
		(net "PWRGD_P1V8_STBY")
	)
	(segment
		(start 72.228964 -113.043462)
		(end 72.88276 -113.043462)
		(width 0.254)
		(layer "In2.Cu")
		(net "PWRGD_P1V8_STBY")
	)
	(segment
		(start 80.772 -34.1376)
		(end 80.389476 -33.755076)
		(width 0.254)
		(layer "In2.Cu")
		(net "PWRGD_P1V8_STBY")
	)
	(segment
		(start 76.1746 -48.467772)
		(end 77.150976 -47.491396)
		(width 0.254)
		(layer "In2.Cu")
		(net "PWRGD_P1V8_STBY")
	)
	(segment
		(start 81.545176 -107.9627)
		(end 82.561938 -106.945938)
		(width 0.254)
		(layer "In2.Cu")
		(net "PWRGD_P1V8_STBY")
	)
	(segment
		(start 77.607668 -65.135506)
		(end 76.1746 -63.702438)
		(width 0.254)
		(layer "In2.Cu")
		(net "PWRGD_P1V8_STBY")
	)
	(segment
		(start 77.963776 -107.9627)
		(end 81.545176 -107.9627)
		(width 0.254)
		(layer "In2.Cu")
		(net "PWRGD_P1V8_STBY")
	)
	(segment
		(start 96.231456 -3.5433)
		(end 144.45361 -3.5433)
		(width 0.254)
		(layer "In2.Cu")
		(net "PWRGD_P1V8_STBY")
	)
	(segment
		(start 79.471012 -96.69653)
		(end 78.55458 -95.780098)
		(width 0.254)
		(layer "In2.Cu")
		(net "PWRGD_P1V8_STBY")
	)
	(segment
		(start 148.030438 -7.120128)
		(end 148.030438 -8.078978)
		(width 0.254)
		(layer "In2.Cu")
		(net "PWRGD_P1V8_STBY")
	)
	(segment
		(start 78.55458 -93.89237)
		(end 79.102204 -93.344746)
		(width 0.254)
		(layer "In2.Cu")
		(net "PWRGD_P1V8_STBY")
	)
	(segment
		(start 92.851224 -6.450076)
		(end 95.758254 -3.543046)
		(width 0.254)
		(layer "In2.Cu")
		(net "PWRGD_P1V8_STBY")
	)
	(segment
		(start 80.19288 -93.344746)
		(end 81.110328 -92.427298)
		(width 0.254)
		(layer "In2.Cu")
		(net "PWRGD_P1V8_STBY")
	)
	(segment
		(start 79.167736 -47.491396)
		(end 80.772 -45.887132)
		(width 0.254)
		(layer "In2.Cu")
		(net "PWRGD_P1V8_STBY")
	)
	(segment
		(start 79.471012 -100.061268)
		(end 79.471012 -96.69653)
		(width 0.254)
		(layer "In2.Cu")
		(net "PWRGD_P1V8_STBY")
	)
	(segment
		(start 79.2988 -67.809872)
		(end 79.2988 -66.615056)
		(width 0.254)
		(layer "In2.Cu")
		(net "PWRGD_P1V8_STBY")
	)
	(segment
		(start 80.389476 -9.250426)
		(end 83.189826 -6.450076)
		(width 0.254)
		(layer "In2.Cu")
		(net "PWRGD_P1V8_STBY")
	)
	(segment
		(start 96.231202 -3.543046)
		(end 96.231456 -3.5433)
		(width 0.254)
		(layer "In2.Cu")
		(net "PWRGD_P1V8_STBY")
	)
	(segment
		(start 83.0834 -103.673656)
		(end 79.471012 -100.061268)
		(width 0.254)
		(layer "In2.Cu")
		(net "PWRGD_P1V8_STBY")
	)
	(segment
		(start 83.0834 -106.42473)
		(end 83.0834 -103.673656)
		(width 0.254)
		(layer "In2.Cu")
		(net "PWRGD_P1V8_STBY")
	)
	(segment
		(start 77.646022 -108.2802)
		(end 77.646276 -108.2802)
		(width 0.254)
		(layer "In2.Cu")
		(net "PWRGD_P1V8_STBY")
	)
	(segment
		(start 72.88276 -113.043462)
		(end 77.646022 -108.2802)
		(width 0.254)
		(layer "In2.Cu")
		(net "PWRGD_P1V8_STBY")
	)
	(segment
		(start 80.772 -45.887132)
		(end 80.772 -34.1376)
		(width 0.254)
		(layer "In2.Cu")
		(net "PWRGD_P1V8_STBY")
	)
	(segment
		(start 79.102204 -93.344746)
		(end 80.19288 -93.344746)
		(width 0.254)
		(layer "In2.Cu")
		(net "PWRGD_P1V8_STBY")
	)
	(segment
		(start 76.1746 -63.702438)
		(end 76.1746 -48.467772)
		(width 0.254)
		(layer "In2.Cu")
		(net "PWRGD_P1V8_STBY")
	)
	(segment
		(start 81.110328 -92.427298)
		(end 81.110328 -69.6214)
		(width 0.254)
		(layer "In2.Cu")
		(net "PWRGD_P1V8_STBY")
	)
	(segment
		(start 95.758254 -3.543046)
		(end 96.231202 -3.543046)
		(width 0.254)
		(layer "In2.Cu")
		(net "PWRGD_P1V8_STBY")
	)
	(segment
		(start 81.110328 -69.6214)
		(end 79.2988 -67.809872)
		(width 0.254)
		(layer "In2.Cu")
		(net "PWRGD_P1V8_STBY")
	)
	(segment
		(start 70.751954 -113.043716)
		(end 72.22871 -113.043716)
		(width 0.254)
		(layer "In2.Cu")
		(net "PWRGD_P1V8_STBY")
	)
	(segment
		(start 82.561938 -106.945938)
		(end 83.0834 -106.42473)
		(width 0.254)
		(layer "In2.Cu")
		(net "PWRGD_P1V8_STBY")
	)
	(segment
		(start 79.2988 -66.615056)
		(end 77.81925 -65.135506)
		(width 0.254)
		(layer "In2.Cu")
		(net "PWRGD_P1V8_STBY")
	)
	(segment
		(start 83.189826 -6.450076)
		(end 92.851224 -6.450076)
		(width 0.254)
		(layer "In2.Cu")
		(net "PWRGD_P1V8_STBY")
	)
	(segment
		(start 80.389476 -33.755076)
		(end 80.389476 -9.250426)
		(width 0.254)
		(layer "In2.Cu")
		(net "PWRGD_P1V8_STBY")
	)
	(segment
		(start 77.646276 -108.2802)
		(end 77.963776 -107.9627)
		(width 0.254)
		(layer "In2.Cu")
		(net "PWRGD_P1V8_STBY")
	)
	(segment
		(start 70.47357 -113.3221)
		(end 70.751954 -113.043716)
		(width 0.254)
		(layer "In2.Cu")
		(net "PWRGD_P1V8_STBY")
	)
	(segment
		(start 52.100226 -138.199876)
		(end 52.500022 -137.80008)
		(width 0.127)
		(layer "F.Cu")
		(net "PWRBTN_OUT_N_R")
	)
	(segment
		(start 52.099972 -138.199876)
		(end 52.100226 -138.199876)
		(width 0.127)
		(layer "F.Cu")
		(net "PWRBTN_OUT_N_R")
	)
	(via
		(at 52.500022 -137.80008)
		(size 0.4572)
		(drill 0.2032)
		(layers "F.Cu" "B.Cu")
		(net "PWRBTN_OUT_N_R")
	)
	(via
		(at 53.245258 -137.31367)
		(size 0.6096)
		(drill 0.3048)
		(layers "F.Cu" "B.Cu")
		(net "PWRBTN_OUT_N_R")
	)
	(segment
		(start 52.80152 -137.80008)
		(end 52.500022 -137.80008)
		(width 0.127)
		(layer "B.Cu")
		(net "PWRBTN_OUT_N_R")
	)
	(segment
		(start 53.245258 -137.31367)
		(end 53.245258 -137.356342)
		(width 0.127)
		(layer "B.Cu")
		(net "PWRBTN_OUT_N_R")
	)
	(segment
		(start 53.245258 -137.356342)
		(end 52.80152 -137.80008)
		(width 0.127)
		(layer "B.Cu")
		(net "PWRBTN_OUT_N_R")
	)
	(segment
		(start 53.245258 -136.7028)
		(end 52.648612 -136.106154)
		(width 0.127)
		(layer "B.Cu")
		(net "PWRBTN_OUT_N_R")
	)
	(segment
		(start 53.245258 -137.31367)
		(end 53.245258 -136.7028)
		(width 0.127)
		(layer "B.Cu")
		(net "PWRBTN_OUT_N_R")
	)
	(segment
		(start 91.783154 -158.507176)
		(end 91.783154 -160.064704)
		(width 0.127)
		(layer "F.Cu")
		(net "PLLFILT")
	)
	(segment
		(start 91.396058 -160.4518)
		(end 90.600276 -160.4518)
		(width 0.127)
		(layer "F.Cu")
		(net "PLLFILT")
	)
	(segment
		(start 91.783154 -160.064704)
		(end 91.751658 -160.0962)
		(width 0.127)
		(layer "F.Cu")
		(net "PLLFILT")
	)
	(segment
		(start 91.751658 -158.47568)
		(end 91.783154 -158.507176)
		(width 0.127)
		(layer "F.Cu")
		(net "PLLFILT")
	)
	(segment
		(start 91.751658 -160.0962)
		(end 91.396058 -160.4518)
		(width 0.127)
		(layer "F.Cu")
		(net "PLLFILT")
	)
	(segment
		(start 90.600276 -160.4518)
		(end 89.45372 -161.598356)
		(width 0.127)
		(layer "F.Cu")
		(net "PLLFILT")
	)
	(via
		(at 91.751658 -160.0962)
		(size 0.508)
		(drill 0.254)
		(layers "F.Cu" "B.Cu")
		(net "PLLFILT")
	)
	(segment
		(start 91.895168 -158.915608)
		(end 91.895168 -159.95269)
		(width 0.127)
		(layer "B.Cu")
		(net "PLLFILT")
	)
	(segment
		(start 91.895168 -159.95269)
		(end 91.751658 -160.0962)
		(width 0.127)
		(layer "B.Cu")
		(net "PLLFILT")
	)
	(segment
		(start 212.64753 -45.13834)
		(end 211.48167 -45.13834)
		(width 0.254)
		(layer "F.Cu")
		(net "P5V_VFB_R")
	)
	(segment
		(start 213.77275 -45.142658)
		(end 213.768432 -45.13834)
		(width 0.254)
		(layer "F.Cu")
		(net "P5V_VFB_R")
	)
	(segment
		(start 213.79815 -45.117258)
		(end 213.77275 -45.142658)
		(width 0.254)
		(layer "F.Cu")
		(net "P5V_VFB_R")
	)
	(segment
		(start 214.78875 -45.117258)
		(end 213.79815 -45.117258)
		(width 0.254)
		(layer "F.Cu")
		(net "P5V_VFB_R")
	)
	(segment
		(start 211.48167 -45.13834)
		(end 211.473288 -45.129958)
		(width 0.254)
		(layer "F.Cu")
		(net "P5V_VFB_R")
	)
	(segment
		(start 213.768432 -45.13834)
		(end 212.64753 -45.13834)
		(width 0.254)
		(layer "F.Cu")
		(net "P5V_VFB_R")
	)
	(via
		(at 212.64753 -45.13834)
		(size 0.6604)
		(drill 0.3302)
		(layers "F.Cu" "B.Cu")
		(net "P5V_VFB_R")
	)
	(segment
		(start 216.857326 -46.131988)
		(end 216.8525 -46.127162)
		(width 0.254)
		(layer "F.Cu")
		(net "P5V_VFB")
	)
	(segment
		(start 213.79815 -46.006258)
		(end 213.77275 -46.031658)
		(width 0.254)
		(layer "F.Cu")
		(net "P5V_VFB")
	)
	(segment
		(start 213.77275 -46.893734)
		(end 213.910672 -47.031656)
		(width 0.254)
		(layer "F.Cu")
		(net "P5V_VFB")
	)
	(segment
		(start 214.78875 -46.006258)
		(end 215.77935 -46.006258)
		(width 0.254)
		(layer "F.Cu")
		(net "P5V_VFB")
	)
	(segment
		(start 216.8525 -46.127162)
		(end 215.900254 -46.127162)
		(width 0.254)
		(layer "F.Cu")
		(net "P5V_VFB")
	)
	(segment
		(start 214.78875 -46.006258)
		(end 213.79815 -46.006258)
		(width 0.254)
		(layer "F.Cu")
		(net "P5V_VFB")
	)
	(segment
		(start 215.900254 -46.127162)
		(end 215.80475 -46.031658)
		(width 0.254)
		(layer "F.Cu")
		(net "P5V_VFB")
	)
	(segment
		(start 215.77935 -46.006258)
		(end 215.80475 -46.031658)
		(width 0.254)
		(layer "F.Cu")
		(net "P5V_VFB")
	)
	(segment
		(start 213.77275 -46.031658)
		(end 213.77275 -46.893734)
		(width 0.254)
		(layer "F.Cu")
		(net "P5V_VFB")
	)
	(segment
		(start 218.383866 -46.131988)
		(end 216.857326 -46.131988)
		(width 0.254)
		(layer "F.Cu")
		(net "P5V_VFB")
	)
	(via
		(at 216.8525 -46.127162)
		(size 0.6604)
		(drill 0.3302)
		(layers "F.Cu" "B.Cu")
		(net "P5V_VFB")
	)
	(segment
		(start 219.748862 -52.254658)
		(end 219.748862 -52.266596)
		(width 0.254)
		(layer "F.Cu")
		(net "P5V_VDD")
	)
	(segment
		(start 219.88399 -51.030632)
		(end 219.88399 -52.11953)
		(width 0.254)
		(layer "F.Cu")
		(net "P5V_VDD")
	)
	(segment
		(start 219.748862 -52.266596)
		(end 219.580968 -52.43449)
		(width 0.254)
		(layer "F.Cu")
		(net "P5V_VDD")
	)
	(segment
		(start 219.88399 -52.11953)
		(end 219.748862 -52.254658)
		(width 0.254)
		(layer "F.Cu")
		(net "P5V_VDD")
	)
	(via
		(at 221.037912 -55.332122)
		(size 0.6096)
		(drill 0.3048)
		(layers "F.Cu" "B.Cu")
		(net "P5V_VDD")
	)
	(via
		(at 219.580968 -52.43449)
		(size 0.508)
		(drill 0.254)
		(layers "F.Cu" "B.Cu")
		(net "P5V_VDD")
	)
	(segment
		(start 220.78823 -53.89499)
		(end 220.78823 -55.08244)
		(width 0.254)
		(layer "B.Cu")
		(net "P5V_VDD")
	)
	(segment
		(start 219.580968 -52.43449)
		(end 220.78823 -53.641752)
		(width 0.254)
		(layer "B.Cu")
		(net "P5V_VDD")
	)
	(segment
		(start 221.18066 -55.47487)
		(end 221.037912 -55.332122)
		(width 0.254)
		(layer "B.Cu")
		(net "P5V_VDD")
	)
	(segment
		(start 220.78823 -55.08244)
		(end 221.037912 -55.332122)
		(width 0.254)
		(layer "B.Cu")
		(net "P5V_VDD")
	)
	(segment
		(start 221.18066 -56.533542)
		(end 221.18066 -55.47487)
		(width 0.254)
		(layer "B.Cu")
		(net "P5V_VDD")
	)
	(segment
		(start 220.78823 -53.641752)
		(end 220.78823 -53.89499)
		(width 0.254)
		(layer "B.Cu")
		(net "P5V_VDD")
	)
	(via
		(at 218.563444 -41.578276)
		(size 0.6096)
		(drill 0.3048)
		(layers "F.Cu" "B.Cu")
		(net "P5V_VBST_RC")
	)
	(segment
		(start 218.563444 -41.578276)
		(end 218.563444 -40.51046)
		(width 0.508)
		(layer "B.Cu")
		(net "P5V_VBST_RC")
	)
	(segment
		(start 218.563444 -42.678604)
		(end 218.563444 -41.578276)
		(width 0.508)
		(layer "B.Cu")
		(net "P5V_VBST_RC")
	)
	(segment
		(start 218.568016 -42.683176)
		(end 218.563444 -42.678604)
		(width 0.508)
		(layer "B.Cu")
		(net "P5V_VBST_RC")
	)
	(segment
		(start 219.88399 -44.736512)
		(end 219.88399 -46.131988)
		(width 0.254)
		(layer "F.Cu")
		(net "P5V_VBST")
	)
	(segment
		(start 219.707968 -44.56049)
		(end 219.88399 -44.736512)
		(width 0.254)
		(layer "F.Cu")
		(net "P5V_VBST")
	)
	(via
		(at 219.707968 -44.56049)
		(size 0.508)
		(drill 0.254)
		(layers "F.Cu" "B.Cu")
		(net "P5V_VBST")
	)
	(segment
		(start 219.707968 -44.56049)
		(end 218.92133 -44.56049)
		(width 0.508)
		(layer "B.Cu")
		(net "P5V_VBST")
	)
	(segment
		(start 218.92133 -44.56049)
		(end 218.568016 -44.207176)
		(width 0.508)
		(layer "B.Cu")
		(net "P5V_VBST")
	)
	(segment
		(start 217.492072 -52.594256)
		(end 217.288872 -52.797456)
		(width 0.254)
		(layer "F.Cu")
		(net "P5V_TRIP")
	)
	(segment
		(start 217.288872 -52.797456)
		(end 216.514172 -52.797456)
		(width 0.254)
		(layer "F.Cu")
		(net "P5V_TRIP")
	)
	(segment
		(start 218.127072 -51.959256)
		(end 218.525852 -51.959256)
		(width 0.254)
		(layer "F.Cu")
		(net "P5V_TRIP")
	)
	(segment
		(start 217.542872 -52.594256)
		(end 217.492072 -52.594256)
		(width 0.254)
		(layer "F.Cu")
		(net "P5V_TRIP")
	)
	(segment
		(start 218.883992 -51.601116)
		(end 218.883992 -51.030632)
		(width 0.254)
		(layer "F.Cu")
		(net "P5V_TRIP")
	)
	(segment
		(start 218.525852 -51.959256)
		(end 218.883992 -51.601116)
		(width 0.254)
		(layer "F.Cu")
		(net "P5V_TRIP")
	)
	(segment
		(start 217.492072 -52.594256)
		(end 218.127072 -51.959256)
		(width 0.254)
		(layer "F.Cu")
		(net "P5V_TRIP")
	)
	(via
		(at 217.542872 -52.594256)
		(size 0.6604)
		(drill 0.3302)
		(layers "F.Cu" "B.Cu")
		(net "P5V_TRIP")
	)
	(segment
		(start 217.8558 -56.4642)
		(end 219.083128 -56.4642)
		(width 0.254)
		(layer "F.Cu")
		(net "P5V_STBY_VREG")
	)
	(segment
		(start 220.209872 -53.483256)
		(end 220.209872 -52.892706)
		(width 0.254)
		(layer "F.Cu")
		(net "P5V_STBY_VREG")
	)
	(segment
		(start 220.23832 -55.309008)
		(end 220.23832 -54.676548)
		(width 0.254)
		(layer "F.Cu")
		(net "P5V_STBY_VREG")
	)
	(segment
		(start 219.083128 -56.4642)
		(end 220.23832 -55.309008)
		(width 0.254)
		(layer "F.Cu")
		(net "P5V_STBY_VREG")
	)
	(segment
		(start 220.209872 -54.6481)
		(end 220.209872 -53.483256)
		(width 0.254)
		(layer "F.Cu")
		(net "P5V_STBY_VREG")
	)
	(segment
		(start 220.209872 -52.892706)
		(end 220.383862 -52.718716)
		(width 0.254)
		(layer "F.Cu")
		(net "P5V_STBY_VREG")
	)
	(segment
		(start 220.383862 -52.718716)
		(end 220.383862 -51.030632)
		(width 0.254)
		(layer "F.Cu")
		(net "P5V_STBY_VREG")
	)
	(segment
		(start 220.23832 -54.676548)
		(end 220.209872 -54.6481)
		(width 0.254)
		(layer "F.Cu")
		(net "P5V_STBY_VREG")
	)
	(segment
		(start 218.089988 -40.402256)
		(end 218.089988 -39.525956)
		(width 0.254)
		(layer "F.Cu")
		(net "P5V_STBY_VREG")
	)
	(via
		(at 217.8558 -56.4642)
		(size 0.508)
		(drill 0.254)
		(layers "F.Cu" "B.Cu")
		(net "P5V_STBY_VREG")
	)
	(via
		(at 216.839038 -40.9575)
		(size 0.6096)
		(drill 0.3048)
		(layers "F.Cu" "B.Cu")
		(net "P5V_STBY_VREG")
	)
	(via
		(at 218.089988 -39.525956)
		(size 0.508)
		(drill 0.254)
		(layers "F.Cu" "B.Cu")
		(net "P5V_STBY_VREG")
	)
	(segment
		(start 218.089988 -39.525956)
		(end 216.839038 -40.776906)
		(width 0.254)
		(layer "B.Cu")
		(net "P5V_STBY_VREG")
	)
	(segment
		(start 213.504272 -45.634656)
		(end 215.993472 -43.145456)
		(width 0.254)
		(layer "B.Cu")
		(net "P5V_STBY_VREG")
	)
	(segment
		(start 215.993472 -43.145456)
		(end 215.993472 -41.803066)
		(width 0.254)
		(layer "B.Cu")
		(net "P5V_STBY_VREG")
	)
	(segment
		(start 215.993472 -41.803066)
		(end 216.839038 -40.9575)
		(width 0.254)
		(layer "B.Cu")
		(net "P5V_STBY_VREG")
	)
	(segment
		(start 215.342216 -56.4642)
		(end 213.504272 -54.626256)
		(width 0.254)
		(layer "B.Cu")
		(net "P5V_STBY_VREG")
	)
	(segment
		(start 213.504272 -54.626256)
		(end 213.504272 -45.634656)
		(width 0.254)
		(layer "B.Cu")
		(net "P5V_STBY_VREG")
	)
	(segment
		(start 216.839038 -40.776906)
		(end 216.839038 -40.9575)
		(width 0.254)
		(layer "B.Cu")
		(net "P5V_STBY_VREG")
	)
	(segment
		(start 217.8558 -56.4642)
		(end 215.342216 -56.4642)
		(width 0.254)
		(layer "B.Cu")
		(net "P5V_STBY_VREG")
	)
	(segment
		(start 227.069396 -47.325788)
		(end 227.256594 -47.512986)
		(width 0.508)
		(layer "F.Cu")
		(net "P5V_SNB")
	)
	(segment
		(start 227.275136 -48.9712)
		(end 227.275136 -47.531528)
		(width 0.508)
		(layer "F.Cu")
		(net "P5V_SNB")
	)
	(segment
		(start 227.275136 -47.531528)
		(end 227.256594 -47.512986)
		(width 0.508)
		(layer "F.Cu")
		(net "P5V_SNB")
	)
	(segment
		(start 227.069396 -46.40199)
		(end 227.069396 -47.325788)
		(width 0.508)
		(layer "F.Cu")
		(net "P5V_SNB")
	)
	(via
		(at 227.256594 -47.512986)
		(size 0.6604)
		(drill 0.3302)
		(layers "F.Cu" "B.Cu")
		(net "P5V_SNB")
	)
	(segment
		(start 219.34932 -55.131208)
		(end 219.34932 -54.676548)
		(width 0.254)
		(layer "F.Cu")
		(net "P5V_RF")
	)
	(segment
		(start 217.136472 -51.375056)
		(end 217.568272 -51.375056)
		(width 0.254)
		(layer "F.Cu")
		(net "P5V_RF")
	)
	(segment
		(start 216.730072 -51.781456)
		(end 217.136472 -51.375056)
		(width 0.254)
		(layer "F.Cu")
		(net "P5V_RF")
	)
	(segment
		(start 216.514172 -51.09083)
		(end 216.188798 -50.765456)
		(width 0.254)
		(layer "F.Cu")
		(net "P5V_RF")
	)
	(segment
		(start 217.568272 -51.375056)
		(end 217.912696 -51.030632)
		(width 0.254)
		(layer "F.Cu")
		(net "P5V_RF")
	)
	(segment
		(start 216.514172 -51.781456)
		(end 216.514172 -51.09083)
		(width 0.254)
		(layer "F.Cu")
		(net "P5V_RF")
	)
	(segment
		(start 216.514172 -51.781456)
		(end 216.730072 -51.781456)
		(width 0.254)
		(layer "F.Cu")
		(net "P5V_RF")
	)
	(segment
		(start 218.660472 -55.820056)
		(end 219.34932 -55.131208)
		(width 0.254)
		(layer "F.Cu")
		(net "P5V_RF")
	)
	(segment
		(start 217.912696 -51.030632)
		(end 218.383866 -51.030632)
		(width 0.254)
		(layer "F.Cu")
		(net "P5V_RF")
	)
	(via
		(at 216.642188 -52.7812)
		(size 0.6096)
		(drill 0.3048)
		(layers "F.Cu" "B.Cu")
		(net "P5V_RF")
	)
	(via
		(at 218.660472 -55.820056)
		(size 0.508)
		(drill 0.254)
		(layers "F.Cu" "B.Cu")
		(net "P5V_RF")
	)
	(via
		(at 216.188798 -50.765456)
		(size 0.508)
		(drill 0.254)
		(layers "F.Cu" "B.Cu")
		(net "P5V_RF")
	)
	(segment
		(start 217.226134 -53.365146)
		(end 216.642188 -52.7812)
		(width 0.254)
		(layer "B.Cu")
		(net "P5V_RF")
	)
	(segment
		(start 218.660472 -55.820056)
		(end 217.707972 -55.820056)
		(width 0.254)
		(layer "B.Cu")
		(net "P5V_RF")
	)
	(segment
		(start 216.188798 -52.32781)
		(end 216.642188 -52.7812)
		(width 0.254)
		(layer "B.Cu")
		(net "P5V_RF")
	)
	(segment
		(start 217.226134 -55.338218)
		(end 217.226134 -53.365146)
		(width 0.254)
		(layer "B.Cu")
		(net "P5V_RF")
	)
	(segment
		(start 217.707972 -55.820056)
		(end 217.226134 -55.338218)
		(width 0.254)
		(layer "B.Cu")
		(net "P5V_RF")
	)
	(segment
		(start 216.188798 -50.765456)
		(end 216.188798 -52.32781)
		(width 0.254)
		(layer "B.Cu")
		(net "P5V_RF")
	)
	(segment
		(start 219.383864 -51.820064)
		(end 219.383864 -51.030632)
		(width 0.254)
		(layer "F.Cu")
		(net "P5V_MODE")
	)
	(segment
		(start 217.473784 -53.939186)
		(end 217.473784 -53.552344)
		(width 0.254)
		(layer "F.Cu")
		(net "P5V_MODE")
	)
	(segment
		(start 217.143584 -54.854856)
		(end 217.473784 -54.524656)
		(width 0.254)
		(layer "F.Cu")
		(net "P5V_MODE")
	)
	(segment
		(start 217.473784 -54.524656)
		(end 217.473784 -53.939186)
		(width 0.254)
		(layer "F.Cu")
		(net "P5V_MODE")
	)
	(segment
		(start 216.514172 -54.854856)
		(end 217.143584 -54.854856)
		(width 0.254)
		(layer "F.Cu")
		(net "P5V_MODE")
	)
	(segment
		(start 218.469972 -52.733956)
		(end 219.383864 -51.820064)
		(width 0.254)
		(layer "F.Cu")
		(net "P5V_MODE")
	)
	(segment
		(start 218.292172 -52.733956)
		(end 218.469972 -52.733956)
		(width 0.254)
		(layer "F.Cu")
		(net "P5V_MODE")
	)
	(segment
		(start 217.473784 -53.552344)
		(end 218.292172 -52.733956)
		(width 0.254)
		(layer "F.Cu")
		(net "P5V_MODE")
	)
	(segment
		(start 216.514172 -53.813456)
		(end 216.514172 -54.854856)
		(width 0.254)
		(layer "F.Cu")
		(net "P5V_MODE")
	)
	(via
		(at 217.473784 -53.939186)
		(size 0.6604)
		(drill 0.3302)
		(layers "F.Cu" "B.Cu")
		(net "P5V_MODE")
	)
	(segment
		(start 215.499188 -37.278056)
		(end 216.197688 -37.976556)
		(width 0.254)
		(layer "F.Cu")
		(net "P5V_LL_R")
	)
	(segment
		(start 215.80475 -44.385738)
		(end 215.411558 -43.992546)
		(width 0.254)
		(layer "F.Cu")
		(net "P5V_LL_R")
	)
	(segment
		(start 212.4583 -42.42689)
		(end 212.4583 -37.770054)
		(width 0.254)
		(layer "F.Cu")
		(net "P5V_LL_R")
	)
	(segment
		(start 215.411558 -43.992546)
		(end 214.023956 -43.992546)
		(width 0.254)
		(layer "F.Cu")
		(net "P5V_LL_R")
	)
	(segment
		(start 215.80475 -45.142658)
		(end 215.80475 -44.385738)
		(width 0.254)
		(layer "F.Cu")
		(net "P5V_LL_R")
	)
	(segment
		(start 212.4583 -37.770054)
		(end 213.394798 -36.833556)
		(width 0.254)
		(layer "F.Cu")
		(net "P5V_LL_R")
	)
	(segment
		(start 214.023956 -43.992546)
		(end 212.4583 -42.42689)
		(width 0.254)
		(layer "F.Cu")
		(net "P5V_LL_R")
	)
	(segment
		(start 213.394798 -36.833556)
		(end 213.997032 -36.833556)
		(width 0.254)
		(layer "F.Cu")
		(net "P5V_LL_R")
	)
	(segment
		(start 213.997032 -36.833556)
		(end 215.499188 -36.833556)
		(width 0.254)
		(layer "F.Cu")
		(net "P5V_LL_R")
	)
	(segment
		(start 215.499188 -36.833556)
		(end 215.499188 -37.278056)
		(width 0.254)
		(layer "F.Cu")
		(net "P5V_LL_R")
	)
	(via
		(at 213.997032 -36.833556)
		(size 0.6604)
		(drill 0.3302)
		(layers "F.Cu" "B.Cu")
		(net "P5V_LL_R")
	)
	(segment
		(start 217.886788 -37.671756)
		(end 223.703388 -37.671756)
		(width 0.254)
		(layer "F.Cu")
		(net "P5V_LL")
	)
	(segment
		(start 217.086688 -37.976556)
		(end 217.581988 -37.976556)
		(width 0.254)
		(layer "F.Cu")
		(net "P5V_LL")
	)
	(segment
		(start 224.185988 -38.154356)
		(end 224.185988 -41.72585)
		(width 0.254)
		(layer "F.Cu")
		(net "P5V_LL")
	)
	(segment
		(start 223.703388 -37.671756)
		(end 224.185988 -38.154356)
		(width 0.254)
		(layer "F.Cu")
		(net "P5V_LL")
	)
	(segment
		(start 217.581988 -37.976556)
		(end 217.886788 -37.671756)
		(width 0.254)
		(layer "F.Cu")
		(net "P5V_LL")
	)
	(via
		(at 225.533712 -45.194728)
		(size 0.6604)
		(drill 0.3302)
		(layers "F.Cu" "B.Cu")
		(net "P5V_LL")
	)
	(via
		(at 220.434154 -41.55059)
		(size 0.508)
		(drill 0.254)
		(layers "F.Cu" "B.Cu")
		(net "P5V_LL")
	)
	(segment
		(start 220.434154 -41.55059)
		(end 220.434154 -40.85717)
		(width 0.508)
		(layer "B.Cu")
		(net "P5V_LL")
	)
	(segment
		(start 220.434154 -40.85717)
		(end 220.087444 -40.51046)
		(width 0.508)
		(layer "B.Cu")
		(net "P5V_LL")
	)
	(segment
		(start 218.026742 -44.40809)
		(end 218.883992 -45.26534)
		(width 0.254)
		(layer "F.Cu")
		(net "P5V_EN_R")
	)
	(segment
		(start 216.666064 -43.047412)
		(end 218.026742 -44.40809)
		(width 0.254)
		(layer "F.Cu")
		(net "P5V_EN_R")
	)
	(segment
		(start 218.883992 -45.26534)
		(end 218.883992 -46.131988)
		(width 0.254)
		(layer "F.Cu")
		(net "P5V_EN_R")
	)
	(segment
		(start 214.903558 -40.708326)
		(end 214.914988 -40.719756)
		(width 0.254)
		(layer "F.Cu")
		(net "P5V_EN_R")
	)
	(segment
		(start 215.915494 -43.047412)
		(end 215.915494 -41.955212)
		(width 0.254)
		(layer "F.Cu")
		(net "P5V_EN_R")
	)
	(segment
		(start 215.915494 -41.955212)
		(end 215.915494 -41.720262)
		(width 0.254)
		(layer "F.Cu")
		(net "P5V_EN_R")
	)
	(segment
		(start 214.903558 -39.541196)
		(end 214.903558 -40.708326)
		(width 0.254)
		(layer "F.Cu")
		(net "P5V_EN_R")
	)
	(segment
		(start 215.915494 -43.047412)
		(end 216.666064 -43.047412)
		(width 0.254)
		(layer "F.Cu")
		(net "P5V_EN_R")
	)
	(segment
		(start 215.915494 -41.720262)
		(end 214.914988 -40.719756)
		(width 0.254)
		(layer "F.Cu")
		(net "P5V_EN_R")
	)
	(via
		(at 218.026742 -44.40809)
		(size 0.6604)
		(drill 0.3302)
		(layers "F.Cu" "B.Cu")
		(net "P5V_EN_R")
	)
	(segment
		(start 214.4522 -21.13153)
		(end 214.4522 -33.4899)
		(width 0.254)
		(layer "F.Cu")
		(net "P5V_CC")
	)
	(segment
		(start 214.4522 -33.4899)
		(end 210.9343 -37.0078)
		(width 0.254)
		(layer "F.Cu")
		(net "P5V_CC")
	)
	(segment
		(start 229.682548 -18.10131)
		(end 229.682548 -17.66316)
		(width 0.1016)
		(layer "F.Cu")
		(net "P5V_CC")
	)
	(segment
		(start 229.682548 -17.66316)
		(end 229.682548 -15.272004)
		(width 0.254)
		(layer "F.Cu")
		(net "P5V_CC")
	)
	(segment
		(start 221.621604 -13.962126)
		(end 216.581228 -19.002502)
		(width 0.254)
		(layer "F.Cu")
		(net "P5V_CC")
	)
	(segment
		(start 216.581228 -19.002502)
		(end 214.4522 -21.13153)
		(width 0.254)
		(layer "F.Cu")
		(net "P5V_CC")
	)
	(segment
		(start 210.9343 -37.0078)
		(end 210.9343 -43.06697)
		(width 0.254)
		(layer "F.Cu")
		(net "P5V_CC")
	)
	(segment
		(start 228.37267 -13.962126)
		(end 221.621604 -13.962126)
		(width 0.254)
		(layer "F.Cu")
		(net "P5V_CC")
	)
	(segment
		(start 210.9343 -43.06697)
		(end 211.473288 -43.605958)
		(width 0.254)
		(layer "F.Cu")
		(net "P5V_CC")
	)
	(segment
		(start 229.682548 -15.272004)
		(end 228.37267 -13.962126)
		(width 0.254)
		(layer "F.Cu")
		(net "P5V_CC")
	)
	(via
		(at 216.581228 -19.002502)
		(size 0.6604)
		(drill 0.3302)
		(layers "F.Cu" "B.Cu")
		(net "P5V_CC")
	)
	(via
		(at 39.584884 -183.713628)
		(size 0.6096)
		(drill 0.3048)
		(layers "F.Cu" "B.Cu")
		(net "P3V3_VBST_RC")
	)
	(segment
		(start 38.0238 -183.642)
		(end 39.513256 -183.642)
		(width 0.508)
		(layer "B.Cu")
		(net "P3V3_VBST_RC")
	)
	(segment
		(start 39.513256 -183.642)
		(end 39.584884 -183.713628)
		(width 0.508)
		(layer "B.Cu")
		(net "P3V3_VBST_RC")
	)
	(segment
		(start 39.58844 -183.710072)
		(end 39.584884 -183.713628)
		(width 0.508)
		(layer "B.Cu")
		(net "P3V3_VBST_RC")
	)
	(segment
		(start 40.884856 -183.710072)
		(end 39.58844 -183.710072)
		(width 0.508)
		(layer "B.Cu")
		(net "P3V3_VBST_RC")
	)
	(segment
		(start 38.315646 -180.39461)
		(end 38.139624 -180.570632)
		(width 0.254)
		(layer "F.Cu")
		(net "P3V3_VBST")
	)
	(segment
		(start 38.139624 -180.570632)
		(end 36.744148 -180.570632)
		(width 0.254)
		(layer "F.Cu")
		(net "P3V3_VBST")
	)
	(via
		(at 38.315646 -180.39461)
		(size 0.508)
		(drill 0.254)
		(layers "F.Cu" "B.Cu")
		(net "P3V3_VBST")
	)
	(segment
		(start 38.315646 -180.39461)
		(end 38.0238 -180.686456)
		(width 0.508)
		(layer "B.Cu")
		(net "P3V3_VBST")
	)
	(segment
		(start 38.0238 -180.686456)
		(end 38.0238 -181.7116)
		(width 0.508)
		(layer "B.Cu")
		(net "P3V3_VBST")
	)
	(segment
		(start 28.2448 -181.1909)
		(end 29.277056 -181.1909)
		(width 0.254)
		(layer "F.Cu")
		(net "P3V3_STBY_VREG")
	)
	(segment
		(start 41.3258 -178.689)
		(end 41.31691 -178.68011)
		(width 0.254)
		(layer "F.Cu")
		(net "P3V3_STBY_VREG")
	)
	(segment
		(start 29.367226 -181.10073)
		(end 29.397452 -181.070504)
		(width 0.254)
		(layer "F.Cu")
		(net "P3V3_STBY_VREG")
	)
	(segment
		(start 41.31691 -178.68011)
		(end 40.220646 -178.68011)
		(width 0.254)
		(layer "F.Cu")
		(net "P3V3_STBY_VREG")
	)
	(segment
		(start 29.397452 -181.070504)
		(end 31.845504 -181.070504)
		(width 0.254)
		(layer "F.Cu")
		(net "P3V3_STBY_VREG")
	)
	(segment
		(start 29.277056 -181.1909)
		(end 29.367226 -181.10073)
		(width 0.254)
		(layer "F.Cu")
		(net "P3V3_STBY_VREG")
	)
	(segment
		(start 27.67584 -181.1909)
		(end 27.01417 -180.52923)
		(width 0.254)
		(layer "F.Cu")
		(net "P3V3_STBY_VREG")
	)
	(segment
		(start 28.2448 -181.1909)
		(end 27.67584 -181.1909)
		(width 0.254)
		(layer "F.Cu")
		(net "P3V3_STBY_VREG")
	)
	(via
		(at 29.361892 -179.889912)
		(size 0.6096)
		(drill 0.3048)
		(layers "F.Cu" "B.Cu")
		(net "P3V3_STBY_VREG")
	)
	(via
		(at 27.01417 -180.52923)
		(size 0.508)
		(drill 0.254)
		(layers "F.Cu" "B.Cu")
		(net "P3V3_STBY_VREG")
	)
	(via
		(at 41.3258 -178.689)
		(size 0.508)
		(drill 0.254)
		(layers "F.Cu" "B.Cu")
		(net "P3V3_STBY_VREG")
	)
	(segment
		(start 32.827214 -177.917602)
		(end 31.40837 -179.336446)
		(width 0.254)
		(layer "B.Cu")
		(net "P3V3_STBY_VREG")
	)
	(segment
		(start 29.915358 -179.336446)
		(end 29.361892 -179.889912)
		(width 0.254)
		(layer "B.Cu")
		(net "P3V3_STBY_VREG")
	)
	(segment
		(start 29.361892 -179.889912)
		(end 28.722574 -180.52923)
		(width 0.254)
		(layer "B.Cu")
		(net "P3V3_STBY_VREG")
	)
	(segment
		(start 41.3258 -178.689)
		(end 41.325292 -178.688492)
		(width 0.254)
		(layer "B.Cu")
		(net "P3V3_STBY_VREG")
	)
	(segment
		(start 31.40837 -179.336446)
		(end 29.915358 -179.336446)
		(width 0.254)
		(layer "B.Cu")
		(net "P3V3_STBY_VREG")
	)
	(segment
		(start 38.661594 -177.917602)
		(end 32.827214 -177.917602)
		(width 0.254)
		(layer "B.Cu")
		(net "P3V3_STBY_VREG")
	)
	(segment
		(start 28.722574 -180.52923)
		(end 27.01417 -180.52923)
		(width 0.254)
		(layer "B.Cu")
		(net "P3V3_STBY_VREG")
	)
	(segment
		(start 41.325292 -178.688492)
		(end 39.432484 -178.688492)
		(width 0.254)
		(layer "B.Cu")
		(net "P3V3_STBY_VREG")
	)
	(segment
		(start 39.432484 -178.688492)
		(end 38.661594 -177.917602)
		(width 0.254)
		(layer "B.Cu")
		(net "P3V3_STBY_VREG")
	)
	(segment
		(start 37.744146 -173.66361)
		(end 37.744146 -174.67961)
		(width 0.254)
		(layer "F.Cu")
		(net "P3V3_STBY_VFB_R")
	)
	(segment
		(start 37.744146 -174.67961)
		(end 41.871646 -174.67961)
		(width 0.254)
		(layer "F.Cu")
		(net "P3V3_STBY_VFB_R")
	)
	(segment
		(start 41.871646 -174.67961)
		(end 42.913046 -175.72101)
		(width 0.254)
		(layer "F.Cu")
		(net "P3V3_STBY_VFB_R")
	)
	(segment
		(start 36.3474 -176.9872)
		(end 36.744148 -177.383948)
		(width 0.254)
		(layer "F.Cu")
		(net "P3V3_STBY_VFB")
	)
	(segment
		(start 36.744148 -177.383948)
		(end 36.744148 -179.070508)
		(width 0.254)
		(layer "F.Cu")
		(net "P3V3_STBY_VFB")
	)
	(segment
		(start 36.8681 -174.692564)
		(end 36.855146 -174.67961)
		(width 0.254)
		(layer "F.Cu")
		(net "P3V3_STBY_VFB")
	)
	(segment
		(start 36.855146 -173.66361)
		(end 36.845494 -173.653958)
		(width 0.254)
		(layer "F.Cu")
		(net "P3V3_STBY_VFB")
	)
	(segment
		(start 36.8681 -175.6664)
		(end 36.3474 -176.1871)
		(width 0.254)
		(layer "F.Cu")
		(net "P3V3_STBY_VFB")
	)
	(segment
		(start 36.855146 -174.67961)
		(end 36.855146 -173.66361)
		(width 0.254)
		(layer "F.Cu")
		(net "P3V3_STBY_VFB")
	)
	(segment
		(start 36.240974 -173.653958)
		(end 35.839146 -174.055786)
		(width 0.254)
		(layer "F.Cu")
		(net "P3V3_STBY_VFB")
	)
	(segment
		(start 36.845494 -173.653958)
		(end 36.240974 -173.653958)
		(width 0.254)
		(layer "F.Cu")
		(net "P3V3_STBY_VFB")
	)
	(segment
		(start 36.8681 -175.6664)
		(end 36.8681 -174.692564)
		(width 0.254)
		(layer "F.Cu")
		(net "P3V3_STBY_VFB")
	)
	(segment
		(start 35.839146 -174.055786)
		(end 35.839146 -174.67961)
		(width 0.254)
		(layer "F.Cu")
		(net "P3V3_STBY_VFB")
	)
	(segment
		(start 36.3474 -176.1871)
		(end 36.3474 -176.9872)
		(width 0.254)
		(layer "F.Cu")
		(net "P3V3_STBY_VFB")
	)
	(via
		(at 36.3474 -176.9872)
		(size 0.6604)
		(drill 0.3302)
		(layers "F.Cu" "B.Cu")
		(net "P3V3_STBY_VFB")
	)
	(segment
		(start 31.0134 -178.257454)
		(end 30.861254 -178.4096)
		(width 0.254)
		(layer "F.Cu")
		(net "P3V3_STBY_TRIP")
	)
	(segment
		(start 30.657038 -177.062638)
		(end 29.806646 -177.062638)
		(width 0.254)
		(layer "F.Cu")
		(net "P3V3_STBY_TRIP")
	)
	(segment
		(start 31.0134 -177.419)
		(end 31.0134 -178.257454)
		(width 0.254)
		(layer "F.Cu")
		(net "P3V3_STBY_TRIP")
	)
	(segment
		(start 30.861254 -179.163218)
		(end 31.26867 -179.570634)
		(width 0.254)
		(layer "F.Cu")
		(net "P3V3_STBY_TRIP")
	)
	(segment
		(start 31.26867 -179.570634)
		(end 31.845504 -179.570634)
		(width 0.254)
		(layer "F.Cu")
		(net "P3V3_STBY_TRIP")
	)
	(segment
		(start 30.861254 -178.4096)
		(end 30.861254 -179.163218)
		(width 0.254)
		(layer "F.Cu")
		(net "P3V3_STBY_TRIP")
	)
	(segment
		(start 31.0134 -177.419)
		(end 30.657038 -177.062638)
		(width 0.254)
		(layer "F.Cu")
		(net "P3V3_STBY_TRIP")
	)
	(via
		(at 31.0134 -177.419)
		(size 0.6604)
		(drill 0.3302)
		(layers "F.Cu" "B.Cu")
		(net "P3V3_STBY_TRIP")
	)
	(segment
		(start 39.077646 -180.64861)
		(end 38.655752 -181.070504)
		(width 0.254)
		(layer "F.Cu")
		(net "P3V3_STBY_ROVP")
	)
	(segment
		(start 38.655752 -181.070504)
		(end 36.744148 -181.070504)
		(width 0.254)
		(layer "F.Cu")
		(net "P3V3_STBY_ROVP")
	)
	(segment
		(start 39.395146 -180.64861)
		(end 39.077646 -180.64861)
		(width 0.254)
		(layer "F.Cu")
		(net "P3V3_STBY_ROVP")
	)
	(segment
		(start 31.845504 -176.752504)
		(end 31.444438 -176.351438)
		(width 0.254)
		(layer "F.Cu")
		(net "P3V3_STBY_RF")
	)
	(segment
		(start 27.147266 -179.64023)
		(end 27.58313 -179.64023)
		(width 0.254)
		(layer "F.Cu")
		(net "P3V3_STBY_RF")
	)
	(segment
		(start 31.444438 -176.351438)
		(end 30.848046 -176.351438)
		(width 0.254)
		(layer "F.Cu")
		(net "P3V3_STBY_RF")
	)
	(segment
		(start 27.58313 -179.64023)
		(end 28.2448 -180.3019)
		(width 0.254)
		(layer "F.Cu")
		(net "P3V3_STBY_RF")
	)
	(segment
		(start 31.845504 -179.070508)
		(end 31.845504 -178.085496)
		(width 0.254)
		(layer "F.Cu")
		(net "P3V3_STBY_RF")
	)
	(segment
		(start 31.845504 -178.085496)
		(end 31.845504 -176.752504)
		(width 0.254)
		(layer "F.Cu")
		(net "P3V3_STBY_RF")
	)
	(via
		(at 31.845504 -178.085496)
		(size 0.508)
		(drill 0.254)
		(layers "F.Cu" "B.Cu")
		(net "P3V3_STBY_RF")
	)
	(via
		(at 30.225492 -178.085496)
		(size 0.6096)
		(drill 0.3048)
		(layers "F.Cu" "B.Cu")
		(net "P3V3_STBY_RF")
	)
	(via
		(at 27.147266 -179.64023)
		(size 0.508)
		(drill 0.254)
		(layers "F.Cu" "B.Cu")
		(net "P3V3_STBY_RF")
	)
	(segment
		(start 27.147266 -179.64023)
		(end 27.7368 -179.050696)
		(width 0.254)
		(layer "B.Cu")
		(net "P3V3_STBY_RF")
	)
	(segment
		(start 27.7368 -179.050696)
		(end 27.7368 -178.97602)
		(width 0.254)
		(layer "B.Cu")
		(net "P3V3_STBY_RF")
	)
	(segment
		(start 27.7368 -178.97602)
		(end 28.627324 -178.085496)
		(width 0.254)
		(layer "B.Cu")
		(net "P3V3_STBY_RF")
	)
	(segment
		(start 30.225492 -178.085496)
		(end 31.845504 -178.085496)
		(width 0.254)
		(layer "B.Cu")
		(net "P3V3_STBY_RF")
	)
	(segment
		(start 28.627324 -178.085496)
		(end 30.225492 -178.085496)
		(width 0.254)
		(layer "B.Cu")
		(net "P3V3_STBY_RF")
	)
	(segment
		(start 45.76826 -184.60085)
		(end 43.826938 -184.60085)
		(width 0.254)
		(layer "F.Cu")
		(net "P3V3_STBY_OUT")
	)
	(segment
		(start 59.0042 -178.8922)
		(end 58.1787 -178.0667)
		(width 0.381)
		(layer "F.Cu")
		(net "P3V3_STBY_OUT")
	)
	(segment
		(start 58.1787 -178.0667)
		(end 46.782736 -178.0667)
		(width 0.381)
		(layer "F.Cu")
		(net "P3V3_STBY_OUT")
	)
	(segment
		(start 43.826938 -184.60085)
		(end 43.420538 -184.19445)
		(width 0.254)
		(layer "F.Cu")
		(net "P3V3_STBY_OUT")
	)
	(segment
		(start 46.782736 -178.0667)
		(end 44.437046 -175.72101)
		(width 0.381)
		(layer "F.Cu")
		(net "P3V3_STBY_OUT")
	)
	(segment
		(start 59.0042 -181.0004)
		(end 59.0042 -178.8922)
		(width 0.381)
		(layer "F.Cu")
		(net "P3V3_STBY_OUT")
	)
	(segment
		(start 43.420538 -184.19445)
		(end 43.420538 -180.14315)
		(width 0.254)
		(layer "F.Cu")
		(net "P3V3_STBY_OUT")
	)
	(segment
		(start 43.420538 -180.14315)
		(end 43.623738 -179.93995)
		(width 0.254)
		(layer "F.Cu")
		(net "P3V3_STBY_OUT")
	)
	(via
		(at 56.465724 -187.414154)
		(size 0.6604)
		(drill 0.3302)
		(layers "F.Cu" "B.Cu")
		(net "P3V3_STBY_OUT")
	)
	(via
		(at 56.384698 -185.046112)
		(size 0.6604)
		(drill 0.3302)
		(layers "F.Cu" "B.Cu")
		(net "P3V3_STBY_OUT")
	)
	(segment
		(start 30.093158 -178.327558)
		(end 30.187646 -178.422046)
		(width 0.254)
		(layer "F.Cu")
		(net "P3V3_STBY_MODE")
	)
	(segment
		(start 30.187646 -178.422046)
		(end 30.187646 -179.209446)
		(width 0.254)
		(layer "F.Cu")
		(net "P3V3_STBY_MODE")
	)
	(segment
		(start 28.790646 -178.17211)
		(end 29.93771 -178.17211)
		(width 0.254)
		(layer "F.Cu")
		(net "P3V3_STBY_MODE")
	)
	(segment
		(start 31.048706 -180.070506)
		(end 31.845504 -180.070506)
		(width 0.254)
		(layer "F.Cu")
		(net "P3V3_STBY_MODE")
	)
	(segment
		(start 30.187646 -179.209446)
		(end 31.048706 -180.070506)
		(width 0.254)
		(layer "F.Cu")
		(net "P3V3_STBY_MODE")
	)
	(segment
		(start 28.790646 -178.17211)
		(end 28.790646 -177.062638)
		(width 0.254)
		(layer "F.Cu")
		(net "P3V3_STBY_MODE")
	)
	(segment
		(start 29.93771 -178.17211)
		(end 30.093158 -178.327558)
		(width 0.254)
		(layer "F.Cu")
		(net "P3V3_STBY_MODE")
	)
	(via
		(at 30.093158 -178.327558)
		(size 0.6604)
		(drill 0.3302)
		(layers "F.Cu" "B.Cu")
		(net "P3V3_STBY_MODE")
	)
	(segment
		(start 38.565836 -175.6664)
		(end 38.595046 -175.69561)
		(width 0.254)
		(layer "F.Cu")
		(net "P3V3_STBY_LL_R")
	)
	(segment
		(start 37.7571 -175.6664)
		(end 38.565836 -175.6664)
		(width 0.254)
		(layer "F.Cu")
		(net "P3V3_STBY_LL_R")
	)
	(segment
		(start 43.598338 -179.07635)
		(end 43.623738 -179.05095)
		(width 0.254)
		(layer "F.Cu")
		(net "P3V3_STBY_LL_R")
	)
	(segment
		(start 43.623738 -179.05095)
		(end 44.817538 -179.05095)
		(width 0.254)
		(layer "F.Cu")
		(net "P3V3_STBY_LL_R")
	)
	(segment
		(start 42.683938 -179.07635)
		(end 43.598338 -179.07635)
		(width 0.254)
		(layer "F.Cu")
		(net "P3V3_STBY_LL_R")
	)
	(via
		(at 38.595046 -175.69561)
		(size 0.508)
		(drill 0.254)
		(layers "F.Cu" "B.Cu")
		(net "P3V3_STBY_LL_R")
	)
	(via
		(at 43.903392 -177.827432)
		(size 0.6096)
		(drill 0.3048)
		(layers "F.Cu" "B.Cu")
		(net "P3V3_STBY_LL_R")
	)
	(via
		(at 44.817538 -179.05095)
		(size 0.508)
		(drill 0.254)
		(layers "F.Cu" "B.Cu")
		(net "P3V3_STBY_LL_R")
	)
	(segment
		(start 42.619676 -177.827432)
		(end 43.903392 -177.827432)
		(width 0.254)
		(layer "B.Cu")
		(net "P3V3_STBY_LL_R")
	)
	(segment
		(start 41.956736 -177.164492)
		(end 42.619676 -177.827432)
		(width 0.254)
		(layer "B.Cu")
		(net "P3V3_STBY_LL_R")
	)
	(segment
		(start 43.903392 -177.827432)
		(end 44.25188 -177.827432)
		(width 0.254)
		(layer "B.Cu")
		(net "P3V3_STBY_LL_R")
	)
	(segment
		(start 44.817538 -178.39309)
		(end 44.817538 -179.05095)
		(width 0.254)
		(layer "B.Cu")
		(net "P3V3_STBY_LL_R")
	)
	(segment
		(start 40.063928 -177.164492)
		(end 41.956736 -177.164492)
		(width 0.254)
		(layer "B.Cu")
		(net "P3V3_STBY_LL_R")
	)
	(segment
		(start 38.595046 -175.69561)
		(end 40.063928 -177.164492)
		(width 0.254)
		(layer "B.Cu")
		(net "P3V3_STBY_LL_R")
	)
	(segment
		(start 44.25188 -177.827432)
		(end 44.817538 -178.39309)
		(width 0.254)
		(layer "B.Cu")
		(net "P3V3_STBY_LL_R")
	)
	(segment
		(start 42.963338 -180.24475)
		(end 42.683938 -179.96535)
		(width 0.254)
		(layer "F.Cu")
		(net "P3V3_STBY_LL")
	)
	(segment
		(start 42.963338 -184.14365)
		(end 42.963338 -180.24475)
		(width 0.254)
		(layer "F.Cu")
		(net "P3V3_STBY_LL")
	)
	(segment
		(start 42.506138 -184.60085)
		(end 42.963338 -184.14365)
		(width 0.254)
		(layer "F.Cu")
		(net "P3V3_STBY_LL")
	)
	(segment
		(start 40.209216 -184.60085)
		(end 42.506138 -184.60085)
		(width 0.254)
		(layer "F.Cu")
		(net "P3V3_STBY_LL")
	)
	(via
		(at 36.588192 -186.820556)
		(size 0.6604)
		(drill 0.3302)
		(layers "F.Cu" "B.Cu")
		(net "P3V3_STBY_LL")
	)
	(via
		(at 39.4716 -182.2958)
		(size 0.7112)
		(drill 0.4064)
		(layers "F.Cu" "B.Cu")
		(net "P3V3_STBY_LL")
	)
	(segment
		(start 40.884856 -182.186072)
		(end 39.581328 -182.186072)
		(width 0.508)
		(layer "B.Cu")
		(net "P3V3_STBY_LL")
	)
	(segment
		(start 39.581328 -182.186072)
		(end 39.4716 -182.2958)
		(width 0.508)
		(layer "B.Cu")
		(net "P3V3_STBY_LL")
	)
	(segment
		(start 38.18509 -177.58791)
		(end 37.680646 -178.092354)
		(width 0.254)
		(layer "F.Cu")
		(net "P3V3_STBY_EN")
	)
	(segment
		(start 39.585646 -177.58791)
		(end 38.544246 -177.58791)
		(width 0.254)
		(layer "F.Cu")
		(net "P3V3_STBY_EN")
	)
	(segment
		(start 40.6908 -177.58791)
		(end 39.585646 -177.58791)
		(width 0.254)
		(layer "F.Cu")
		(net "P3V3_STBY_EN")
	)
	(segment
		(start 37.680646 -178.092354)
		(end 37.680646 -179.37861)
		(width 0.254)
		(layer "F.Cu")
		(net "P3V3_STBY_EN")
	)
	(segment
		(start 38.544246 -177.58791)
		(end 38.18509 -177.58791)
		(width 0.254)
		(layer "F.Cu")
		(net "P3V3_STBY_EN")
	)
	(segment
		(start 37.488622 -179.570634)
		(end 36.744148 -179.570634)
		(width 0.254)
		(layer "F.Cu")
		(net "P3V3_STBY_EN")
	)
	(segment
		(start 37.680646 -179.37861)
		(end 37.488622 -179.570634)
		(width 0.254)
		(layer "F.Cu")
		(net "P3V3_STBY_EN")
	)
	(segment
		(start 41.719246 -177.58791)
		(end 40.6908 -177.58791)
		(width 0.254)
		(layer "F.Cu")
		(net "P3V3_STBY_EN")
	)
	(via
		(at 40.6908 -177.58791)
		(size 0.6604)
		(drill 0.3302)
		(layers "F.Cu" "B.Cu")
		(net "P3V3_STBY_EN")
	)
	(segment
		(start 33.693354 -187.96381)
		(end 35.306 -187.96381)
		(width 0.508)
		(layer "F.Cu")
		(net "P3V3_SNB")
	)
	(segment
		(start 36.542218 -187.972192)
		(end 36.533836 -187.96381)
		(width 0.508)
		(layer "F.Cu")
		(net "P3V3_SNB")
	)
	(segment
		(start 36.533836 -187.96381)
		(end 35.306 -187.96381)
		(width 0.508)
		(layer "F.Cu")
		(net "P3V3_SNB")
	)
	(via
		(at 35.306 -187.96381)
		(size 0.6604)
		(drill 0.3302)
		(layers "F.Cu" "B.Cu")
		(net "P3V3_SNB")
	)
	(segment
		(start 150.684738 -12.168378)
		(end 151.014938 -12.168378)
		(width 0.254)
		(layer "F.Cu")
		(net "P1V8_STBY_VRG5")
	)
	(segment
		(start 148.616416 -10.596118)
		(end 148.679916 -10.532618)
		(width 0.254)
		(layer "F.Cu")
		(net "P1V8_STBY_VRG5")
	)
	(segment
		(start 151.511762 -11.671554)
		(end 152.386792 -11.671554)
		(width 0.254)
		(layer "F.Cu")
		(net "P1V8_STBY_VRG5")
	)
	(segment
		(start 149.109176 -12.168378)
		(end 150.684738 -12.168378)
		(width 0.254)
		(layer "F.Cu")
		(net "P1V8_STBY_VRG5")
	)
	(segment
		(start 151.014938 -12.168378)
		(end 151.511762 -11.671554)
		(width 0.254)
		(layer "F.Cu")
		(net "P1V8_STBY_VRG5")
	)
	(segment
		(start 148.616416 -11.675618)
		(end 148.616416 -10.596118)
		(width 0.254)
		(layer "F.Cu")
		(net "P1V8_STBY_VRG5")
	)
	(segment
		(start 148.616416 -11.675618)
		(end 149.109176 -12.168378)
		(width 0.254)
		(layer "F.Cu")
		(net "P1V8_STBY_VRG5")
	)
	(via
		(at 150.684738 -12.168378)
		(size 0.6604)
		(drill 0.3302)
		(layers "F.Cu" "B.Cu")
		(net "P1V8_STBY_VRG5")
	)
	(segment
		(start 153.174954 -13.352272)
		(end 153.174954 -12.972542)
		(width 0.254)
		(layer "F.Cu")
		(net "P1V8_STBY_VO")
	)
	(segment
		(start 151.03221 -14.504924)
		(end 151.004016 -14.533118)
		(width 0.254)
		(layer "F.Cu")
		(net "P1V8_STBY_VO")
	)
	(segment
		(start 152.022302 -14.504924)
		(end 151.03221 -14.504924)
		(width 0.254)
		(layer "F.Cu")
		(net "P1V8_STBY_VO")
	)
	(segment
		(start 152.022302 -14.504924)
		(end 153.174954 -13.352272)
		(width 0.254)
		(layer "F.Cu")
		(net "P1V8_STBY_VO")
	)
	(via
		(at 152.022302 -14.504924)
		(size 0.6604)
		(drill 0.3302)
		(layers "F.Cu" "B.Cu")
		(net "P1V8_STBY_VO")
	)
	(segment
		(start 159.1818 -15.187168)
		(end 157.999684 -14.005052)
		(width 0.508)
		(layer "F.Cu")
		(net "P1V8_STBY_VBST_RR")
	)
	(segment
		(start 159.1818 -15.2908)
		(end 159.946594 -16.055594)
		(width 0.508)
		(layer "F.Cu")
		(net "P1V8_STBY_VBST_RR")
	)
	(segment
		(start 159.1818 -15.2908)
		(end 159.1818 -15.187168)
		(width 0.508)
		(layer "F.Cu")
		(net "P1V8_STBY_VBST_RR")
	)
	(segment
		(start 159.946594 -16.055594)
		(end 160.472374 -16.055594)
		(width 0.508)
		(layer "F.Cu")
		(net "P1V8_STBY_VBST_RR")
	)
	(via
		(at 159.1818 -15.2908)
		(size 0.6604)
		(drill 0.3302)
		(layers "F.Cu" "B.Cu")
		(net "P1V8_STBY_VBST_RR")
	)
	(segment
		(start 161.403538 -10.847578)
		(end 160.089342 -10.847578)
		(width 0.254)
		(layer "F.Cu")
		(net "P1V8_STBY_SW")
	)
	(segment
		(start 161.886138 -13.881862)
		(end 161.886138 -11.330178)
		(width 0.254)
		(layer "F.Cu")
		(net "P1V8_STBY_SW")
	)
	(segment
		(start 160.04413 -10.847578)
		(end 160.089342 -10.847578)
		(width 0.254)
		(layer "F.Cu")
		(net "P1V8_STBY_SW")
	)
	(segment
		(start 161.886138 -11.330178)
		(end 161.403538 -10.847578)
		(width 0.254)
		(layer "F.Cu")
		(net "P1V8_STBY_SW")
	)
	(segment
		(start 161.708338 -14.441678)
		(end 161.708338 -14.059662)
		(width 0.254)
		(layer "F.Cu")
		(net "P1V8_STBY_SW")
	)
	(segment
		(start 161.708338 -14.059662)
		(end 161.886138 -13.881862)
		(width 0.254)
		(layer "F.Cu")
		(net "P1V8_STBY_SW")
	)
	(via
		(at 157.909514 -10.194544)
		(size 0.6604)
		(drill 0.3302)
		(layers "F.Cu" "B.Cu")
		(net "P1V8_STBY_SW")
	)
	(segment
		(start 151.398478 -10.977118)
		(end 151.593042 -11.171682)
		(width 0.254)
		(layer "F.Cu")
		(net "P1V8_STBY_SS")
	)
	(segment
		(start 151.593042 -11.171682)
		(end 152.386792 -11.171682)
		(width 0.254)
		(layer "F.Cu")
		(net "P1V8_STBY_SS")
	)
	(segment
		(start 150.710138 -10.977118)
		(end 151.398478 -10.977118)
		(width 0.254)
		(layer "F.Cu")
		(net "P1V8_STBY_SS")
	)
	(segment
		(start 149.632416 -10.977118)
		(end 150.710138 -10.977118)
		(width 0.254)
		(layer "F.Cu")
		(net "P1V8_STBY_SS")
	)
	(via
		(at 150.710138 -10.977118)
		(size 0.6604)
		(drill 0.3302)
		(layers "F.Cu" "B.Cu")
		(net "P1V8_STBY_SS")
	)
	(segment
		(start 153.67508 -9.883394)
		(end 153.67508 -8.14832)
		(width 0.254)
		(layer "F.Cu")
		(net "P1V8_STBY_EN_R")
	)
	(segment
		(start 153.224738 -7.697978)
		(end 152.058624 -7.697978)
		(width 0.254)
		(layer "F.Cu")
		(net "P1V8_STBY_EN_R")
	)
	(segment
		(start 151.366728 -8.389874)
		(end 152.058624 -7.697978)
		(width 0.254)
		(layer "F.Cu")
		(net "P1V8_STBY_EN_R")
	)
	(segment
		(start 151.013414 -8.389874)
		(end 151.366728 -8.389874)
		(width 0.254)
		(layer "F.Cu")
		(net "P1V8_STBY_EN_R")
	)
	(segment
		(start 153.67508 -8.14832)
		(end 153.224738 -7.697978)
		(width 0.254)
		(layer "F.Cu")
		(net "P1V8_STBY_EN_R")
	)
	(via
		(at 152.058624 -7.697978)
		(size 0.6604)
		(drill 0.3302)
		(layers "F.Cu" "B.Cu")
		(net "P1V8_STBY_EN_R")
	)
	(segment
		(start 149.008338 -15.432278)
		(end 149.948138 -15.432278)
		(width 0.254)
		(layer "F.Cu")
		(net "P1V8_STBY_CC_R")
	)
	(segment
		(start 149.958298 -15.422118)
		(end 151.004016 -15.422118)
		(width 0.254)
		(layer "F.Cu")
		(net "P1V8_STBY_CC_R")
	)
	(segment
		(start 146.663156 -15.432278)
		(end 146.660616 -15.434818)
		(width 0.254)
		(layer "F.Cu")
		(net "P1V8_STBY_CC_R")
	)
	(segment
		(start 147.886928 -15.432278)
		(end 146.663156 -15.432278)
		(width 0.254)
		(layer "F.Cu")
		(net "P1V8_STBY_CC_R")
	)
	(segment
		(start 149.948138 -15.432278)
		(end 149.958298 -15.422118)
		(width 0.254)
		(layer "F.Cu")
		(net "P1V8_STBY_CC_R")
	)
	(segment
		(start 149.008338 -15.432278)
		(end 147.886928 -15.432278)
		(width 0.254)
		(layer "F.Cu")
		(net "P1V8_STBY_CC_R")
	)
	(via
		(at 147.886928 -15.432278)
		(size 0.6604)
		(drill 0.3302)
		(layers "F.Cu" "B.Cu")
		(net "P1V8_STBY_CC_R")
	)
	(segment
		(start 146.660616 -13.0175)
		(end 146.660616 -13.910818)
		(width 0.254)
		(layer "F.Cu")
		(net "P1V8_STBY_CC")
	)
	(segment
		(start 171.106338 -9.056878)
		(end 171.106338 -8.409178)
		(width 0.1016)
		(layer "F.Cu")
		(net "P1V8_STBY_CC")
	)
	(segment
		(start 146.773138 -12.904978)
		(end 146.660616 -13.0175)
		(width 0.254)
		(layer "F.Cu")
		(net "P1V8_STBY_CC")
	)
	(via
		(at 146.773138 -12.904978)
		(size 0.508)
		(drill 0.254)
		(layers "F.Cu" "B.Cu")
		(net "P1V8_STBY_CC")
	)
	(via
		(at 171.106338 -8.409178)
		(size 0.508)
		(drill 0.254)
		(layers "F.Cu" "B.Cu")
		(net "P1V8_STBY_CC")
	)
	(via
		(at 160.816798 -5.018786)
		(size 0.6096)
		(drill 0.3048)
		(layers "F.Cu" "B.Cu")
		(net "P1V8_STBY_CC")
	)
	(segment
		(start 148.841714 -5.018786)
		(end 147.273264 -6.587236)
		(width 0.254)
		(layer "B.Cu")
		(net "P1V8_STBY_CC")
	)
	(segment
		(start 170.042586 -5.018786)
		(end 160.816798 -5.018786)
		(width 0.254)
		(layer "B.Cu")
		(net "P1V8_STBY_CC")
	)
	(segment
		(start 171.106338 -6.082538)
		(end 170.042586 -5.018786)
		(width 0.254)
		(layer "B.Cu")
		(net "P1V8_STBY_CC")
	)
	(segment
		(start 147.273264 -6.587236)
		(end 147.273264 -12.404852)
		(width 0.254)
		(layer "B.Cu")
		(net "P1V8_STBY_CC")
	)
	(segment
		(start 147.273264 -12.404852)
		(end 146.773138 -12.904978)
		(width 0.254)
		(layer "B.Cu")
		(net "P1V8_STBY_CC")
	)
	(segment
		(start 160.816798 -5.018786)
		(end 148.841714 -5.018786)
		(width 0.254)
		(layer "B.Cu")
		(net "P1V8_STBY_CC")
	)
	(segment
		(start 171.106338 -8.409178)
		(end 171.106338 -6.082538)
		(width 0.254)
		(layer "B.Cu")
		(net "P1V8_STBY_CC")
	)
	(segment
		(start 73.1774 -137.889996)
		(end 73.1774 -137.8966)
		(width 0.127)
		(layer "F.Cu")
		(net "FP_PWR_BTN_N_R")
	)
	(segment
		(start 72.007222 -138.895836)
		(end 71.53783 -138.895836)
		(width 0.127)
		(layer "F.Cu")
		(net "FP_PWR_BTN_N_R")
	)
	(segment
		(start 73.1774 -137.8966)
		(end 73.006458 -137.8966)
		(width 0.127)
		(layer "F.Cu")
		(net "FP_PWR_BTN_N_R")
	)
	(segment
		(start 73.48347 -138.863324)
		(end 73.48347 -138.196066)
		(width 0.127)
		(layer "F.Cu")
		(net "FP_PWR_BTN_N_R")
	)
	(segment
		(start 73.006458 -137.8966)
		(end 72.007222 -138.895836)
		(width 0.127)
		(layer "F.Cu")
		(net "FP_PWR_BTN_N_R")
	)
	(segment
		(start 73.48347 -138.196066)
		(end 73.1774 -137.889996)
		(width 0.127)
		(layer "F.Cu")
		(net "FP_PWR_BTN_N_R")
	)
	(via
		(at 73.1774 -137.8966)
		(size 0.6604)
		(drill 0.3302)
		(layers "F.Cu" "B.Cu")
		(net "FP_PWR_BTN_N_R")
	)
	(segment
		(start 71.933562 -157.089094)
		(end 71.919846 -157.10281)
		(width 0.127)
		(layer "F.Cu")
		(net "FM_OSC_50M_EN")
	)
	(segment
		(start 71.919846 -157.10281)
		(end 71.05523 -157.10281)
		(width 0.127)
		(layer "F.Cu")
		(net "FM_OSC_50M_EN")
	)
	(segment
		(start 72.822562 -157.089094)
		(end 71.933562 -157.089094)
		(width 0.127)
		(layer "F.Cu")
		(net "FM_OSC_50M_EN")
	)
	(segment
		(start 94.03588 -150.085044)
		(end 94.03588 -148.992844)
		(width 0.127)
		(layer "F.Cu")
		(net "CRFILT")
	)
	(segment
		(start 92.751656 -152.73528)
		(end 92.751656 -151.238458)
		(width 0.127)
		(layer "F.Cu")
		(net "CRFILT")
	)
	(segment
		(start 93.7514 -150.369524)
		(end 94.03588 -150.085044)
		(width 0.127)
		(layer "F.Cu")
		(net "CRFILT")
	)
	(segment
		(start 92.751656 -151.238458)
		(end 93.120972 -150.869142)
		(width 0.127)
		(layer "F.Cu")
		(net "CRFILT")
	)
	(segment
		(start 93.120972 -150.869142)
		(end 93.251782 -150.869142)
		(width 0.127)
		(layer "F.Cu")
		(net "CRFILT")
	)
	(segment
		(start 93.251782 -150.869142)
		(end 93.7514 -150.369524)
		(width 0.127)
		(layer "F.Cu")
		(net "CRFILT")
	)
	(segment
		(start 97.663 -156.591)
		(end 97.648522 -156.605478)
		(width 0.127)
		(layer "F.Cu")
		(net "CFG_SEL1")
	)
	(segment
		(start 97.663 -156.591)
		(end 98.121724 -156.591)
		(width 0.127)
		(layer "F.Cu")
		(net "CFG_SEL1")
	)
	(segment
		(start 98.121724 -156.591)
		(end 98.497644 -156.96692)
		(width 0.127)
		(layer "F.Cu")
		(net "CFG_SEL1")
	)
	(segment
		(start 97.648522 -156.605478)
		(end 95.621856 -156.605478)
		(width 0.127)
		(layer "F.Cu")
		(net "CFG_SEL1")
	)
	(via
		(at 97.663 -156.591)
		(size 0.508)
		(drill 0.254)
		(layers "F.Cu" "B.Cu")
		(net "CFG_SEL1")
	)
	(segment
		(start 97.42805 -156.82595)
		(end 97.663 -156.591)
		(width 0.127)
		(layer "B.Cu")
		(net "CFG_SEL1")
	)
	(segment
		(start 96.35871 -156.82595)
		(end 97.42805 -156.82595)
		(width 0.127)
		(layer "B.Cu")
		(net "CFG_SEL1")
	)
	(segment
		(start 98.4885 -155.9306)
		(end 98.4631 -155.9052)
		(width 0.127)
		(layer "F.Cu")
		(net "CFG_SEL0")
	)
	(segment
		(start 98.1456 -154.0637)
		(end 98.4377 -153.7716)
		(width 0.127)
		(layer "F.Cu")
		(net "CFG_SEL0")
	)
	(segment
		(start 98.4631 -155.9052)
		(end 97.6122 -155.9052)
		(width 0.127)
		(layer "F.Cu")
		(net "CFG_SEL0")
	)
	(segment
		(start 98.4377 -153.7716)
		(end 98.9457 -153.7716)
		(width 0.127)
		(layer "F.Cu")
		(net "CFG_SEL0")
	)
	(segment
		(start 97.411794 -156.105606)
		(end 95.621856 -156.105606)
		(width 0.127)
		(layer "F.Cu")
		(net "CFG_SEL0")
	)
	(segment
		(start 98.1456 -154.813)
		(end 98.1456 -154.0637)
		(width 0.127)
		(layer "F.Cu")
		(net "CFG_SEL0")
	)
	(segment
		(start 97.6122 -155.9052)
		(end 97.411794 -156.105606)
		(width 0.127)
		(layer "F.Cu")
		(net "CFG_SEL0")
	)
	(segment
		(start 98.4885 -155.9306)
		(end 98.4885 -155.1559)
		(width 0.127)
		(layer "F.Cu")
		(net "CFG_SEL0")
	)
	(segment
		(start 98.4885 -155.1559)
		(end 98.1456 -154.813)
		(width 0.127)
		(layer "F.Cu")
		(net "CFG_SEL0")
	)
	(via
		(at 98.1456 -154.813)
		(size 0.6604)
		(drill 0.3302)
		(layers "F.Cu" "B.Cu")
		(net "CFG_SEL0")
	)
	(segment
		(start 46.500034 -151.800052)
		(end 46.122844 -152.177242)
		(width 0.127)
		(layer "F.Cu")
		(net "BOARD_REV_2")
	)
	(via
		(at 45.865034 -155.27655)
		(size 0.6096)
		(drill 0.3048)
		(layers "F.Cu" "B.Cu")
		(net "BOARD_REV_2")
	)
	(via
		(at 46.122844 -152.177242)
		(size 0.4572)
		(drill 0.2032)
		(layers "F.Cu" "B.Cu")
		(net "BOARD_REV_2")
	)
	(segment
		(start 46.477428 -152.852628)
		(end 46.122844 -152.498044)
		(width 0.127)
		(layer "B.Cu")
		(net "BOARD_REV_2")
	)
	(segment
		(start 45.865034 -155.495752)
		(end 46.303692 -155.93441)
		(width 0.127)
		(layer "B.Cu")
		(net "BOARD_REV_2")
	)
	(segment
		(start 46.303692 -156.292804)
		(end 46.90364 -156.892752)
		(width 0.127)
		(layer "B.Cu")
		(net "BOARD_REV_2")
	)
	(segment
		(start 45.865034 -155.27655)
		(end 45.865034 -155.495752)
		(width 0.127)
		(layer "B.Cu")
		(net "BOARD_REV_2")
	)
	(segment
		(start 46.8376 -154.3939)
		(end 46.303692 -154.3939)
		(width 0.127)
		(layer "B.Cu")
		(net "BOARD_REV_2")
	)
	(segment
		(start 46.303692 -155.93441)
		(end 46.303692 -156.292804)
		(width 0.127)
		(layer "B.Cu")
		(net "BOARD_REV_2")
	)
	(segment
		(start 46.8376 -153.276554)
		(end 46.477428 -152.916382)
		(width 0.127)
		(layer "B.Cu")
		(net "BOARD_REV_2")
	)
	(segment
		(start 46.303692 -154.3939)
		(end 45.865034 -154.832558)
		(width 0.127)
		(layer "B.Cu")
		(net "BOARD_REV_2")
	)
	(segment
		(start 46.122844 -152.498044)
		(end 46.122844 -152.177242)
		(width 0.127)
		(layer "B.Cu")
		(net "BOARD_REV_2")
	)
	(segment
		(start 46.477428 -152.916382)
		(end 46.477428 -152.852628)
		(width 0.127)
		(layer "B.Cu")
		(net "BOARD_REV_2")
	)
	(segment
		(start 45.865034 -154.832558)
		(end 45.865034 -155.27655)
		(width 0.127)
		(layer "B.Cu")
		(net "BOARD_REV_2")
	)
	(segment
		(start 46.8376 -154.3939)
		(end 46.8376 -153.276554)
		(width 0.127)
		(layer "B.Cu")
		(net "BOARD_REV_2")
	)
	(segment
		(start 48.09998 -152.599644)
		(end 48.09998 -152.599898)
		(width 0.127)
		(layer "F.Cu")
		(net "BOARD_REV_1")
	)
	(segment
		(start 47.700184 -152.199848)
		(end 48.09998 -152.599644)
		(width 0.127)
		(layer "F.Cu")
		(net "BOARD_REV_1")
	)
	(via
		(at 46.972728 -152.71115)
		(size 0.6096)
		(drill 0.3048)
		(layers "F.Cu" "B.Cu")
		(net "BOARD_REV_1")
	)
	(via
		(at 47.700184 -152.199848)
		(size 0.4572)
		(drill 0.2032)
		(layers "F.Cu" "B.Cu")
		(net "BOARD_REV_1")
	)
	(segment
		(start 48.115474 -155.165552)
		(end 47.861474 -154.911552)
		(width 0.127)
		(layer "B.Cu")
		(net "BOARD_REV_1")
	)
	(segment
		(start 47.739808 -154.789886)
		(end 47.861474 -154.911552)
		(width 0.127)
		(layer "B.Cu")
		(net "BOARD_REV_1")
	)
	(segment
		(start 47.48403 -152.199848)
		(end 47.700184 -152.199848)
		(width 0.127)
		(layer "B.Cu")
		(net "BOARD_REV_1")
	)
	(segment
		(start 48.887634 -155.165552)
		(end 48.115474 -155.165552)
		(width 0.127)
		(layer "B.Cu")
		(net "BOARD_REV_1")
	)
	(segment
		(start 47.739808 -153.85542)
		(end 47.739808 -154.789886)
		(width 0.127)
		(layer "B.Cu")
		(net "BOARD_REV_1")
	)
	(segment
		(start 46.972728 -152.71115)
		(end 46.972728 -153.08834)
		(width 0.127)
		(layer "B.Cu")
		(net "BOARD_REV_1")
	)
	(segment
		(start 46.972728 -153.08834)
		(end 47.739808 -153.85542)
		(width 0.127)
		(layer "B.Cu")
		(net "BOARD_REV_1")
	)
	(segment
		(start 46.972728 -152.71115)
		(end 47.48403 -152.199848)
		(width 0.127)
		(layer "B.Cu")
		(net "BOARD_REV_1")
	)
	(segment
		(start 43.179492 -157.187392)
		(end 43.179492 -155.48102)
		(width 0.127)
		(layer "F.Cu")
		(net "BOARD_REV_0")
	)
	(segment
		(start 42.291 -159.962088)
		(end 43.0784 -159.174688)
		(width 0.127)
		(layer "F.Cu")
		(net "BOARD_REV_0")
	)
	(segment
		(start 43.0784 -159.174688)
		(end 43.0784 -158.735014)
		(width 0.127)
		(layer "F.Cu")
		(net "BOARD_REV_0")
	)
	(segment
		(start 43.2943 -158.519114)
		(end 43.2943 -157.3022)
		(width 0.127)
		(layer "F.Cu")
		(net "BOARD_REV_0")
	)
	(segment
		(start 44.538392 -154.12212)
		(end 44.538392 -153.18994)
		(width 0.127)
		(layer "F.Cu")
		(net "BOARD_REV_0")
	)
	(segment
		(start 44.538392 -153.18994)
		(end 44.899834 -152.828498)
		(width 0.127)
		(layer "F.Cu")
		(net "BOARD_REV_0")
	)
	(segment
		(start 42.282872 -160.980628)
		(end 41.137332 -160.980628)
		(width 0.127)
		(layer "F.Cu")
		(net "BOARD_REV_0")
	)
	(segment
		(start 42.291 -160.9725)
		(end 42.282872 -160.980628)
		(width 0.127)
		(layer "F.Cu")
		(net "BOARD_REV_0")
	)
	(segment
		(start 43.179492 -155.48102)
		(end 44.538392 -154.12212)
		(width 0.127)
		(layer "F.Cu")
		(net "BOARD_REV_0")
	)
	(segment
		(start 39.994332 -160.980628)
		(end 41.137332 -160.980628)
		(width 0.127)
		(layer "F.Cu")
		(net "BOARD_REV_0")
	)
	(segment
		(start 43.0784 -158.735014)
		(end 43.2943 -158.519114)
		(width 0.127)
		(layer "F.Cu")
		(net "BOARD_REV_0")
	)
	(segment
		(start 44.899834 -152.828498)
		(end 44.899834 -152.599898)
		(width 0.127)
		(layer "F.Cu")
		(net "BOARD_REV_0")
	)
	(segment
		(start 42.291 -160.9725)
		(end 42.291 -159.962088)
		(width 0.127)
		(layer "F.Cu")
		(net "BOARD_REV_0")
	)
	(segment
		(start 43.2943 -157.3022)
		(end 43.179492 -157.187392)
		(width 0.127)
		(layer "F.Cu")
		(net "BOARD_REV_0")
	)
	(via
		(at 41.137332 -160.980628)
		(size 0.6604)
		(drill 0.3302)
		(layers "F.Cu" "B.Cu")
		(net "BOARD_REV_0")
	)
	(segment
		(start 57.8104 -143.002)
		(end 57.012332 -143.800068)
		(width 0.127)
		(layer "F.Cu")
		(net "BMC_SMB9_DAT")
	)
	(segment
		(start 57.012332 -143.800068)
		(end 56.099964 -143.800068)
		(width 0.127)
		(layer "F.Cu")
		(net "BMC_SMB9_DAT")
	)
	(via
		(at 57.8104 -143.002)
		(size 0.508)
		(drill 0.254)
		(layers "F.Cu" "B.Cu")
		(net "BMC_SMB9_DAT")
	)
	(via
		(at 58.490358 -142.067534)
		(size 0.6096)
		(drill 0.3048)
		(layers "F.Cu" "B.Cu")
		(net "BMC_SMB9_DAT")
	)
	(segment
		(start 58.490358 -142.067534)
		(end 59.621166 -142.067534)
		(width 0.127)
		(layer "B.Cu")
		(net "BMC_SMB9_DAT")
	)
	(segment
		(start 58.075576 -142.067534)
		(end 58.490358 -142.067534)
		(width 0.127)
		(layer "B.Cu")
		(net "BMC_SMB9_DAT")
	)
	(segment
		(start 57.8104 -143.002)
		(end 57.8104 -142.33271)
		(width 0.127)
		(layer "B.Cu")
		(net "BMC_SMB9_DAT")
	)
	(segment
		(start 59.621166 -142.067534)
		(end 60.4393 -141.2494)
		(width 0.127)
		(layer "B.Cu")
		(net "BMC_SMB9_DAT")
	)
	(segment
		(start 57.8104 -142.33271)
		(end 58.075576 -142.067534)
		(width 0.127)
		(layer "B.Cu")
		(net "BMC_SMB9_DAT")
	)
	(segment
		(start 54.89956 -142.600426)
		(end 54.500018 -142.999968)
		(width 0.127)
		(layer "F.Cu")
		(net "BMC_SMB9_CLK")
	)
	(segment
		(start 54.899814 -142.600426)
		(end 54.89956 -142.600426)
		(width 0.127)
		(layer "F.Cu")
		(net "BMC_SMB9_CLK")
	)
	(via
		(at 54.899814 -142.600426)
		(size 0.4572)
		(drill 0.2032)
		(layers "F.Cu" "B.Cu")
		(net "BMC_SMB9_CLK")
	)
	(via
		(at 57.0484 -142.4686)
		(size 0.6096)
		(drill 0.3048)
		(layers "F.Cu" "B.Cu")
		(net "BMC_SMB9_CLK")
	)
	(segment
		(start 57.0484 -142.4686)
		(end 55.03164 -142.4686)
		(width 0.127)
		(layer "B.Cu")
		(net "BMC_SMB9_CLK")
	)
	(segment
		(start 60.4393 -140.1826)
		(end 59.495944 -141.125956)
		(width 0.127)
		(layer "B.Cu")
		(net "BMC_SMB9_CLK")
	)
	(segment
		(start 58.657744 -141.125956)
		(end 57.66435 -142.11935)
		(width 0.127)
		(layer "B.Cu")
		(net "BMC_SMB9_CLK")
	)
	(segment
		(start 59.495944 -141.125956)
		(end 58.657744 -141.125956)
		(width 0.127)
		(layer "B.Cu")
		(net "BMC_SMB9_CLK")
	)
	(segment
		(start 57.66435 -142.11935)
		(end 57.39765 -142.11935)
		(width 0.127)
		(layer "B.Cu")
		(net "BMC_SMB9_CLK")
	)
	(segment
		(start 57.39765 -142.11935)
		(end 57.0484 -142.4686)
		(width 0.127)
		(layer "B.Cu")
		(net "BMC_SMB9_CLK")
	)
	(segment
		(start 55.03164 -142.4686)
		(end 54.899814 -142.600426)
		(width 0.127)
		(layer "B.Cu")
		(net "BMC_SMB9_CLK")
	)
	(segment
		(start 43.700192 -155.491688)
		(end 43.700192 -156.085032)
		(width 0.127)
		(layer "F.Cu")
		(net "BMC_SMB8_DAT")
	)
	(segment
		(start 43.8023 -158.0896)
		(end 43.8658 -158.1531)
		(width 0.127)
		(layer "F.Cu")
		(net "BMC_SMB8_DAT")
	)
	(segment
		(start 43.8023 -156.800042)
		(end 43.8023 -158.0896)
		(width 0.127)
		(layer "F.Cu")
		(net "BMC_SMB8_DAT")
	)
	(segment
		(start 43.700192 -156.697934)
		(end 43.8023 -156.800042)
		(width 0.127)
		(layer "F.Cu")
		(net "BMC_SMB8_DAT")
	)
	(segment
		(start 44.899834 -154.292046)
		(end 43.700192 -155.491688)
		(width 0.127)
		(layer "F.Cu")
		(net "BMC_SMB8_DAT")
	)
	(segment
		(start 43.700192 -156.085032)
		(end 43.700192 -156.697934)
		(width 0.127)
		(layer "F.Cu")
		(net "BMC_SMB8_DAT")
	)
	(segment
		(start 44.899834 -153.399998)
		(end 44.899834 -154.292046)
		(width 0.127)
		(layer "F.Cu")
		(net "BMC_SMB8_DAT")
	)
	(via
		(at 43.700192 -156.085032)
		(size 0.6604)
		(drill 0.3302)
		(layers "F.Cu" "B.Cu")
		(net "BMC_SMB8_DAT")
	)
	(segment
		(start 44.9072 -158.1531)
		(end 44.9072 -157.394656)
		(width 0.127)
		(layer "F.Cu")
		(net "BMC_SMB8_CLK")
	)
	(segment
		(start 45.2882 -154.545538)
		(end 45.2882 -153.011632)
		(width 0.127)
		(layer "F.Cu")
		(net "BMC_SMB8_CLK")
	)
	(segment
		(start 44.5262 -157.013656)
		(end 44.5262 -157.0228)
		(width 0.127)
		(layer "F.Cu")
		(net "BMC_SMB8_CLK")
	)
	(segment
		(start 45.2882 -153.011632)
		(end 45.699934 -152.599898)
		(width 0.127)
		(layer "F.Cu")
		(net "BMC_SMB8_CLK")
	)
	(segment
		(start 44.9072 -157.394656)
		(end 44.5262 -157.013656)
		(width 0.127)
		(layer "F.Cu")
		(net "BMC_SMB8_CLK")
	)
	(segment
		(start 44.34586 -155.487878)
		(end 45.2882 -154.545538)
		(width 0.127)
		(layer "F.Cu")
		(net "BMC_SMB8_CLK")
	)
	(segment
		(start 44.34586 -156.833316)
		(end 44.34586 -155.487878)
		(width 0.127)
		(layer "F.Cu")
		(net "BMC_SMB8_CLK")
	)
	(segment
		(start 44.5262 -157.013656)
		(end 44.34586 -156.833316)
		(width 0.127)
		(layer "F.Cu")
		(net "BMC_SMB8_CLK")
	)
	(via
		(at 44.5262 -157.0228)
		(size 0.6604)
		(drill 0.3302)
		(layers "F.Cu" "B.Cu")
		(net "BMC_SMB8_CLK")
	)
	(segment
		(start 45.97019 -158.1531)
		(end 45.56506 -157.74797)
		(width 0.127)
		(layer "F.Cu")
		(net "BMC_SMB7_DAT")
	)
	(segment
		(start 45.56506 -157.02026)
		(end 44.956222 -156.411422)
		(width 0.127)
		(layer "F.Cu")
		(net "BMC_SMB7_DAT")
	)
	(segment
		(start 45.699934 -155.00858)
		(end 45.699934 -153.399998)
		(width 0.127)
		(layer "F.Cu")
		(net "BMC_SMB7_DAT")
	)
	(segment
		(start 45.56506 -157.74797)
		(end 45.56506 -157.02026)
		(width 0.127)
		(layer "F.Cu")
		(net "BMC_SMB7_DAT")
	)
	(segment
		(start 44.956222 -155.752292)
		(end 45.699934 -155.00858)
		(width 0.127)
		(layer "F.Cu")
		(net "BMC_SMB7_DAT")
	)
	(segment
		(start 44.956222 -155.895802)
		(end 44.956222 -155.752292)
		(width 0.127)
		(layer "F.Cu")
		(net "BMC_SMB7_DAT")
	)
	(segment
		(start 44.956222 -156.411422)
		(end 44.956222 -155.895802)
		(width 0.127)
		(layer "F.Cu")
		(net "BMC_SMB7_DAT")
	)
	(via
		(at 44.956222 -155.895802)
		(size 0.6604)
		(drill 0.3302)
		(layers "F.Cu" "B.Cu")
		(net "BMC_SMB7_DAT")
	)
	(segment
		(start 46.37278 -156.811218)
		(end 46.37278 -153.527252)
		(width 0.127)
		(layer "F.Cu")
		(net "BMC_SMB7_CLK")
	)
	(segment
		(start 46.37278 -153.527252)
		(end 46.500034 -153.399998)
		(width 0.127)
		(layer "F.Cu")
		(net "BMC_SMB7_CLK")
	)
	(segment
		(start 46.436026 -156.874464)
		(end 46.436026 -157.274006)
		(width 0.127)
		(layer "F.Cu")
		(net "BMC_SMB7_CLK")
	)
	(segment
		(start 47.01159 -157.84957)
		(end 47.01159 -158.1531)
		(width 0.127)
		(layer "F.Cu")
		(net "BMC_SMB7_CLK")
	)
	(segment
		(start 46.436026 -156.874464)
		(end 46.37278 -156.811218)
		(width 0.127)
		(layer "F.Cu")
		(net "BMC_SMB7_CLK")
	)
	(segment
		(start 46.436026 -157.274006)
		(end 47.01159 -157.84957)
		(width 0.127)
		(layer "F.Cu")
		(net "BMC_SMB7_CLK")
	)
	(via
		(at 46.436026 -156.874464)
		(size 0.6604)
		(drill 0.3302)
		(layers "F.Cu" "B.Cu")
		(net "BMC_SMB7_CLK")
	)
	(segment
		(start 48.05299 -157.345634)
		(end 47.554134 -156.846778)
		(width 0.127)
		(layer "F.Cu")
		(net "BMC_SMB6_DAT")
	)
	(segment
		(start 46.915578 -153.015442)
		(end 46.915578 -154.821636)
		(width 0.127)
		(layer "F.Cu")
		(net "BMC_SMB6_DAT")
	)
	(segment
		(start 46.915578 -154.821636)
		(end 47.53356 -155.439618)
		(width 0.127)
		(layer "F.Cu")
		(net "BMC_SMB6_DAT")
	)
	(segment
		(start 48.05299 -158.1531)
		(end 48.05299 -157.345634)
		(width 0.127)
		(layer "F.Cu")
		(net "BMC_SMB6_DAT")
	)
	(segment
		(start 46.500034 -152.599898)
		(end 46.915578 -153.015442)
		(width 0.127)
		(layer "F.Cu")
		(net "BMC_SMB6_DAT")
	)
	(segment
		(start 47.53356 -156.846778)
		(end 47.554134 -156.846778)
		(width 0.127)
		(layer "F.Cu")
		(net "BMC_SMB6_DAT")
	)
	(segment
		(start 47.53356 -155.439618)
		(end 47.53356 -156.846778)
		(width 0.127)
		(layer "F.Cu")
		(net "BMC_SMB6_DAT")
	)
	(via
		(at 47.554134 -156.846778)
		(size 0.6604)
		(drill 0.3302)
		(layers "F.Cu" "B.Cu")
		(net "BMC_SMB6_DAT")
	)
	(segment
		(start 49.09439 -158.1531)
		(end 49.09439 -156.627576)
		(width 0.127)
		(layer "F.Cu")
		(net "BMC_SMB6_CLK")
	)
	(segment
		(start 48.09998 -155.633166)
		(end 48.62449 -156.157676)
		(width 0.127)
		(layer "F.Cu")
		(net "BMC_SMB6_CLK")
	)
	(segment
		(start 49.09439 -156.627576)
		(end 48.62449 -156.157676)
		(width 0.127)
		(layer "F.Cu")
		(net "BMC_SMB6_CLK")
	)
	(segment
		(start 48.09998 -153.399998)
		(end 48.09998 -155.633166)
		(width 0.127)
		(layer "F.Cu")
		(net "BMC_SMB6_CLK")
	)
	(via
		(at 48.62449 -156.157676)
		(size 0.6604)
		(drill 0.3302)
		(layers "F.Cu" "B.Cu")
		(net "BMC_SMB6_CLK")
	)
	(segment
		(start 48.09998 -151.000206)
		(end 48.09998 -150.999952)
		(width 0.127)
		(layer "F.Cu")
		(net "BMC_SMB5_DAT")
	)
	(segment
		(start 48.499776 -151.400002)
		(end 48.09998 -151.000206)
		(width 0.127)
		(layer "F.Cu")
		(net "BMC_SMB5_DAT")
	)
	(via
		(at 49.1236 -160.1724)
		(size 0.508)
		(drill 0.254)
		(layers "F.Cu" "B.Cu")
		(net "BMC_SMB5_DAT")
	)
	(via
		(at 48.499776 -151.400002)
		(size 0.4572)
		(drill 0.2032)
		(layers "F.Cu" "B.Cu")
		(net "BMC_SMB5_DAT")
	)
	(segment
		(start 48.299116 -161.59226)
		(end 48.299116 -160.996884)
		(width 0.127)
		(layer "B.Cu")
		(net "BMC_SMB5_DAT")
	)
	(segment
		(start 48.299116 -160.996884)
		(end 49.1236 -160.1724)
		(width 0.127)
		(layer "B.Cu")
		(net "BMC_SMB5_DAT")
	)
	(segment
		(start 48.106076 -155.624276)
		(end 48.106076 -151.793702)
		(width 0.127)
		(layer "In2.Cu")
		(net "BMC_SMB5_DAT")
	)
	(segment
		(start 49.2506 -159.87014)
		(end 49.0982 -159.71774)
		(width 0.127)
		(layer "In2.Cu")
		(net "BMC_SMB5_DAT")
	)
	(segment
		(start 49.0982 -156.6164)
		(end 48.106076 -155.624276)
		(width 0.127)
		(layer "In2.Cu")
		(net "BMC_SMB5_DAT")
	)
	(segment
		(start 48.106076 -151.793702)
		(end 48.499776 -151.400002)
		(width 0.127)
		(layer "In2.Cu")
		(net "BMC_SMB5_DAT")
	)
	(segment
		(start 49.1236 -160.1724)
		(end 49.2506 -160.0454)
		(width 0.127)
		(layer "In2.Cu")
		(net "BMC_SMB5_DAT")
	)
	(segment
		(start 49.2506 -160.0454)
		(end 49.2506 -159.87014)
		(width 0.127)
		(layer "In2.Cu")
		(net "BMC_SMB5_DAT")
	)
	(segment
		(start 49.0982 -159.71774)
		(end 49.0982 -156.6164)
		(width 0.127)
		(layer "In2.Cu")
		(net "BMC_SMB5_DAT")
	)
	(segment
		(start 48.50003 -152.200102)
		(end 48.09998 -151.800052)
		(width 0.127)
		(layer "F.Cu")
		(net "BMC_SMB5_CLK")
	)
	(via
		(at 48.50003 -152.200102)
		(size 0.4572)
		(drill 0.2032)
		(layers "F.Cu" "B.Cu")
		(net "BMC_SMB5_CLK")
	)
	(via
		(at 50.193194 -160.197292)
		(size 0.508)
		(drill 0.254)
		(layers "F.Cu" "B.Cu")
		(net "BMC_SMB5_CLK")
	)
	(segment
		(start 50.19548 -161.59734)
		(end 50.19548 -160.199578)
		(width 0.127)
		(layer "B.Cu")
		(net "BMC_SMB5_CLK")
	)
	(segment
		(start 50.19548 -160.199578)
		(end 50.193194 -160.197292)
		(width 0.127)
		(layer "B.Cu")
		(net "BMC_SMB5_CLK")
	)
	(segment
		(start 50.193194 -160.197292)
		(end 50.2666 -160.123886)
		(width 0.127)
		(layer "In2.Cu")
		(net "BMC_SMB5_CLK")
	)
	(segment
		(start 48.895 -152.6286)
		(end 48.50003 -152.23363)
		(width 0.127)
		(layer "In2.Cu")
		(net "BMC_SMB5_CLK")
	)
	(segment
		(start 48.895 -155.7528)
		(end 48.895 -152.6286)
		(width 0.127)
		(layer "In2.Cu")
		(net "BMC_SMB5_CLK")
	)
	(segment
		(start 48.50003 -152.23363)
		(end 48.50003 -152.200102)
		(width 0.127)
		(layer "In2.Cu")
		(net "BMC_SMB5_CLK")
	)
	(segment
		(start 49.657 -156.5148)
		(end 48.895 -155.7528)
		(width 0.127)
		(layer "In2.Cu")
		(net "BMC_SMB5_CLK")
	)
	(segment
		(start 49.657 -159.3342)
		(end 49.657 -156.5148)
		(width 0.127)
		(layer "In2.Cu")
		(net "BMC_SMB5_CLK")
	)
	(segment
		(start 50.2666 -159.9438)
		(end 49.657 -159.3342)
		(width 0.127)
		(layer "In2.Cu")
		(net "BMC_SMB5_CLK")
	)
	(segment
		(start 50.2666 -160.123886)
		(end 50.2666 -159.9438)
		(width 0.127)
		(layer "In2.Cu")
		(net "BMC_SMB5_CLK")
	)
	(segment
		(start 59.443874 -146.943318)
		(end 59.444636 -146.943318)
		(width 0.127)
		(layer "F.Cu")
		(net "BMC_SMB4_DAT")
	)
	(segment
		(start 56.87441 -146.65706)
		(end 57.44337 -146.0881)
		(width 0.127)
		(layer "F.Cu")
		(net "BMC_SMB4_DAT")
	)
	(segment
		(start 60.657232 -147.74926)
		(end 60.244228 -147.74926)
		(width 0.127)
		(layer "F.Cu")
		(net "BMC_SMB4_DAT")
	)
	(segment
		(start 60.244228 -147.74926)
		(end 59.443874 -146.948906)
		(width 0.127)
		(layer "F.Cu")
		(net "BMC_SMB4_DAT")
	)
	(segment
		(start 55.642764 -146.65706)
		(end 56.87441 -146.65706)
		(width 0.127)
		(layer "F.Cu")
		(net "BMC_SMB4_DAT")
	)
	(segment
		(start 57.44337 -146.0881)
		(end 58.983372 -146.0881)
		(width 0.127)
		(layer "F.Cu")
		(net "BMC_SMB4_DAT")
	)
	(segment
		(start 55.299864 -146.99996)
		(end 55.642764 -146.65706)
		(width 0.127)
		(layer "F.Cu")
		(net "BMC_SMB4_DAT")
	)
	(segment
		(start 58.983372 -146.0881)
		(end 59.444636 -146.549364)
		(width 0.127)
		(layer "F.Cu")
		(net "BMC_SMB4_DAT")
	)
	(segment
		(start 59.443874 -146.948906)
		(end 59.443874 -146.943318)
		(width 0.127)
		(layer "F.Cu")
		(net "BMC_SMB4_DAT")
	)
	(segment
		(start 59.444636 -146.549364)
		(end 59.444636 -146.943318)
		(width 0.127)
		(layer "F.Cu")
		(net "BMC_SMB4_DAT")
	)
	(via
		(at 59.444636 -146.943318)
		(size 0.6604)
		(drill 0.3302)
		(layers "F.Cu" "B.Cu")
		(net "BMC_SMB4_DAT")
	)
	(segment
		(start 59.107832 -147.550632)
		(end 58.55716 -146.99996)
		(width 0.127)
		(layer "F.Cu")
		(net "BMC_SMB4_CLK")
	)
	(segment
		(start 59.107832 -148.338032)
		(end 59.107832 -147.550632)
		(width 0.127)
		(layer "F.Cu")
		(net "BMC_SMB4_CLK")
	)
	(segment
		(start 59.76874 -148.7678)
		(end 59.5376 -148.7678)
		(width 0.127)
		(layer "F.Cu")
		(net "BMC_SMB4_CLK")
	)
	(segment
		(start 59.5376 -148.7678)
		(end 59.107832 -148.338032)
		(width 0.127)
		(layer "F.Cu")
		(net "BMC_SMB4_CLK")
	)
	(segment
		(start 60.9981 -148.7678)
		(end 59.76874 -148.7678)
		(width 0.127)
		(layer "F.Cu")
		(net "BMC_SMB4_CLK")
	)
	(segment
		(start 58.55716 -146.99996)
		(end 56.099964 -146.99996)
		(width 0.127)
		(layer "F.Cu")
		(net "BMC_SMB4_CLK")
	)
	(via
		(at 59.76874 -148.7678)
		(size 0.6604)
		(drill 0.3302)
		(layers "F.Cu" "B.Cu")
		(net "BMC_SMB4_CLK")
	)
	(segment
		(start 56.612282 -146.19986)
		(end 56.099964 -146.19986)
		(width 0.127)
		(layer "F.Cu")
		(net "BMC_SMB3_DAT")
	)
	(segment
		(start 61.237368 -145.43659)
		(end 60.677806 -145.996152)
		(width 0.127)
		(layer "F.Cu")
		(net "BMC_SMB3_DAT")
	)
	(segment
		(start 59.540394 -145.8595)
		(end 56.952642 -145.8595)
		(width 0.127)
		(layer "F.Cu")
		(net "BMC_SMB3_DAT")
	)
	(segment
		(start 59.677046 -145.996152)
		(end 59.540394 -145.8595)
		(width 0.127)
		(layer "F.Cu")
		(net "BMC_SMB3_DAT")
	)
	(segment
		(start 60.050934 -145.996152)
		(end 59.677046 -145.996152)
		(width 0.127)
		(layer "F.Cu")
		(net "BMC_SMB3_DAT")
	)
	(segment
		(start 56.952642 -145.8595)
		(end 56.612282 -146.19986)
		(width 0.127)
		(layer "F.Cu")
		(net "BMC_SMB3_DAT")
	)
	(segment
		(start 60.677806 -145.996152)
		(end 60.050934 -145.996152)
		(width 0.127)
		(layer "F.Cu")
		(net "BMC_SMB3_DAT")
	)
	(via
		(at 60.050934 -145.996152)
		(size 0.6604)
		(drill 0.3302)
		(layers "F.Cu" "B.Cu")
		(net "BMC_SMB3_DAT")
	)
	(segment
		(start 60.59805 -144.404588)
		(end 60.502038 -144.5006)
		(width 0.127)
		(layer "F.Cu")
		(net "BMC_SMB3_CLK")
	)
	(segment
		(start 58.519822 -144.5006)
		(end 59.638438 -144.5006)
		(width 0.127)
		(layer "F.Cu")
		(net "BMC_SMB3_CLK")
	)
	(segment
		(start 56.518048 -145.400014)
		(end 57.074562 -144.8435)
		(width 0.127)
		(layer "F.Cu")
		(net "BMC_SMB3_CLK")
	)
	(segment
		(start 60.502038 -144.5006)
		(end 59.638438 -144.5006)
		(width 0.127)
		(layer "F.Cu")
		(net "BMC_SMB3_CLK")
	)
	(segment
		(start 57.074562 -144.8435)
		(end 58.176922 -144.8435)
		(width 0.127)
		(layer "F.Cu")
		(net "BMC_SMB3_CLK")
	)
	(segment
		(start 58.176922 -144.8435)
		(end 58.519822 -144.5006)
		(width 0.127)
		(layer "F.Cu")
		(net "BMC_SMB3_CLK")
	)
	(segment
		(start 56.099964 -145.400014)
		(end 56.518048 -145.400014)
		(width 0.127)
		(layer "F.Cu")
		(net "BMC_SMB3_CLK")
	)
	(via
		(at 59.638438 -144.5006)
		(size 0.6604)
		(drill 0.3302)
		(layers "F.Cu" "B.Cu")
		(net "BMC_SMB3_CLK")
	)
	(segment
		(start 45.471334 -133.471666)
		(end 45.471334 -134.341108)
		(width 0.127)
		(layer "F.Cu")
		(net "BMC_SMB2_DAT")
	)
	(segment
		(start 45.297852 -134.991348)
		(end 45.469302 -134.819898)
		(width 0.127)
		(layer "F.Cu")
		(net "BMC_SMB2_DAT")
	)
	(segment
		(start 46.392592 -129.564892)
		(end 46.472856 -129.645156)
		(width 0.127)
		(layer "F.Cu")
		(net "BMC_SMB2_DAT")
	)
	(segment
		(start 45.5676 -133.3754)
		(end 45.471334 -133.471666)
		(width 0.127)
		(layer "F.Cu")
		(net "BMC_SMB2_DAT")
	)
	(segment
		(start 45.469302 -134.34314)
		(end 45.471334 -134.341108)
		(width 0.127)
		(layer "F.Cu")
		(net "BMC_SMB2_DAT")
	)
	(segment
		(start 45.297852 -137.797794)
		(end 45.297852 -134.991348)
		(width 0.127)
		(layer "F.Cu")
		(net "BMC_SMB2_DAT")
	)
	(segment
		(start 45.699934 -138.199876)
		(end 45.297852 -137.797794)
		(width 0.127)
		(layer "F.Cu")
		(net "BMC_SMB2_DAT")
	)
	(segment
		(start 45.331126 -132.446522)
		(end 45.331126 -133.138926)
		(width 0.127)
		(layer "F.Cu")
		(net "BMC_SMB2_DAT")
	)
	(segment
		(start 46.392592 -128.652016)
		(end 46.392592 -129.564892)
		(width 0.127)
		(layer "F.Cu")
		(net "BMC_SMB2_DAT")
	)
	(segment
		(start 45.469302 -134.819898)
		(end 45.469302 -134.34314)
		(width 0.127)
		(layer "F.Cu")
		(net "BMC_SMB2_DAT")
	)
	(segment
		(start 45.331126 -133.138926)
		(end 45.5676 -133.3754)
		(width 0.127)
		(layer "F.Cu")
		(net "BMC_SMB2_DAT")
	)
	(via
		(at 46.472856 -129.645156)
		(size 0.508)
		(drill 0.254)
		(layers "F.Cu" "B.Cu")
		(net "BMC_SMB2_DAT")
	)
	(via
		(at 45.471334 -134.341108)
		(size 0.6604)
		(drill 0.3302)
		(layers "F.Cu" "B.Cu")
		(net "BMC_SMB2_DAT")
	)
	(via
		(at 45.5676 -133.3754)
		(size 0.508)
		(drill 0.254)
		(layers "F.Cu" "B.Cu")
		(net "BMC_SMB2_DAT")
	)
	(segment
		(start 46.91888 -130.31851)
		(end 46.91888 -130.737356)
		(width 0.127)
		(layer "B.Cu")
		(net "BMC_SMB2_DAT")
	)
	(segment
		(start 45.6438 -133.2992)
		(end 45.5676 -133.3754)
		(width 0.127)
		(layer "B.Cu")
		(net "BMC_SMB2_DAT")
	)
	(segment
		(start 46.472856 -129.872486)
		(end 46.91888 -130.31851)
		(width 0.127)
		(layer "B.Cu")
		(net "BMC_SMB2_DAT")
	)
	(segment
		(start 45.6438 -132.707634)
		(end 45.6438 -133.2992)
		(width 0.127)
		(layer "B.Cu")
		(net "BMC_SMB2_DAT")
	)
	(segment
		(start 46.472856 -129.645156)
		(end 46.472856 -129.872486)
		(width 0.127)
		(layer "B.Cu")
		(net "BMC_SMB2_DAT")
	)
	(segment
		(start 46.28642 -131.369816)
		(end 46.28642 -132.065014)
		(width 0.127)
		(layer "B.Cu")
		(net "BMC_SMB2_DAT")
	)
	(segment
		(start 46.91888 -130.737356)
		(end 46.28642 -131.369816)
		(width 0.127)
		(layer "B.Cu")
		(net "BMC_SMB2_DAT")
	)
	(segment
		(start 46.28642 -132.065014)
		(end 45.6438 -132.707634)
		(width 0.127)
		(layer "B.Cu")
		(net "BMC_SMB2_DAT")
	)
	(segment
		(start 46.89983 -137.799826)
		(end 47.29988 -138.199876)
		(width 0.127)
		(layer "F.Cu")
		(net "BMC_SMB2_CLK")
	)
	(segment
		(start 46.087538 -124.383292)
		(end 46.0248 -124.320554)
		(width 0.127)
		(layer "F.Cu")
		(net "BMC_SMB2_CLK")
	)
	(segment
		(start 46.970696 -124.383292)
		(end 46.087538 -124.383292)
		(width 0.127)
		(layer "F.Cu")
		(net "BMC_SMB2_CLK")
	)
	(via
		(at 46.7106 -125.2474)
		(size 0.6096)
		(drill 0.3048)
		(layers "F.Cu" "B.Cu")
		(net "BMC_SMB2_CLK")
	)
	(via
		(at 46.89983 -137.799826)
		(size 0.4572)
		(drill 0.2032)
		(layers "F.Cu" "B.Cu")
		(net "BMC_SMB2_CLK")
	)
	(via
		(at 46.0248 -124.320554)
		(size 0.508)
		(drill 0.254)
		(layers "F.Cu" "B.Cu")
		(net "BMC_SMB2_CLK")
	)
	(segment
		(start 46.0248 -124.9426)
		(end 46.0248 -124.320554)
		(width 0.127)
		(layer "B.Cu")
		(net "BMC_SMB2_CLK")
	)
	(segment
		(start 46.9265 -125.0315)
		(end 46.7106 -125.2474)
		(width 0.127)
		(layer "B.Cu")
		(net "BMC_SMB2_CLK")
	)
	(segment
		(start 46.9265 -124.206)
		(end 46.9265 -125.0315)
		(width 0.127)
		(layer "B.Cu")
		(net "BMC_SMB2_CLK")
	)
	(segment
		(start 46.3296 -125.2474)
		(end 46.0248 -124.9426)
		(width 0.127)
		(layer "B.Cu")
		(net "BMC_SMB2_CLK")
	)
	(segment
		(start 46.7106 -125.2474)
		(end 46.3296 -125.2474)
		(width 0.127)
		(layer "B.Cu")
		(net "BMC_SMB2_CLK")
	)
	(segment
		(start 46.4566 -127.4572)
		(end 46.942756 -127.943356)
		(width 0.127)
		(layer "In2.Cu")
		(net "BMC_SMB2_CLK")
	)
	(segment
		(start 47.1424 -130.0988)
		(end 47.1424 -134.112)
		(width 0.127)
		(layer "In2.Cu")
		(net "BMC_SMB2_CLK")
	)
	(segment
		(start 46.50613 -134.74827)
		(end 46.50613 -137.406126)
		(width 0.127)
		(layer "In2.Cu")
		(net "BMC_SMB2_CLK")
	)
	(segment
		(start 47.1424 -134.112)
		(end 46.50613 -134.74827)
		(width 0.127)
		(layer "In2.Cu")
		(net "BMC_SMB2_CLK")
	)
	(segment
		(start 46.942756 -127.943356)
		(end 46.942756 -129.899156)
		(width 0.127)
		(layer "In2.Cu")
		(net "BMC_SMB2_CLK")
	)
	(segment
		(start 46.0248 -124.320554)
		(end 46.4566 -124.752354)
		(width 0.127)
		(layer "In2.Cu")
		(net "BMC_SMB2_CLK")
	)
	(segment
		(start 46.50613 -137.406126)
		(end 46.89983 -137.799826)
		(width 0.127)
		(layer "In2.Cu")
		(net "BMC_SMB2_CLK")
	)
	(segment
		(start 46.4566 -124.752354)
		(end 46.4566 -127.4572)
		(width 0.127)
		(layer "In2.Cu")
		(net "BMC_SMB2_CLK")
	)
	(segment
		(start 46.942756 -129.899156)
		(end 47.1424 -130.0988)
		(width 0.127)
		(layer "In2.Cu")
		(net "BMC_SMB2_CLK")
	)
	(segment
		(start 48.264318 -135.682482)
		(end 47.417482 -135.682482)
		(width 0.127)
		(layer "F.Cu")
		(net "BMC_SMB14_DAT")
	)
	(segment
		(start 48.9712 -134.3914)
		(end 48.9712 -134.9756)
		(width 0.127)
		(layer "F.Cu")
		(net "BMC_SMB14_DAT")
	)
	(segment
		(start 47.417482 -135.682482)
		(end 46.500034 -136.59993)
		(width 0.127)
		(layer "F.Cu")
		(net "BMC_SMB14_DAT")
	)
	(segment
		(start 49.440846 -132.651754)
		(end 49.1744 -132.9182)
		(width 0.127)
		(layer "F.Cu")
		(net "BMC_SMB14_DAT")
	)
	(segment
		(start 49.440846 -132.181854)
		(end 49.440846 -132.651754)
		(width 0.127)
		(layer "F.Cu")
		(net "BMC_SMB14_DAT")
	)
	(segment
		(start 48.9712 -134.9756)
		(end 48.264318 -135.682482)
		(width 0.127)
		(layer "F.Cu")
		(net "BMC_SMB14_DAT")
	)
	(segment
		(start 49.1744 -134.1882)
		(end 48.9712 -134.3914)
		(width 0.127)
		(layer "F.Cu")
		(net "BMC_SMB14_DAT")
	)
	(segment
		(start 49.1744 -132.9182)
		(end 49.1744 -134.1882)
		(width 0.127)
		(layer "F.Cu")
		(net "BMC_SMB14_DAT")
	)
	(via
		(at 48.9712 -134.3914)
		(size 0.6604)
		(drill 0.3302)
		(layers "F.Cu" "B.Cu")
		(net "BMC_SMB14_DAT")
	)
	(segment
		(start 46.157134 -137.05713)
		(end 46.500034 -137.40003)
		(width 0.127)
		(layer "F.Cu")
		(net "BMC_SMB14_CLK")
	)
	(segment
		(start 47.792132 -133.985)
		(end 47.0662 -134.710932)
		(width 0.127)
		(layer "F.Cu")
		(net "BMC_SMB14_CLK")
	)
	(segment
		(start 48.0949 -132.2578)
		(end 48.4124 -131.9403)
		(width 0.127)
		(layer "F.Cu")
		(net "BMC_SMB14_CLK")
	)
	(segment
		(start 47.0662 -135.083296)
		(end 46.157134 -135.992362)
		(width 0.127)
		(layer "F.Cu")
		(net "BMC_SMB14_CLK")
	)
	(segment
		(start 47.792132 -133.985)
		(end 48.0949 -133.682232)
		(width 0.127)
		(layer "F.Cu")
		(net "BMC_SMB14_CLK")
	)
	(segment
		(start 46.157134 -135.992362)
		(end 46.157134 -137.05713)
		(width 0.127)
		(layer "F.Cu")
		(net "BMC_SMB14_CLK")
	)
	(segment
		(start 47.0662 -134.710932)
		(end 47.0662 -135.083296)
		(width 0.127)
		(layer "F.Cu")
		(net "BMC_SMB14_CLK")
	)
	(segment
		(start 48.0949 -133.682232)
		(end 48.0949 -132.2578)
		(width 0.127)
		(layer "F.Cu")
		(net "BMC_SMB14_CLK")
	)
	(via
		(at 47.792132 -133.985)
		(size 0.6604)
		(drill 0.3302)
		(layers "F.Cu" "B.Cu")
		(net "BMC_SMB14_CLK")
	)
	(segment
		(start 55.299864 -145.400014)
		(end 54.899814 -145.800064)
		(width 0.127)
		(layer "F.Cu")
		(net "BMC_SMB13_DAT")
	)
	(via
		(at 54.899814 -145.800064)
		(size 0.4572)
		(drill 0.2032)
		(layers "F.Cu" "B.Cu")
		(net "BMC_SMB13_DAT")
	)
	(via
		(at 60.1472 -145.871438)
		(size 0.6096)
		(drill 0.3048)
		(layers "F.Cu" "B.Cu")
		(net "BMC_SMB13_DAT")
	)
	(segment
		(start 56.11114 -145.391124)
		(end 56.45277 -145.732754)
		(width 0.127)
		(layer "B.Cu")
		(net "BMC_SMB13_DAT")
	)
	(segment
		(start 56.45277 -145.732754)
		(end 59.141614 -145.732754)
		(width 0.127)
		(layer "B.Cu")
		(net "BMC_SMB13_DAT")
	)
	(segment
		(start 59.141614 -145.732754)
		(end 59.280298 -145.871438)
		(width 0.127)
		(layer "B.Cu")
		(net "BMC_SMB13_DAT")
	)
	(segment
		(start 60.1472 -145.871438)
		(end 60.55741 -145.871438)
		(width 0.127)
		(layer "B.Cu")
		(net "BMC_SMB13_DAT")
	)
	(segment
		(start 55.308754 -145.391124)
		(end 56.11114 -145.391124)
		(width 0.127)
		(layer "B.Cu")
		(net "BMC_SMB13_DAT")
	)
	(segment
		(start 60.55741 -145.871438)
		(end 61.38672 -145.042128)
		(width 0.127)
		(layer "B.Cu")
		(net "BMC_SMB13_DAT")
	)
	(segment
		(start 59.280298 -145.871438)
		(end 60.1472 -145.871438)
		(width 0.127)
		(layer "B.Cu")
		(net "BMC_SMB13_DAT")
	)
	(segment
		(start 54.899814 -145.800064)
		(end 55.308754 -145.391124)
		(width 0.127)
		(layer "B.Cu")
		(net "BMC_SMB13_DAT")
	)
	(segment
		(start 54.500018 -145.400014)
		(end 54.499764 -145.400014)
		(width 0.127)
		(layer "F.Cu")
		(net "BMC_SMB13_CLK")
	)
	(segment
		(start 54.499764 -145.400014)
		(end 54.099714 -145.800064)
		(width 0.127)
		(layer "F.Cu")
		(net "BMC_SMB13_CLK")
	)
	(via
		(at 60.325 -146.9517)
		(size 0.6096)
		(drill 0.3048)
		(layers "F.Cu" "B.Cu")
		(net "BMC_SMB13_CLK")
	)
	(via
		(at 54.099714 -145.800064)
		(size 0.4572)
		(drill 0.2032)
		(layers "F.Cu" "B.Cu")
		(net "BMC_SMB13_CLK")
	)
	(segment
		(start 55.552848 -145.704052)
		(end 55.9943 -145.704052)
		(width 0.127)
		(layer "B.Cu")
		(net "BMC_SMB13_CLK")
	)
	(segment
		(start 55.063136 -146.193764)
		(end 55.552848 -145.704052)
		(width 0.127)
		(layer "B.Cu")
		(net "BMC_SMB13_CLK")
	)
	(segment
		(start 60.325 -146.9517)
		(end 61.6204 -146.9517)
		(width 0.127)
		(layer "B.Cu")
		(net "BMC_SMB13_CLK")
	)
	(segment
		(start 59.762136 -146.9517)
		(end 60.325 -146.9517)
		(width 0.127)
		(layer "B.Cu")
		(net "BMC_SMB13_CLK")
	)
	(segment
		(start 58.77179 -145.961354)
		(end 59.762136 -146.9517)
		(width 0.127)
		(layer "B.Cu")
		(net "BMC_SMB13_CLK")
	)
	(segment
		(start 54.493414 -146.193764)
		(end 55.063136 -146.193764)
		(width 0.127)
		(layer "B.Cu")
		(net "BMC_SMB13_CLK")
	)
	(segment
		(start 56.251602 -145.961354)
		(end 58.77179 -145.961354)
		(width 0.127)
		(layer "B.Cu")
		(net "BMC_SMB13_CLK")
	)
	(segment
		(start 55.9943 -145.704052)
		(end 56.251602 -145.961354)
		(width 0.127)
		(layer "B.Cu")
		(net "BMC_SMB13_CLK")
	)
	(segment
		(start 54.099714 -145.800064)
		(end 54.493414 -146.193764)
		(width 0.127)
		(layer "B.Cu")
		(net "BMC_SMB13_CLK")
	)
	(segment
		(start 53.299868 -144.200118)
		(end 53.299614 -144.200118)
		(width 0.127)
		(layer "F.Cu")
		(net "BMC_SMB12_DAT")
	)
	(segment
		(start 53.299614 -144.200118)
		(end 52.899818 -144.599914)
		(width 0.127)
		(layer "F.Cu")
		(net "BMC_SMB12_DAT")
	)
	(via
		(at 67.3354 -142.8242)
		(size 0.508)
		(drill 0.254)
		(layers "F.Cu" "B.Cu")
		(net "BMC_SMB12_DAT")
	)
	(via
		(at 67.368674 -144.940274)
		(size 0.6096)
		(drill 0.3048)
		(layers "F.Cu" "B.Cu")
		(net "BMC_SMB12_DAT")
	)
	(via
		(at 53.299868 -144.200118)
		(size 0.4572)
		(drill 0.2032)
		(layers "F.Cu" "B.Cu")
		(net "BMC_SMB12_DAT")
	)
	(segment
		(start 68.530724 -145.136108)
		(end 67.564508 -145.136108)
		(width 0.127)
		(layer "B.Cu")
		(net "BMC_SMB12_DAT")
	)
	(segment
		(start 67.368674 -144.940274)
		(end 67.368674 -142.857474)
		(width 0.127)
		(layer "B.Cu")
		(net "BMC_SMB12_DAT")
	)
	(segment
		(start 67.564508 -145.136108)
		(end 67.368674 -144.940274)
		(width 0.127)
		(layer "B.Cu")
		(net "BMC_SMB12_DAT")
	)
	(segment
		(start 67.368674 -142.857474)
		(end 67.3354 -142.8242)
		(width 0.127)
		(layer "B.Cu")
		(net "BMC_SMB12_DAT")
	)
	(segment
		(start 59.024266 -142.543276)
		(end 57.676288 -142.543276)
		(width 0.127)
		(layer "In5.Cu")
		(net "BMC_SMB12_DAT")
	)
	(segment
		(start 61.278008 -142.691358)
		(end 59.901328 -142.691358)
		(width 0.127)
		(layer "In5.Cu")
		(net "BMC_SMB12_DAT")
	)
	(segment
		(start 57.3913 -143.389604)
		(end 56.186832 -144.594072)
		(width 0.127)
		(layer "In5.Cu")
		(net "BMC_SMB12_DAT")
	)
	(segment
		(start 59.155584 -142.411958)
		(end 59.024266 -142.543276)
		(width 0.127)
		(layer "In5.Cu")
		(net "BMC_SMB12_DAT")
	)
	(segment
		(start 59.621928 -142.411958)
		(end 59.155584 -142.411958)
		(width 0.127)
		(layer "In5.Cu")
		(net "BMC_SMB12_DAT")
	)
	(segment
		(start 56.186832 -144.594072)
		(end 53.693822 -144.594072)
		(width 0.127)
		(layer "In5.Cu")
		(net "BMC_SMB12_DAT")
	)
	(segment
		(start 66.3448 -141.8336)
		(end 62.135766 -141.8336)
		(width 0.127)
		(layer "In5.Cu")
		(net "BMC_SMB12_DAT")
	)
	(segment
		(start 62.135766 -141.8336)
		(end 61.278008 -142.691358)
		(width 0.127)
		(layer "In5.Cu")
		(net "BMC_SMB12_DAT")
	)
	(segment
		(start 57.3913 -142.828264)
		(end 57.3913 -143.389604)
		(width 0.127)
		(layer "In5.Cu")
		(net "BMC_SMB12_DAT")
	)
	(segment
		(start 67.3354 -142.8242)
		(end 66.3448 -141.8336)
		(width 0.127)
		(layer "In5.Cu")
		(net "BMC_SMB12_DAT")
	)
	(segment
		(start 59.901328 -142.691358)
		(end 59.621928 -142.411958)
		(width 0.127)
		(layer "In5.Cu")
		(net "BMC_SMB12_DAT")
	)
	(segment
		(start 57.676288 -142.543276)
		(end 57.3913 -142.828264)
		(width 0.127)
		(layer "In5.Cu")
		(net "BMC_SMB12_DAT")
	)
	(segment
		(start 53.693822 -144.594072)
		(end 53.299868 -144.200118)
		(width 0.127)
		(layer "In5.Cu")
		(net "BMC_SMB12_DAT")
	)
	(segment
		(start 54.099714 -146.599656)
		(end 53.699918 -146.19986)
		(width 0.127)
		(layer "F.Cu")
		(net "BMC_SMB12_CLK")
	)
	(segment
		(start 54.099714 -146.59991)
		(end 54.099714 -146.599656)
		(width 0.127)
		(layer "F.Cu")
		(net "BMC_SMB12_CLK")
	)
	(via
		(at 54.099714 -146.59991)
		(size 0.4572)
		(drill 0.2032)
		(layers "F.Cu" "B.Cu")
		(net "BMC_SMB12_CLK")
	)
	(via
		(at 66.170302 -143.29029)
		(size 0.6604)
		(drill 0.254)
		(layers "F.Cu" "B.Cu")
		(net "BMC_SMB12_CLK")
	)
	(segment
		(start 67.12839 -142.332202)
		(end 66.170302 -143.29029)
		(width 0.127)
		(layer "B.Cu")
		(net "BMC_SMB12_CLK")
	)
	(segment
		(start 68.506086 -142.332202)
		(end 67.12839 -142.332202)
		(width 0.127)
		(layer "B.Cu")
		(net "BMC_SMB12_CLK")
	)
	(segment
		(start 54.12867 -146.59991)
		(end 54.099714 -146.59991)
		(width 0.127)
		(layer "In5.Cu")
		(net "BMC_SMB12_CLK")
	)
	(segment
		(start 58.995564 -144.3482)
		(end 56.350154 -146.99361)
		(width 0.127)
		(layer "In5.Cu")
		(net "BMC_SMB12_CLK")
	)
	(segment
		(start 54.52237 -146.99361)
		(end 54.12867 -146.59991)
		(width 0.127)
		(layer "In5.Cu")
		(net "BMC_SMB12_CLK")
	)
	(segment
		(start 65.112392 -144.3482)
		(end 58.995564 -144.3482)
		(width 0.127)
		(layer "In5.Cu")
		(net "BMC_SMB12_CLK")
	)
	(segment
		(start 56.350154 -146.99361)
		(end 54.52237 -146.99361)
		(width 0.127)
		(layer "In5.Cu")
		(net "BMC_SMB12_CLK")
	)
	(segment
		(start 66.170302 -143.29029)
		(end 65.112392 -144.3482)
		(width 0.127)
		(layer "In5.Cu")
		(net "BMC_SMB12_CLK")
	)
	(segment
		(start 60.102496 -142.341092)
		(end 59.812936 -142.630652)
		(width 0.127)
		(layer "F.Cu")
		(net "BMC_SMB11_DAT")
	)
	(segment
		(start 53.699918 -146.99996)
		(end 54.099968 -147.40001)
		(width 0.127)
		(layer "F.Cu")
		(net "BMC_SMB11_DAT")
	)
	(segment
		(start 59.812936 -142.630652)
		(end 59.675522 -142.768066)
		(width 0.127)
		(layer "F.Cu")
		(net "BMC_SMB11_DAT")
	)
	(segment
		(start 60.844684 -142.341092)
		(end 60.102496 -142.341092)
		(width 0.127)
		(layer "F.Cu")
		(net "BMC_SMB11_DAT")
	)
	(segment
		(start 59.675522 -142.768066)
		(end 59.675522 -143.560546)
		(width 0.127)
		(layer "F.Cu")
		(net "BMC_SMB11_DAT")
	)
	(via
		(at 54.099968 -147.40001)
		(size 0.4572)
		(drill 0.2032)
		(layers "F.Cu" "B.Cu")
		(net "BMC_SMB11_DAT")
	)
	(via
		(at 59.812936 -142.630652)
		(size 0.6604)
		(drill 0.3302)
		(layers "F.Cu" "B.Cu")
		(net "BMC_SMB11_DAT")
	)
	(via
		(at 59.675522 -143.560546)
		(size 0.508)
		(drill 0.254)
		(layers "F.Cu" "B.Cu")
		(net "BMC_SMB11_DAT")
	)
	(segment
		(start 53.706014 -146.436588)
		(end 53.706014 -147.006056)
		(width 0.127)
		(layer "In5.Cu")
		(net "BMC_SMB11_DAT")
	)
	(segment
		(start 56.206644 -146.20621)
		(end 53.936392 -146.20621)
		(width 0.127)
		(layer "In5.Cu")
		(net "BMC_SMB11_DAT")
	)
	(segment
		(start 59.294268 -143.9418)
		(end 58.471054 -143.9418)
		(width 0.127)
		(layer "In5.Cu")
		(net "BMC_SMB11_DAT")
	)
	(segment
		(start 53.706014 -147.006056)
		(end 54.099968 -147.40001)
		(width 0.127)
		(layer "In5.Cu")
		(net "BMC_SMB11_DAT")
	)
	(segment
		(start 59.675522 -143.560546)
		(end 59.294268 -143.9418)
		(width 0.127)
		(layer "In5.Cu")
		(net "BMC_SMB11_DAT")
	)
	(segment
		(start 53.936392 -146.20621)
		(end 53.706014 -146.436588)
		(width 0.127)
		(layer "In5.Cu")
		(net "BMC_SMB11_DAT")
	)
	(segment
		(start 58.471054 -143.9418)
		(end 56.206644 -146.20621)
		(width 0.127)
		(layer "In5.Cu")
		(net "BMC_SMB11_DAT")
	)
	(segment
		(start 59.149742 -143.784574)
		(end 58.632852 -143.784574)
		(width 0.127)
		(layer "F.Cu")
		(net "BMC_SMB11_CLK")
	)
	(segment
		(start 59.344814 -143.979646)
		(end 59.149742 -143.784574)
		(width 0.127)
		(layer "F.Cu")
		(net "BMC_SMB11_CLK")
	)
	(segment
		(start 55.299864 -144.599914)
		(end 55.642764 -144.942814)
		(width 0.127)
		(layer "F.Cu")
		(net "BMC_SMB11_CLK")
	)
	(segment
		(start 55.642764 -144.942814)
		(end 56.242204 -144.942814)
		(width 0.127)
		(layer "F.Cu")
		(net "BMC_SMB11_CLK")
	)
	(segment
		(start 57.439306 -144.342612)
		(end 57.997344 -143.784574)
		(width 0.127)
		(layer "F.Cu")
		(net "BMC_SMB11_CLK")
	)
	(segment
		(start 56.242204 -144.942814)
		(end 56.842406 -144.342612)
		(width 0.127)
		(layer "F.Cu")
		(net "BMC_SMB11_CLK")
	)
	(segment
		(start 60.844684 -143.382492)
		(end 60.554108 -143.382492)
		(width 0.127)
		(layer "F.Cu")
		(net "BMC_SMB11_CLK")
	)
	(segment
		(start 57.997344 -143.784574)
		(end 58.632852 -143.784574)
		(width 0.127)
		(layer "F.Cu")
		(net "BMC_SMB11_CLK")
	)
	(segment
		(start 60.554108 -143.382492)
		(end 59.956954 -143.979646)
		(width 0.127)
		(layer "F.Cu")
		(net "BMC_SMB11_CLK")
	)
	(segment
		(start 56.842406 -144.342612)
		(end 57.439306 -144.342612)
		(width 0.127)
		(layer "F.Cu")
		(net "BMC_SMB11_CLK")
	)
	(segment
		(start 59.956954 -143.979646)
		(end 59.344814 -143.979646)
		(width 0.127)
		(layer "F.Cu")
		(net "BMC_SMB11_CLK")
	)
	(via
		(at 58.632852 -143.784574)
		(size 0.6604)
		(drill 0.3302)
		(layers "F.Cu" "B.Cu")
		(net "BMC_SMB11_CLK")
	)
	(segment
		(start 56.099964 -144.59966)
		(end 55.700422 -144.200118)
		(width 0.127)
		(layer "F.Cu")
		(net "BMC_SMB10_DAT")
	)
	(segment
		(start 56.099964 -144.599914)
		(end 56.099964 -144.59966)
		(width 0.127)
		(layer "F.Cu")
		(net "BMC_SMB10_DAT")
	)
	(via
		(at 60.0456 -144.4752)
		(size 0.6096)
		(drill 0.3048)
		(layers "F.Cu" "B.Cu")
		(net "BMC_SMB10_DAT")
	)
	(via
		(at 55.700422 -144.200118)
		(size 0.4572)
		(drill 0.2032)
		(layers "F.Cu" "B.Cu")
		(net "BMC_SMB10_DAT")
	)
	(segment
		(start 59.4741 -144.4752)
		(end 59.3852 -144.5641)
		(width 0.127)
		(layer "B.Cu")
		(net "BMC_SMB10_DAT")
	)
	(segment
		(start 59.3852 -144.5641)
		(end 56.064404 -144.5641)
		(width 0.127)
		(layer "B.Cu")
		(net "BMC_SMB10_DAT")
	)
	(segment
		(start 60.0456 -144.4752)
		(end 60.785248 -144.4752)
		(width 0.127)
		(layer "B.Cu")
		(net "BMC_SMB10_DAT")
	)
	(segment
		(start 60.0456 -144.4752)
		(end 59.4741 -144.4752)
		(width 0.127)
		(layer "B.Cu")
		(net "BMC_SMB10_DAT")
	)
	(segment
		(start 56.064404 -144.5641)
		(end 55.700422 -144.200118)
		(width 0.127)
		(layer "B.Cu")
		(net "BMC_SMB10_DAT")
	)
	(segment
		(start 60.785248 -144.4752)
		(end 61.31052 -143.949928)
		(width 0.127)
		(layer "B.Cu")
		(net "BMC_SMB10_DAT")
	)
	(segment
		(start 54.500272 -144.599914)
		(end 54.899814 -144.200372)
		(width 0.127)
		(layer "F.Cu")
		(net "BMC_SMB10_CLK")
	)
	(segment
		(start 54.500018 -144.599914)
		(end 54.500272 -144.599914)
		(width 0.127)
		(layer "F.Cu")
		(net "BMC_SMB10_CLK")
	)
	(via
		(at 59.690508 -142.77848)
		(size 0.6096)
		(drill 0.3048)
		(layers "F.Cu" "B.Cu")
		(net "BMC_SMB10_CLK")
	)
	(via
		(at 54.899814 -144.200372)
		(size 0.4572)
		(drill 0.2032)
		(layers "F.Cu" "B.Cu")
		(net "BMC_SMB10_CLK")
	)
	(segment
		(start 54.899814 -144.120362)
		(end 54.899814 -144.200372)
		(width 0.127)
		(layer "B.Cu")
		(net "BMC_SMB10_CLK")
	)
	(segment
		(start 55.446676 -143.5735)
		(end 54.899814 -144.120362)
		(width 0.127)
		(layer "B.Cu")
		(net "BMC_SMB10_CLK")
	)
	(segment
		(start 60.311792 -142.77848)
		(end 60.413646 -142.880334)
		(width 0.127)
		(layer "B.Cu")
		(net "BMC_SMB10_CLK")
	)
	(segment
		(start 58.962036 -142.5829)
		(end 58.614564 -142.5829)
		(width 0.127)
		(layer "B.Cu")
		(net "BMC_SMB10_CLK")
	)
	(segment
		(start 56.362854 -143.5735)
		(end 55.446676 -143.5735)
		(width 0.127)
		(layer "B.Cu")
		(net "BMC_SMB10_CLK")
	)
	(segment
		(start 59.690508 -142.77848)
		(end 60.311792 -142.77848)
		(width 0.127)
		(layer "B.Cu")
		(net "BMC_SMB10_CLK")
	)
	(segment
		(start 56.515254 -143.4211)
		(end 56.362854 -143.5735)
		(width 0.127)
		(layer "B.Cu")
		(net "BMC_SMB10_CLK")
	)
	(segment
		(start 60.413646 -142.880334)
		(end 60.82538 -142.880334)
		(width 0.127)
		(layer "B.Cu")
		(net "BMC_SMB10_CLK")
	)
	(segment
		(start 57.984136 -143.4211)
		(end 56.515254 -143.4211)
		(width 0.127)
		(layer "B.Cu")
		(net "BMC_SMB10_CLK")
	)
	(segment
		(start 58.2295 -143.175736)
		(end 57.984136 -143.4211)
		(width 0.127)
		(layer "B.Cu")
		(net "BMC_SMB10_CLK")
	)
	(segment
		(start 58.614564 -142.5829)
		(end 58.2295 -142.967964)
		(width 0.127)
		(layer "B.Cu")
		(net "BMC_SMB10_CLK")
	)
	(segment
		(start 59.157616 -142.77848)
		(end 58.962036 -142.5829)
		(width 0.127)
		(layer "B.Cu")
		(net "BMC_SMB10_CLK")
	)
	(segment
		(start 58.2295 -142.967964)
		(end 58.2295 -143.175736)
		(width 0.127)
		(layer "B.Cu")
		(net "BMC_SMB10_CLK")
	)
	(segment
		(start 59.690508 -142.77848)
		(end 59.157616 -142.77848)
		(width 0.127)
		(layer "B.Cu")
		(net "BMC_SMB10_CLK")
	)
	(segment
		(start 46.900084 -138.600434)
		(end 46.900338 -138.600434)
		(width 0.127)
		(layer "F.Cu")
		(net "BMC_SMB1_DAT")
	)
	(segment
		(start 46.900338 -138.600434)
		(end 47.29988 -138.999976)
		(width 0.127)
		(layer "F.Cu")
		(net "BMC_SMB1_DAT")
	)
	(via
		(at 46.900084 -138.600434)
		(size 0.4572)
		(drill 0.2032)
		(layers "F.Cu" "B.Cu")
		(net "BMC_SMB1_DAT")
	)
	(via
		(at 45.2628 -137.2616)
		(size 0.6096)
		(drill 0.3048)
		(layers "F.Cu" "B.Cu")
		(net "BMC_SMB1_DAT")
	)
	(segment
		(start 45.852334 -138.994134)
		(end 46.506384 -138.994134)
		(width 0.127)
		(layer "B.Cu")
		(net "BMC_SMB1_DAT")
	)
	(segment
		(start 45.2628 -137.2616)
		(end 45.2628 -138.006074)
		(width 0.127)
		(layer "B.Cu")
		(net "BMC_SMB1_DAT")
	)
	(segment
		(start 45.693584 -138.436858)
		(end 45.693584 -138.835384)
		(width 0.127)
		(layer "B.Cu")
		(net "BMC_SMB1_DAT")
	)
	(segment
		(start 45.2628 -137.2616)
		(end 45.2628 -135.3947)
		(width 0.127)
		(layer "B.Cu")
		(net "BMC_SMB1_DAT")
	)
	(segment
		(start 45.2628 -138.006074)
		(end 45.693584 -138.436858)
		(width 0.127)
		(layer "B.Cu")
		(net "BMC_SMB1_DAT")
	)
	(segment
		(start 45.2628 -135.3947)
		(end 45.5676 -135.0899)
		(width 0.127)
		(layer "B.Cu")
		(net "BMC_SMB1_DAT")
	)
	(segment
		(start 45.693584 -138.835384)
		(end 45.852334 -138.994134)
		(width 0.127)
		(layer "B.Cu")
		(net "BMC_SMB1_DAT")
	)
	(segment
		(start 46.506384 -138.994134)
		(end 46.900084 -138.600434)
		(width 0.127)
		(layer "B.Cu")
		(net "BMC_SMB1_DAT")
	)
	(segment
		(start 46.900084 -139.400534)
		(end 46.900338 -139.400534)
		(width 0.127)
		(layer "F.Cu")
		(net "BMC_SMB1_CLK")
	)
	(segment
		(start 46.900338 -139.400534)
		(end 47.29988 -139.800076)
		(width 0.127)
		(layer "F.Cu")
		(net "BMC_SMB1_CLK")
	)
	(via
		(at 47.7012 -139.008612)
		(size 0.6096)
		(drill 0.3048)
		(layers "F.Cu" "B.Cu")
		(net "BMC_SMB1_CLK")
	)
	(via
		(at 46.900084 -139.400534)
		(size 0.4572)
		(drill 0.2032)
		(layers "F.Cu" "B.Cu")
		(net "BMC_SMB1_CLK")
	)
	(segment
		(start 46.71695 -138.193526)
		(end 46.493684 -137.97026)
		(width 0.127)
		(layer "B.Cu")
		(net "BMC_SMB1_CLK")
	)
	(segment
		(start 46.493684 -137.475214)
		(end 45.89526 -136.87679)
		(width 0.127)
		(layer "B.Cu")
		(net "BMC_SMB1_CLK")
	)
	(segment
		(start 47.309278 -139.400534)
		(end 46.900084 -139.400534)
		(width 0.127)
		(layer "B.Cu")
		(net "BMC_SMB1_CLK")
	)
	(segment
		(start 45.89526 -135.965946)
		(end 46.65218 -135.209026)
		(width 0.127)
		(layer "B.Cu")
		(net "BMC_SMB1_CLK")
	)
	(segment
		(start 46.65218 -135.209026)
		(end 46.65218 -135.081264)
		(width 0.127)
		(layer "B.Cu")
		(net "BMC_SMB1_CLK")
	)
	(segment
		(start 45.89526 -136.87679)
		(end 45.89526 -135.965946)
		(width 0.127)
		(layer "B.Cu")
		(net "BMC_SMB1_CLK")
	)
	(segment
		(start 46.493684 -137.97026)
		(end 46.493684 -137.475214)
		(width 0.127)
		(layer "B.Cu")
		(net "BMC_SMB1_CLK")
	)
	(segment
		(start 47.134526 -138.193526)
		(end 46.71695 -138.193526)
		(width 0.127)
		(layer "B.Cu")
		(net "BMC_SMB1_CLK")
	)
	(segment
		(start 47.7012 -138.7602)
		(end 47.134526 -138.193526)
		(width 0.127)
		(layer "B.Cu")
		(net "BMC_SMB1_CLK")
	)
	(segment
		(start 47.7012 -139.008612)
		(end 47.7012 -138.7602)
		(width 0.127)
		(layer "B.Cu")
		(net "BMC_SMB1_CLK")
	)
	(segment
		(start 47.7012 -139.008612)
		(end 47.309278 -139.400534)
		(width 0.127)
		(layer "B.Cu")
		(net "BMC_SMB1_CLK")
	)
	(segment
		(start 220.383862 -46.131988)
		(end 220.383862 -43.882056)
		(width 0.254)
		(layer "F.Cu")
		(net "AGND_P5V")
	)
	(via
		(at 220.383862 -43.882056)
		(size 0.508)
		(drill 0.254)
		(layers "F.Cu" "B.Cu")
		(net "AGND_P5V")
	)
	(via
		(at 214.672672 -48.962056)
		(size 0.508)
		(drill 0.254)
		(layers "F.Cu" "B.Cu")
		(net "AGND_P5V")
	)
	(via
		(at 216.156032 -47.478696)
		(size 0.6096)
		(drill 0.3048)
		(layers "F.Cu" "B.Cu")
		(net "AGND_P5V")
	)
	(segment
		(start 217.508328 -46.1264)
		(end 216.156032 -47.478696)
		(width 0.254)
		(layer "B.Cu")
		(net "AGND_P5V")
	)
	(segment
		(start 214.672672 -48.962056)
		(end 216.156032 -47.478696)
		(width 0.254)
		(layer "B.Cu")
		(net "AGND_P5V")
	)
	(segment
		(start 220.383862 -45.460666)
		(end 219.718128 -46.1264)
		(width 0.254)
		(layer "B.Cu")
		(net "AGND_P5V")
	)
	(segment
		(start 219.718128 -46.1264)
		(end 217.508328 -46.1264)
		(width 0.254)
		(layer "B.Cu")
		(net "AGND_P5V")
	)
	(segment
		(start 220.383862 -43.882056)
		(end 220.383862 -45.460666)
		(width 0.254)
		(layer "B.Cu")
		(net "AGND_P5V")
	)
	(segment
		(start 40.284146 -180.64861)
		(end 41.1734 -180.64861)
		(width 0.508)
		(layer "F.Cu")
		(net "AGND_P3V3_STBY")
	)
	(via
		(at 34.092642 -175.520858)
		(size 0.7112)
		(drill 0.4064)
		(layers "F.Cu" "B.Cu")
		(net "AGND_P3V3_STBY")
	)
	(via
		(at 32.7152 -176.3776)
		(size 0.6604)
		(drill 0.3302)
		(layers "F.Cu" "B.Cu")
		(net "AGND_P3V3_STBY")
	)
	(via
		(at 41.1734 -180.64861)
		(size 0.508)
		(drill 0.254)
		(layers "F.Cu" "B.Cu")
		(net "AGND_P3V3_STBY")
	)
	(segment
		(start 39.310056 -179.466748)
		(end 39.310056 -178.015392)
		(width 0.254)
		(layer "In2.Cu")
		(net "AGND_P3V3_STBY")
	)
	(segment
		(start 38.609016 -177.314352)
		(end 35.886136 -177.314352)
		(width 0.254)
		(layer "In2.Cu")
		(net "AGND_P3V3_STBY")
	)
	(segment
		(start 35.886136 -177.314352)
		(end 34.092642 -175.520858)
		(width 0.254)
		(layer "In2.Cu")
		(net "AGND_P3V3_STBY")
	)
	(segment
		(start 39.310056 -178.015392)
		(end 38.609016 -177.314352)
		(width 0.254)
		(layer "In2.Cu")
		(net "AGND_P3V3_STBY")
	)
	(segment
		(start 40.491918 -180.64861)
		(end 39.310056 -179.466748)
		(width 0.254)
		(layer "In2.Cu")
		(net "AGND_P3V3_STBY")
	)
	(segment
		(start 41.1734 -180.64861)
		(end 40.491918 -180.64861)
		(width 0.254)
		(layer "In2.Cu")
		(net "AGND_P3V3_STBY")
	)
	(segment
		(start 67.9831 -151.6507)
		(end 67.9704 -151.638)
		(width 0.127)
		(layer "F.Cu")
		(net "50M_CLK_OUT_R")
	)
	(segment
		(start 67.9831 -153.8732)
		(end 67.9831 -151.6507)
		(width 0.127)
		(layer "F.Cu")
		(net "50M_CLK_OUT_R")
	)
	(segment
		(start 68.8721 -153.8732)
		(end 68.8721 -155.29306)
		(width 0.127)
		(layer "F.Cu")
		(net "50M_CLK_OUT")
	)
	(segment
		(start 68.8721 -155.29306)
		(end 68.712334 -155.452826)
		(width 0.127)
		(layer "F.Cu")
		(net "50M_CLK_OUT")
	)
	(segment
		(start 74.1426 -151.638)
		(end 74.4474 -151.9428)
		(width 0.127)
		(layer "F.Cu")
		(net "50M_CLK_OE")
	)
	(segment
		(start 73.0504 -151.638)
		(end 74.1426 -151.638)
		(width 0.127)
		(layer "F.Cu")
		(net "50M_CLK_OE")
	)
	(segment
		(start 76.14031 -150.579074)
		(end 76.14031 -151.535892)
		(width 0.127)
		(layer "F.Cu")
		(net "50M_CLK_OE")
	)
	(segment
		(start 74.4474 -151.9428)
		(end 75.733402 -151.9428)
		(width 0.127)
		(layer "F.Cu")
		(net "50M_CLK_OE")
	)
	(segment
		(start 75.733402 -151.9428)
		(end 75.847702 -151.8285)
		(width 0.127)
		(layer "F.Cu")
		(net "50M_CLK_OE")
	)
	(segment
		(start 76.14031 -151.535892)
		(end 75.847702 -151.8285)
		(width 0.127)
		(layer "F.Cu")
		(net "50M_CLK_OE")
	)
	(via
		(at 75.847702 -151.8285)
		(size 0.6604)
		(drill 0.3302)
		(layers "F.Cu" "B.Cu")
		(net "50M_CLK_OE")
	)
	(segment
		(start 64.176402 -154.419046)
		(end 60.591446 -154.419046)
		(width 0.14605)
		(layer "F.Cu")
		(net "USB_P3_DP")
	)
	(segment
		(start 85.761068 -154.090116)
		(end 87.417402 -154.090116)
		(width 0.14605)
		(layer "F.Cu")
		(net "USB_P3_DP")
	)
	(segment
		(start 85.509354 -153.36774)
		(end 85.509354 -153.838402)
		(width 0.14605)
		(layer "F.Cu")
		(net "USB_P3_DP")
	)
	(segment
		(start 58.126376 -151.553926)
		(end 56.40705 -149.8346)
		(width 0.14605)
		(layer "F.Cu")
		(net "USB_P3_DP")
	)
	(segment
		(start 56.40705 -149.8346)
		(end 55.734458 -149.8346)
		(width 0.14605)
		(layer "F.Cu")
		(net "USB_P3_DP")
	)
	(segment
		(start 59.7408 -152.59304)
		(end 58.701686 -151.553926)
		(width 0.14605)
		(layer "F.Cu")
		(net "USB_P3_DP")
	)
	(segment
		(start 85.509354 -153.838402)
		(end 85.761068 -154.090116)
		(width 0.14605)
		(layer "F.Cu")
		(net "USB_P3_DP")
	)
	(segment
		(start 59.7408 -153.5684)
		(end 59.7408 -152.59304)
		(width 0.14605)
		(layer "F.Cu")
		(net "USB_P3_DP")
	)
	(segment
		(start 65.633092 -154.808936)
		(end 65.354454 -154.530298)
		(width 0.14605)
		(layer "F.Cu")
		(net "USB_P3_DP")
	)
	(segment
		(start 88.960452 -154.69616)
		(end 89.051892 -154.605482)
		(width 0.14605)
		(layer "F.Cu")
		(net "USB_P3_DP")
	)
	(segment
		(start 64.287654 -154.530298)
		(end 64.176402 -154.419046)
		(width 0.14605)
		(layer "F.Cu")
		(net "USB_P3_DP")
	)
	(segment
		(start 55.734458 -149.8346)
		(end 55.299864 -149.400006)
		(width 0.14605)
		(layer "F.Cu")
		(net "USB_P3_DP")
	)
	(segment
		(start 60.591446 -154.419046)
		(end 59.7408 -153.5684)
		(width 0.14605)
		(layer "F.Cu")
		(net "USB_P3_DP")
	)
	(segment
		(start 58.701686 -151.553926)
		(end 58.126376 -151.553926)
		(width 0.14605)
		(layer "F.Cu")
		(net "USB_P3_DP")
	)
	(segment
		(start 65.354454 -154.530298)
		(end 64.287654 -154.530298)
		(width 0.14605)
		(layer "F.Cu")
		(net "USB_P3_DP")
	)
	(segment
		(start 87.417402 -154.090116)
		(end 88.023446 -154.69616)
		(width 0.14605)
		(layer "F.Cu")
		(net "USB_P3_DP")
	)
	(segment
		(start 88.023446 -154.69616)
		(end 88.960452 -154.69616)
		(width 0.14605)
		(layer "F.Cu")
		(net "USB_P3_DP")
	)
	(segment
		(start 89.051892 -154.605482)
		(end 89.881456 -154.605482)
		(width 0.14605)
		(layer "F.Cu")
		(net "USB_P3_DP")
	)
	(segment
		(start 85.804502 -153.072592)
		(end 85.509354 -153.36774)
		(width 0.14605)
		(layer "F.Cu")
		(net "USB_P3_DP")
	)
	(via
		(at 85.804502 -153.072592)
		(size 0.508)
		(drill 0.254)
		(layers "F.Cu" "B.Cu")
		(net "USB_P3_DP")
	)
	(via
		(at 65.633092 -154.808936)
		(size 0.508)
		(drill 0.254)
		(layers "F.Cu" "B.Cu")
		(net "USB_P3_DP")
	)
	(segment
		(start 76.201778 -156.212032)
		(end 82.686398 -156.212032)
		(width 0.1397)
		(layer "In5.Cu")
		(net "USB_P3_DP")
	)
	(segment
		(start 85.514434 -153.904442)
		(end 85.514434 -153.36266)
		(width 0.1397)
		(layer "In5.Cu")
		(net "USB_P3_DP")
	)
	(segment
		(start 82.686398 -156.212032)
		(end 84.561934 -154.336496)
		(width 0.1397)
		(layer "In5.Cu")
		(net "USB_P3_DP")
	)
	(segment
		(start 85.514434 -153.36266)
		(end 85.804502 -153.072592)
		(width 0.1397)
		(layer "In5.Cu")
		(net "USB_P3_DP")
	)
	(segment
		(start 84.561934 -154.336496)
		(end 85.08238 -154.336496)
		(width 0.1397)
		(layer "In5.Cu")
		(net "USB_P3_DP")
	)
	(segment
		(start 65.633092 -154.808936)
		(end 65.933828 -154.5082)
		(width 0.1397)
		(layer "In5.Cu")
		(net "USB_P3_DP")
	)
	(segment
		(start 73.818496 -153.82875)
		(end 76.201778 -156.212032)
		(width 0.1397)
		(layer "In5.Cu")
		(net "USB_P3_DP")
	)
	(segment
		(start 65.933828 -154.5082)
		(end 66.225928 -154.5082)
		(width 0.1397)
		(layer "In5.Cu")
		(net "USB_P3_DP")
	)
	(segment
		(start 85.08238 -154.336496)
		(end 85.514434 -153.904442)
		(width 0.1397)
		(layer "In5.Cu")
		(net "USB_P3_DP")
	)
	(segment
		(start 66.225928 -154.5082)
		(end 66.905378 -153.82875)
		(width 0.1397)
		(layer "In5.Cu")
		(net "USB_P3_DP")
	)
	(segment
		(start 66.905378 -153.82875)
		(end 73.818496 -153.82875)
		(width 0.1397)
		(layer "In5.Cu")
		(net "USB_P3_DP")
	)
	(segment
		(start 60.05195 -152.464008)
		(end 58.830718 -151.242776)
		(width 0.14605)
		(layer "F.Cu")
		(net "USB_P3_DN")
	)
	(segment
		(start 64.305434 -154.107896)
		(end 60.720478 -154.107896)
		(width 0.14605)
		(layer "F.Cu")
		(net "USB_P3_DN")
	)
	(segment
		(start 58.255408 -151.242776)
		(end 56.536082 -149.52345)
		(width 0.14605)
		(layer "F.Cu")
		(net "USB_P3_DN")
	)
	(segment
		(start 84.903056 -153.072592)
		(end 85.198204 -153.36774)
		(width 0.14605)
		(layer "F.Cu")
		(net "USB_P3_DN")
	)
	(segment
		(start 87.894414 -155.00731)
		(end 88.953848 -155.00731)
		(width 0.14605)
		(layer "F.Cu")
		(net "USB_P3_DN")
	)
	(segment
		(start 88.953848 -155.00731)
		(end 89.051892 -155.105354)
		(width 0.14605)
		(layer "F.Cu")
		(net "USB_P3_DN")
	)
	(segment
		(start 56.223408 -149.52345)
		(end 56.099964 -149.400006)
		(width 0.14605)
		(layer "F.Cu")
		(net "USB_P3_DN")
	)
	(segment
		(start 87.28837 -154.401266)
		(end 87.894414 -155.00731)
		(width 0.14605)
		(layer "F.Cu")
		(net "USB_P3_DN")
	)
	(segment
		(start 64.416686 -154.219148)
		(end 64.305434 -154.107896)
		(width 0.14605)
		(layer "F.Cu")
		(net "USB_P3_DN")
	)
	(segment
		(start 85.198204 -153.36774)
		(end 85.198204 -153.967434)
		(width 0.14605)
		(layer "F.Cu")
		(net "USB_P3_DN")
	)
	(segment
		(start 89.051892 -155.105354)
		(end 89.881456 -155.105354)
		(width 0.14605)
		(layer "F.Cu")
		(net "USB_P3_DN")
	)
	(segment
		(start 85.198204 -153.967434)
		(end 85.632036 -154.401266)
		(width 0.14605)
		(layer "F.Cu")
		(net "USB_P3_DN")
	)
	(segment
		(start 85.632036 -154.401266)
		(end 87.28837 -154.401266)
		(width 0.14605)
		(layer "F.Cu")
		(net "USB_P3_DN")
	)
	(segment
		(start 60.720478 -154.107896)
		(end 60.05195 -153.439368)
		(width 0.14605)
		(layer "F.Cu")
		(net "USB_P3_DN")
	)
	(segment
		(start 65.316354 -154.219148)
		(end 64.416686 -154.219148)
		(width 0.14605)
		(layer "F.Cu")
		(net "USB_P3_DN")
	)
	(segment
		(start 56.536082 -149.52345)
		(end 56.223408 -149.52345)
		(width 0.14605)
		(layer "F.Cu")
		(net "USB_P3_DN")
	)
	(segment
		(start 60.05195 -153.439368)
		(end 60.05195 -152.464008)
		(width 0.14605)
		(layer "F.Cu")
		(net "USB_P3_DN")
	)
	(segment
		(start 58.830718 -151.242776)
		(end 58.255408 -151.242776)
		(width 0.14605)
		(layer "F.Cu")
		(net "USB_P3_DN")
	)
	(segment
		(start 65.633092 -153.90241)
		(end 65.316354 -154.219148)
		(width 0.14605)
		(layer "F.Cu")
		(net "USB_P3_DN")
	)
	(via
		(at 65.633092 -153.90241)
		(size 0.508)
		(drill 0.254)
		(layers "F.Cu" "B.Cu")
		(net "USB_P3_DN")
	)
	(via
		(at 84.903056 -153.072592)
		(size 0.508)
		(drill 0.254)
		(layers "F.Cu" "B.Cu")
		(net "USB_P3_DN")
	)
	(segment
		(start 80.339692 -155.704032)
		(end 80.758792 -155.704032)
		(width 0.1397)
		(layer "In5.Cu")
		(net "USB_P3_DN")
	)
	(segment
		(start 66.089022 -154.178)
		(end 66.768472 -153.49855)
		(width 0.1397)
		(layer "In5.Cu")
		(net "USB_P3_DN")
	)
	(segment
		(start 74.6506 -154.193748)
		(end 74.90206 -154.193748)
		(width 0.1397)
		(layer "In5.Cu")
		(net "USB_P3_DN")
	)
	(segment
		(start 80.936592 -155.881832)
		(end 81.355692 -155.881832)
		(width 0.1397)
		(layer "In5.Cu")
		(net "USB_P3_DN")
	)
	(segment
		(start 80.758792 -155.704032)
		(end 80.936592 -155.881832)
		(width 0.1397)
		(layer "In5.Cu")
		(net "USB_P3_DN")
	)
	(segment
		(start 73.955402 -153.49855)
		(end 74.6506 -154.193748)
		(width 0.1397)
		(layer "In5.Cu")
		(net "USB_P3_DN")
	)
	(segment
		(start 74.90206 -154.193748)
		(end 75.198224 -154.489912)
		(width 0.1397)
		(layer "In5.Cu")
		(net "USB_P3_DN")
	)
	(segment
		(start 65.908682 -154.178)
		(end 66.089022 -154.178)
		(width 0.1397)
		(layer "In5.Cu")
		(net "USB_P3_DN")
	)
	(segment
		(start 79.564992 -155.704032)
		(end 79.742792 -155.881832)
		(width 0.1397)
		(layer "In5.Cu")
		(net "USB_P3_DN")
	)
	(segment
		(start 75.198224 -154.489912)
		(end 75.198224 -154.741372)
		(width 0.1397)
		(layer "In5.Cu")
		(net "USB_P3_DN")
	)
	(segment
		(start 75.198224 -154.741372)
		(end 75.494642 -155.03779)
		(width 0.1397)
		(layer "In5.Cu")
		(net "USB_P3_DN")
	)
	(segment
		(start 76.042266 -155.585414)
		(end 76.338684 -155.881832)
		(width 0.1397)
		(layer "In5.Cu")
		(net "USB_P3_DN")
	)
	(segment
		(start 78.968092 -155.881832)
		(end 79.145892 -155.704032)
		(width 0.1397)
		(layer "In5.Cu")
		(net "USB_P3_DN")
	)
	(segment
		(start 84.945474 -154.006296)
		(end 85.184234 -153.767536)
		(width 0.1397)
		(layer "In5.Cu")
		(net "USB_P3_DN")
	)
	(segment
		(start 66.768472 -153.49855)
		(end 73.955402 -153.49855)
		(width 0.1397)
		(layer "In5.Cu")
		(net "USB_P3_DN")
	)
	(segment
		(start 81.355692 -155.881832)
		(end 81.533492 -155.704032)
		(width 0.1397)
		(layer "In5.Cu")
		(net "USB_P3_DN")
	)
	(segment
		(start 81.952592 -155.704032)
		(end 82.130392 -155.881832)
		(width 0.1397)
		(layer "In5.Cu")
		(net "USB_P3_DN")
	)
	(segment
		(start 84.425028 -154.006296)
		(end 84.945474 -154.006296)
		(width 0.1397)
		(layer "In5.Cu")
		(net "USB_P3_DN")
	)
	(segment
		(start 82.549492 -155.881832)
		(end 84.425028 -154.006296)
		(width 0.1397)
		(layer "In5.Cu")
		(net "USB_P3_DN")
	)
	(segment
		(start 81.533492 -155.704032)
		(end 81.952592 -155.704032)
		(width 0.1397)
		(layer "In5.Cu")
		(net "USB_P3_DN")
	)
	(segment
		(start 85.184234 -153.35377)
		(end 84.903056 -153.072592)
		(width 0.1397)
		(layer "In5.Cu")
		(net "USB_P3_DN")
	)
	(segment
		(start 85.184234 -153.767536)
		(end 85.184234 -153.35377)
		(width 0.1397)
		(layer "In5.Cu")
		(net "USB_P3_DN")
	)
	(segment
		(start 79.742792 -155.881832)
		(end 80.161892 -155.881832)
		(width 0.1397)
		(layer "In5.Cu")
		(net "USB_P3_DN")
	)
	(segment
		(start 82.130392 -155.881832)
		(end 82.549492 -155.881832)
		(width 0.1397)
		(layer "In5.Cu")
		(net "USB_P3_DN")
	)
	(segment
		(start 78.371192 -155.704032)
		(end 78.548992 -155.881832)
		(width 0.1397)
		(layer "In5.Cu")
		(net "USB_P3_DN")
	)
	(segment
		(start 75.746102 -155.03779)
		(end 76.042266 -155.333954)
		(width 0.1397)
		(layer "In5.Cu")
		(net "USB_P3_DN")
	)
	(segment
		(start 65.633092 -153.90241)
		(end 65.908682 -154.178)
		(width 0.1397)
		(layer "In5.Cu")
		(net "USB_P3_DN")
	)
	(segment
		(start 77.952092 -155.704032)
		(end 78.371192 -155.704032)
		(width 0.1397)
		(layer "In5.Cu")
		(net "USB_P3_DN")
	)
	(segment
		(start 76.338684 -155.881832)
		(end 77.774292 -155.881832)
		(width 0.1397)
		(layer "In5.Cu")
		(net "USB_P3_DN")
	)
	(segment
		(start 80.161892 -155.881832)
		(end 80.339692 -155.704032)
		(width 0.1397)
		(layer "In5.Cu")
		(net "USB_P3_DN")
	)
	(segment
		(start 75.494642 -155.03779)
		(end 75.746102 -155.03779)
		(width 0.1397)
		(layer "In5.Cu")
		(net "USB_P3_DN")
	)
	(segment
		(start 77.774292 -155.881832)
		(end 77.952092 -155.704032)
		(width 0.1397)
		(layer "In5.Cu")
		(net "USB_P3_DN")
	)
	(segment
		(start 79.145892 -155.704032)
		(end 79.564992 -155.704032)
		(width 0.1397)
		(layer "In5.Cu")
		(net "USB_P3_DN")
	)
	(segment
		(start 78.548992 -155.881832)
		(end 78.968092 -155.881832)
		(width 0.1397)
		(layer "In5.Cu")
		(net "USB_P3_DN")
	)
	(segment
		(start 76.042266 -155.333954)
		(end 76.042266 -155.585414)
		(width 0.1397)
		(layer "In5.Cu")
		(net "USB_P3_DN")
	)
	(segment
		(start 88.320372 -156.212794)
		(end 88.980772 -156.212794)
		(width 0.14605)
		(layer "F.Cu")
		(net "USB_P2_DP")
	)
	(segment
		(start 65.094104 -152.784302)
		(end 65.362328 -153.052526)
		(width 0.14605)
		(layer "F.Cu")
		(net "USB_P2_DP")
	)
	(segment
		(start 64.18072 -152.784302)
		(end 65.094104 -152.784302)
		(width 0.14605)
		(layer "F.Cu")
		(net "USB_P2_DP")
	)
	(segment
		(start 86.7664 -155.806902)
		(end 87.07247 -156.112972)
		(width 0.14605)
		(layer "F.Cu")
		(net "USB_P2_DP")
	)
	(segment
		(start 89.08796 -156.105606)
		(end 89.881456 -156.105606)
		(width 0.14605)
		(layer "F.Cu")
		(net "USB_P2_DP")
	)
	(segment
		(start 56.099964 -148.599906)
		(end 56.348122 -148.351748)
		(width 0.14605)
		(layer "F.Cu")
		(net "USB_P2_DP")
	)
	(segment
		(start 57.483756 -148.351748)
		(end 60.770008 -151.638)
		(width 0.14605)
		(layer "F.Cu")
		(net "USB_P2_DP")
	)
	(segment
		(start 87.07247 -156.112972)
		(end 88.22055 -156.112972)
		(width 0.14605)
		(layer "F.Cu")
		(net "USB_P2_DP")
	)
	(segment
		(start 60.770008 -151.638)
		(end 63.034418 -151.638)
		(width 0.14605)
		(layer "F.Cu")
		(net "USB_P2_DP")
	)
	(segment
		(start 56.348122 -148.351748)
		(end 57.483756 -148.351748)
		(width 0.14605)
		(layer "F.Cu")
		(net "USB_P2_DP")
	)
	(segment
		(start 88.22055 -156.112972)
		(end 88.320372 -156.212794)
		(width 0.14605)
		(layer "F.Cu")
		(net "USB_P2_DP")
	)
	(segment
		(start 63.034418 -151.638)
		(end 64.18072 -152.784302)
		(width 0.14605)
		(layer "F.Cu")
		(net "USB_P2_DP")
	)
	(segment
		(start 88.980772 -156.212794)
		(end 89.08796 -156.105606)
		(width 0.14605)
		(layer "F.Cu")
		(net "USB_P2_DP")
	)
	(via
		(at 65.362328 -153.052526)
		(size 0.508)
		(drill 0.254)
		(layers "F.Cu" "B.Cu")
		(net "USB_P2_DP")
	)
	(via
		(at 86.7664 -155.806902)
		(size 0.508)
		(drill 0.254)
		(layers "F.Cu" "B.Cu")
		(net "USB_P2_DP")
	)
	(segment
		(start 78.915768 -155.005532)
		(end 79.093568 -154.827732)
		(width 0.1397)
		(layer "In5.Cu")
		(net "USB_P2_DP")
	)
	(segment
		(start 87.392764 -153.999692)
		(end 87.570564 -154.177492)
		(width 0.1397)
		(layer "In5.Cu")
		(net "USB_P2_DP")
	)
	(segment
		(start 78.496668 -155.005532)
		(end 78.915768 -155.005532)
		(width 0.1397)
		(layer "In5.Cu")
		(net "USB_P2_DP")
	)
	(segment
		(start 79.512668 -154.827732)
		(end 79.690468 -155.005532)
		(width 0.1397)
		(layer "In5.Cu")
		(net "USB_P2_DP")
	)
	(segment
		(start 87.06485 -156.105352)
		(end 86.7664 -155.806902)
		(width 0.1397)
		(layer "In5.Cu")
		(net "USB_P2_DP")
	)
	(segment
		(start 80.884268 -155.005532)
		(end 81.303368 -155.005532)
		(width 0.1397)
		(layer "In5.Cu")
		(net "USB_P2_DP")
	)
	(segment
		(start 87.342218 -156.105352)
		(end 87.06485 -156.105352)
		(width 0.1397)
		(layer "In5.Cu")
		(net "USB_P2_DP")
	)
	(segment
		(start 80.287368 -154.827732)
		(end 80.706468 -154.827732)
		(width 0.1397)
		(layer "In5.Cu")
		(net "USB_P2_DP")
	)
	(segment
		(start 76.55687 -154.827732)
		(end 77.125068 -154.827732)
		(width 0.1397)
		(layer "In5.Cu")
		(net "USB_P2_DP")
	)
	(segment
		(start 84.477352 -152.053036)
		(end 84.655152 -152.230836)
		(width 0.1397)
		(layer "In5.Cu")
		(net "USB_P2_DP")
	)
	(segment
		(start 81.303368 -155.005532)
		(end 81.481168 -154.827732)
		(width 0.1397)
		(layer "In5.Cu")
		(net "USB_P2_DP")
	)
	(segment
		(start 74.534014 -152.804876)
		(end 76.55687 -154.827732)
		(width 0.1397)
		(layer "In5.Cu")
		(net "USB_P2_DP")
	)
	(segment
		(start 78.318868 -154.827732)
		(end 78.496668 -155.005532)
		(width 0.1397)
		(layer "In5.Cu")
		(net "USB_P2_DP")
	)
	(segment
		(start 79.093568 -154.827732)
		(end 79.512668 -154.827732)
		(width 0.1397)
		(layer "In5.Cu")
		(net "USB_P2_DP")
	)
	(segment
		(start 83.87715 -152.053036)
		(end 84.477352 -152.053036)
		(width 0.1397)
		(layer "In5.Cu")
		(net "USB_P2_DP")
	)
	(segment
		(start 77.721968 -155.005532)
		(end 77.899768 -154.827732)
		(width 0.1397)
		(layer "In5.Cu")
		(net "USB_P2_DP")
	)
	(segment
		(start 87.570564 -155.877006)
		(end 87.342218 -156.105352)
		(width 0.1397)
		(layer "In5.Cu")
		(net "USB_P2_DP")
	)
	(segment
		(start 87.570564 -154.177492)
		(end 87.570564 -155.877006)
		(width 0.1397)
		(layer "In5.Cu")
		(net "USB_P2_DP")
	)
	(segment
		(start 65.362328 -153.052526)
		(end 65.609978 -152.804876)
		(width 0.1397)
		(layer "In5.Cu")
		(net "USB_P2_DP")
	)
	(segment
		(start 82.214974 -154.827732)
		(end 83.1342 -153.908506)
		(width 0.1397)
		(layer "In5.Cu")
		(net "USB_P2_DP")
	)
	(segment
		(start 77.125068 -154.827732)
		(end 77.302868 -155.005532)
		(width 0.1397)
		(layer "In5.Cu")
		(net "USB_P2_DP")
	)
	(segment
		(start 86.864952 -152.053036)
		(end 87.570564 -152.758648)
		(width 0.1397)
		(layer "In5.Cu")
		(net "USB_P2_DP")
	)
	(segment
		(start 77.899768 -154.827732)
		(end 78.318868 -154.827732)
		(width 0.1397)
		(layer "In5.Cu")
		(net "USB_P2_DP")
	)
	(segment
		(start 79.690468 -155.005532)
		(end 80.109568 -155.005532)
		(width 0.1397)
		(layer "In5.Cu")
		(net "USB_P2_DP")
	)
	(segment
		(start 85.252052 -152.053036)
		(end 85.671152 -152.053036)
		(width 0.1397)
		(layer "In5.Cu")
		(net "USB_P2_DP")
	)
	(segment
		(start 87.570564 -153.402792)
		(end 87.392764 -153.580592)
		(width 0.1397)
		(layer "In5.Cu")
		(net "USB_P2_DP")
	)
	(segment
		(start 81.481168 -154.827732)
		(end 82.214974 -154.827732)
		(width 0.1397)
		(layer "In5.Cu")
		(net "USB_P2_DP")
	)
	(segment
		(start 87.570564 -152.758648)
		(end 87.570564 -153.402792)
		(width 0.1397)
		(layer "In5.Cu")
		(net "USB_P2_DP")
	)
	(segment
		(start 84.655152 -152.230836)
		(end 85.074252 -152.230836)
		(width 0.1397)
		(layer "In5.Cu")
		(net "USB_P2_DP")
	)
	(segment
		(start 80.706468 -154.827732)
		(end 80.884268 -155.005532)
		(width 0.1397)
		(layer "In5.Cu")
		(net "USB_P2_DP")
	)
	(segment
		(start 65.609978 -152.804876)
		(end 74.534014 -152.804876)
		(width 0.1397)
		(layer "In5.Cu")
		(net "USB_P2_DP")
	)
	(segment
		(start 80.109568 -155.005532)
		(end 80.287368 -154.827732)
		(width 0.1397)
		(layer "In5.Cu")
		(net "USB_P2_DP")
	)
	(segment
		(start 85.074252 -152.230836)
		(end 85.252052 -152.053036)
		(width 0.1397)
		(layer "In5.Cu")
		(net "USB_P2_DP")
	)
	(segment
		(start 83.1342 -153.908506)
		(end 83.1342 -152.795986)
		(width 0.1397)
		(layer "In5.Cu")
		(net "USB_P2_DP")
	)
	(segment
		(start 87.392764 -153.580592)
		(end 87.392764 -153.999692)
		(width 0.1397)
		(layer "In5.Cu")
		(net "USB_P2_DP")
	)
	(segment
		(start 83.1342 -152.795986)
		(end 83.87715 -152.053036)
		(width 0.1397)
		(layer "In5.Cu")
		(net "USB_P2_DP")
	)
	(segment
		(start 86.268052 -152.230836)
		(end 86.445852 -152.053036)
		(width 0.1397)
		(layer "In5.Cu")
		(net "USB_P2_DP")
	)
	(segment
		(start 77.302868 -155.005532)
		(end 77.721968 -155.005532)
		(width 0.1397)
		(layer "In5.Cu")
		(net "USB_P2_DP")
	)
	(segment
		(start 85.671152 -152.053036)
		(end 85.848952 -152.230836)
		(width 0.1397)
		(layer "In5.Cu")
		(net "USB_P2_DP")
	)
	(segment
		(start 86.445852 -152.053036)
		(end 86.864952 -152.053036)
		(width 0.1397)
		(layer "In5.Cu")
		(net "USB_P2_DP")
	)
	(segment
		(start 85.848952 -152.230836)
		(end 86.268052 -152.230836)
		(width 0.1397)
		(layer "In5.Cu")
		(net "USB_P2_DP")
	)
	(segment
		(start 87.050626 -156.424122)
		(end 88.091518 -156.424122)
		(width 0.14605)
		(layer "F.Cu")
		(net "USB_P2_DN")
	)
	(segment
		(start 88.19134 -156.523944)
		(end 88.945466 -156.523944)
		(width 0.14605)
		(layer "F.Cu")
		(net "USB_P2_DN")
	)
	(segment
		(start 64.309752 -152.473152)
		(end 65.081658 -152.473152)
		(width 0.14605)
		(layer "F.Cu")
		(net "USB_P2_DN")
	)
	(segment
		(start 56.099964 -147.80006)
		(end 56.099964 -147.800314)
		(width 0.14605)
		(layer "F.Cu")
		(net "USB_P2_DN")
	)
	(segment
		(start 65.081658 -152.473152)
		(end 65.365884 -152.188926)
		(width 0.14605)
		(layer "F.Cu")
		(net "USB_P2_DN")
	)
	(segment
		(start 56.340248 -148.040598)
		(end 57.612788 -148.040598)
		(width 0.14605)
		(layer "F.Cu")
		(net "USB_P2_DN")
	)
	(segment
		(start 57.612788 -148.040598)
		(end 60.89904 -151.32685)
		(width 0.14605)
		(layer "F.Cu")
		(net "USB_P2_DN")
	)
	(segment
		(start 60.89904 -151.32685)
		(end 63.16345 -151.32685)
		(width 0.14605)
		(layer "F.Cu")
		(net "USB_P2_DN")
	)
	(segment
		(start 86.7664 -156.708348)
		(end 87.050626 -156.424122)
		(width 0.14605)
		(layer "F.Cu")
		(net "USB_P2_DN")
	)
	(segment
		(start 89.027 -156.605478)
		(end 89.881456 -156.605478)
		(width 0.14605)
		(layer "F.Cu")
		(net "USB_P2_DN")
	)
	(segment
		(start 63.16345 -151.32685)
		(end 64.309752 -152.473152)
		(width 0.14605)
		(layer "F.Cu")
		(net "USB_P2_DN")
	)
	(segment
		(start 56.099964 -147.800314)
		(end 56.340248 -148.040598)
		(width 0.14605)
		(layer "F.Cu")
		(net "USB_P2_DN")
	)
	(segment
		(start 88.091518 -156.424122)
		(end 88.19134 -156.523944)
		(width 0.14605)
		(layer "F.Cu")
		(net "USB_P2_DN")
	)
	(segment
		(start 88.945466 -156.523944)
		(end 89.027 -156.605478)
		(width 0.14605)
		(layer "F.Cu")
		(net "USB_P2_DN")
	)
	(via
		(at 86.7664 -156.708348)
		(size 0.508)
		(drill 0.254)
		(layers "F.Cu" "B.Cu")
		(net "USB_P2_DN")
	)
	(via
		(at 65.365884 -152.188926)
		(size 0.508)
		(drill 0.254)
		(layers "F.Cu" "B.Cu")
		(net "USB_P2_DN")
	)
	(segment
		(start 87.001858 -151.722836)
		(end 87.900764 -152.621742)
		(width 0.1397)
		(layer "In5.Cu")
		(net "USB_P2_DN")
	)
	(segment
		(start 87.900764 -152.621742)
		(end 87.900764 -156.013912)
		(width 0.1397)
		(layer "In5.Cu")
		(net "USB_P2_DN")
	)
	(segment
		(start 87.479124 -156.435552)
		(end 87.039196 -156.435552)
		(width 0.1397)
		(layer "In5.Cu")
		(net "USB_P2_DN")
	)
	(segment
		(start 76.693776 -154.497532)
		(end 82.078068 -154.497532)
		(width 0.1397)
		(layer "In5.Cu")
		(net "USB_P2_DN")
	)
	(segment
		(start 65.365884 -152.188926)
		(end 65.651634 -152.474676)
		(width 0.1397)
		(layer "In5.Cu")
		(net "USB_P2_DN")
	)
	(segment
		(start 82.078068 -154.497532)
		(end 82.804 -153.7716)
		(width 0.1397)
		(layer "In5.Cu")
		(net "USB_P2_DN")
	)
	(segment
		(start 82.804 -152.65908)
		(end 83.740244 -151.722836)
		(width 0.1397)
		(layer "In5.Cu")
		(net "USB_P2_DN")
	)
	(segment
		(start 87.039196 -156.435552)
		(end 86.7664 -156.708348)
		(width 0.1397)
		(layer "In5.Cu")
		(net "USB_P2_DN")
	)
	(segment
		(start 65.651634 -152.474676)
		(end 74.67092 -152.474676)
		(width 0.1397)
		(layer "In5.Cu")
		(net "USB_P2_DN")
	)
	(segment
		(start 74.67092 -152.474676)
		(end 76.693776 -154.497532)
		(width 0.1397)
		(layer "In5.Cu")
		(net "USB_P2_DN")
	)
	(segment
		(start 82.804 -153.7716)
		(end 82.804 -152.65908)
		(width 0.1397)
		(layer "In5.Cu")
		(net "USB_P2_DN")
	)
	(segment
		(start 83.740244 -151.722836)
		(end 87.001858 -151.722836)
		(width 0.1397)
		(layer "In5.Cu")
		(net "USB_P2_DN")
	)
	(segment
		(start 87.900764 -156.013912)
		(end 87.479124 -156.435552)
		(width 0.1397)
		(layer "In5.Cu")
		(net "USB_P2_DN")
	)
	(segment
		(start 94.283276 -16.879824)
		(end 89.245186 -16.879824)
		(width 0.14605)
		(layer "F.Cu")
		(net "USB_P1_F_DP1")
	)
	(segment
		(start 88.212168 -17.697958)
		(end 88.000078 -17.485868)
		(width 0.14605)
		(layer "F.Cu")
		(net "USB_P1_F_DP1")
	)
	(segment
		(start 96.458024 -16.888206)
		(end 97.717864 -15.628366)
		(width 0.14605)
		(layer "F.Cu")
		(net "USB_P1_F_DP1")
	)
	(segment
		(start 94.488 -16.6751)
		(end 94.701106 -16.888206)
		(width 0.14605)
		(layer "F.Cu")
		(net "USB_P1_F_DP1")
	)
	(segment
		(start 89.245186 -16.879824)
		(end 88.427052 -17.697958)
		(width 0.14605)
		(layer "F.Cu")
		(net "USB_P1_F_DP1")
	)
	(segment
		(start 88.000078 -17.485868)
		(end 88.000078 -16.9799)
		(width 0.14605)
		(layer "F.Cu")
		(net "USB_P1_F_DP1")
	)
	(segment
		(start 99.065842 -16.146018)
		(end 99.065842 -16.586454)
		(width 0.14605)
		(layer "F.Cu")
		(net "USB_P1_F_DP1")
	)
	(segment
		(start 94.488 -16.6751)
		(end 94.283276 -16.879824)
		(width 0.14605)
		(layer "F.Cu")
		(net "USB_P1_F_DP1")
	)
	(segment
		(start 97.717864 -15.628366)
		(end 98.54819 -15.628366)
		(width 0.14605)
		(layer "F.Cu")
		(net "USB_P1_F_DP1")
	)
	(segment
		(start 99.404932 -16.925544)
		(end 99.404932 -17.563846)
		(width 0.14605)
		(layer "F.Cu")
		(net "USB_P1_F_DP1")
	)
	(segment
		(start 98.54819 -15.628366)
		(end 99.065842 -16.146018)
		(width 0.14605)
		(layer "F.Cu")
		(net "USB_P1_F_DP1")
	)
	(segment
		(start 88.427052 -17.697958)
		(end 88.212168 -17.697958)
		(width 0.14605)
		(layer "F.Cu")
		(net "USB_P1_F_DP1")
	)
	(segment
		(start 99.065842 -16.586454)
		(end 99.404932 -16.925544)
		(width 0.14605)
		(layer "F.Cu")
		(net "USB_P1_F_DP1")
	)
	(segment
		(start 94.701106 -16.888206)
		(end 96.458024 -16.888206)
		(width 0.14605)
		(layer "F.Cu")
		(net "USB_P1_F_DP1")
	)
	(segment
		(start 91.57462 -17.356074)
		(end 91.13647 -17.356074)
		(width 0.14605)
		(layer "F.Cu")
		(net "USB_P1_F_DN1")
	)
	(segment
		(start 94.488 -17.4117)
		(end 94.700344 -17.199356)
		(width 0.14605)
		(layer "F.Cu")
		(net "USB_P1_F_DN1")
	)
	(segment
		(start 94.700344 -17.199356)
		(end 96.587056 -17.199356)
		(width 0.14605)
		(layer "F.Cu")
		(net "USB_P1_F_DN1")
	)
	(segment
		(start 96.587056 -17.199356)
		(end 97.846896 -15.939516)
		(width 0.14605)
		(layer "F.Cu")
		(net "USB_P1_F_DN1")
	)
	(segment
		(start 90.97137 -17.190974)
		(end 89.374218 -17.190974)
		(width 0.14605)
		(layer "F.Cu")
		(net "USB_P1_F_DN1")
	)
	(segment
		(start 92.34297 -17.356074)
		(end 92.17787 -17.190974)
		(width 0.14605)
		(layer "F.Cu")
		(net "USB_P1_F_DN1")
	)
	(segment
		(start 92.17787 -17.190974)
		(end 91.73972 -17.190974)
		(width 0.14605)
		(layer "F.Cu")
		(net "USB_P1_F_DN1")
	)
	(segment
		(start 88.213946 -18.009108)
		(end 88.000078 -18.222976)
		(width 0.14605)
		(layer "F.Cu")
		(net "USB_P1_F_DN1")
	)
	(segment
		(start 94.270068 -17.193768)
		(end 92.94622 -17.193768)
		(width 0.14605)
		(layer "F.Cu")
		(net "USB_P1_F_DN1")
	)
	(segment
		(start 91.13647 -17.356074)
		(end 90.97137 -17.190974)
		(width 0.14605)
		(layer "F.Cu")
		(net "USB_P1_F_DN1")
	)
	(segment
		(start 89.374218 -17.190974)
		(end 88.556084 -18.009108)
		(width 0.14605)
		(layer "F.Cu")
		(net "USB_P1_F_DN1")
	)
	(segment
		(start 94.488 -17.4117)
		(end 94.270068 -17.193768)
		(width 0.14605)
		(layer "F.Cu")
		(net "USB_P1_F_DN1")
	)
	(segment
		(start 92.783914 -17.356074)
		(end 92.34297 -17.356074)
		(width 0.14605)
		(layer "F.Cu")
		(net "USB_P1_F_DN1")
	)
	(segment
		(start 98.419158 -15.939516)
		(end 98.754692 -16.27505)
		(width 0.14605)
		(layer "F.Cu")
		(net "USB_P1_F_DN1")
	)
	(segment
		(start 91.73972 -17.190974)
		(end 91.57462 -17.356074)
		(width 0.14605)
		(layer "F.Cu")
		(net "USB_P1_F_DN1")
	)
	(segment
		(start 98.754692 -16.27505)
		(end 98.754692 -16.544036)
		(width 0.14605)
		(layer "F.Cu")
		(net "USB_P1_F_DN1")
	)
	(segment
		(start 88.556084 -18.009108)
		(end 88.213946 -18.009108)
		(width 0.14605)
		(layer "F.Cu")
		(net "USB_P1_F_DN1")
	)
	(segment
		(start 97.846896 -15.939516)
		(end 98.419158 -15.939516)
		(width 0.14605)
		(layer "F.Cu")
		(net "USB_P1_F_DN1")
	)
	(segment
		(start 98.439732 -16.858996)
		(end 98.439732 -17.563846)
		(width 0.14605)
		(layer "F.Cu")
		(net "USB_P1_F_DN1")
	)
	(segment
		(start 92.94622 -17.193768)
		(end 92.783914 -17.356074)
		(width 0.14605)
		(layer "F.Cu")
		(net "USB_P1_F_DN1")
	)
	(segment
		(start 98.754692 -16.544036)
		(end 98.439732 -16.858996)
		(width 0.14605)
		(layer "F.Cu")
		(net "USB_P1_F_DN1")
	)
	(segment
		(start 88.000078 -18.222976)
		(end 88.000078 -18.979896)
		(width 0.14605)
		(layer "F.Cu")
		(net "USB_P1_F_DN1")
	)
	(segment
		(start 89.881456 -157.105604)
		(end 88.918796 -157.105604)
		(width 0.14605)
		(layer "F.Cu")
		(net "USB_P1_DP")
	)
	(segment
		(start 99.11588 -20.20316)
		(end 99.11588 -20.769072)
		(width 0.14605)
		(layer "F.Cu")
		(net "USB_P1_DP")
	)
	(segment
		(start 99.404932 -19.914108)
		(end 99.11588 -20.20316)
		(width 0.14605)
		(layer "F.Cu")
		(net "USB_P1_DP")
	)
	(segment
		(start 88.918796 -157.105604)
		(end 88.833452 -157.190948)
		(width 0.14605)
		(layer "F.Cu")
		(net "USB_P1_DP")
	)
	(segment
		(start 87.100918 -158.710376)
		(end 86.80577 -158.415228)
		(width 0.14605)
		(layer "F.Cu")
		(net "USB_P1_DP")
	)
	(segment
		(start 99.11588 -20.769072)
		(end 99.411028 -21.06422)
		(width 0.14605)
		(layer "F.Cu")
		(net "USB_P1_DP")
	)
	(segment
		(start 88.833452 -157.190948)
		(end 88.52662 -157.190948)
		(width 0.14605)
		(layer "F.Cu")
		(net "USB_P1_DP")
	)
	(segment
		(start 87.768684 -158.238698)
		(end 87.297006 -158.710376)
		(width 0.14605)
		(layer "F.Cu")
		(net "USB_P1_DP")
	)
	(segment
		(start 88.52662 -157.190948)
		(end 87.768684 -157.948884)
		(width 0.14605)
		(layer "F.Cu")
		(net "USB_P1_DP")
	)
	(segment
		(start 99.404932 -19.240246)
		(end 99.404932 -19.914108)
		(width 0.14605)
		(layer "F.Cu")
		(net "USB_P1_DP")
	)
	(segment
		(start 87.297006 -158.710376)
		(end 87.100918 -158.710376)
		(width 0.14605)
		(layer "F.Cu")
		(net "USB_P1_DP")
	)
	(segment
		(start 87.768684 -157.948884)
		(end 87.768684 -158.238698)
		(width 0.14605)
		(layer "F.Cu")
		(net "USB_P1_DP")
	)
	(via
		(at 86.80577 -158.415228)
		(size 0.508)
		(drill 0.254)
		(layers "F.Cu" "B.Cu")
		(net "USB_P1_DP")
	)
	(via
		(at 99.411028 -21.06422)
		(size 0.508)
		(drill 0.254)
		(layers "F.Cu" "B.Cu")
		(net "USB_P1_DP")
	)
	(segment
		(start 89.74455 -40.603932)
		(end 89.92235 -40.426132)
		(width 0.1397)
		(layer "In2.Cu")
		(net "USB_P1_DP")
	)
	(segment
		(start 89.92235 -42.394632)
		(end 89.74455 -42.216832)
		(width 0.1397)
		(layer "In2.Cu")
		(net "USB_P1_DP")
	)
	(segment
		(start 89.92235 -40.426132)
		(end 89.92235 -40.007032)
		(width 0.1397)
		(layer "In2.Cu")
		(net "USB_P1_DP")
	)
	(segment
		(start 88.627204 -114.999008)
		(end 88.627204 -113.529364)
		(width 0.1397)
		(layer "In2.Cu")
		(net "USB_P1_DP")
	)
	(segment
		(start 90.64625 -95.508826)
		(end 90.07475 -94.937326)
		(width 0.1397)
		(layer "In2.Cu")
		(net "USB_P1_DP")
	)
	(segment
		(start 87.05215 -131.162298)
		(end 87.05215 -125.247146)
		(width 0.1397)
		(layer "In2.Cu")
		(net "USB_P1_DP")
	)
	(segment
		(start 89.92235 -40.007032)
		(end 89.74455 -39.829232)
		(width 0.1397)
		(layer "In2.Cu")
		(net "USB_P1_DP")
	)
	(segment
		(start 90.07475 -94.0562)
		(end 90.22715 -93.9038)
		(width 0.1397)
		(layer "In2.Cu")
		(net "USB_P1_DP")
	)
	(segment
		(start 88.85555 -46.47565)
		(end 89.74455 -45.58665)
		(width 0.1397)
		(layer "In2.Cu")
		(net "USB_P1_DP")
	)
	(segment
		(start 89.74455 -42.216832)
		(end 89.74455 -41.797732)
		(width 0.1397)
		(layer "In2.Cu")
		(net "USB_P1_DP")
	)
	(segment
		(start 99.047554 -21.427694)
		(end 99.411028 -21.06422)
		(width 0.1397)
		(layer "In2.Cu")
		(net "USB_P1_DP")
	)
	(segment
		(start 99.047554 -21.861272)
		(end 99.047554 -21.427694)
		(width 0.1397)
		(layer "In2.Cu")
		(net "USB_P1_DP")
	)
	(segment
		(start 89.171018 -111.787686)
		(end 91.25585 -109.702854)
		(width 0.1397)
		(layer "In2.Cu")
		(net "USB_P1_DP")
	)
	(segment
		(start 87.49665 -139.025122)
		(end 87.49665 -134.197852)
		(width 0.1397)
		(layer "In2.Cu")
		(net "USB_P1_DP")
	)
	(segment
		(start 87.05215 -125.247146)
		(end 88.53805 -123.761246)
		(width 0.1397)
		(layer "In2.Cu")
		(net "USB_P1_DP")
	)
	(segment
		(start 86.305136 -158.6992)
		(end 86.090506 -158.48457)
		(width 0.1397)
		(layer "In2.Cu")
		(net "USB_P1_DP")
	)
	(segment
		(start 89.74455 -41.023032)
		(end 89.74455 -40.603932)
		(width 0.1397)
		(layer "In2.Cu")
		(net "USB_P1_DP")
	)
	(segment
		(start 89.74455 -42.991532)
		(end 89.92235 -42.813732)
		(width 0.1397)
		(layer "In2.Cu")
		(net "USB_P1_DP")
	)
	(segment
		(start 88.53805 -123.761246)
		(end 88.53805 -115.088162)
		(width 0.1397)
		(layer "In2.Cu")
		(net "USB_P1_DP")
	)
	(segment
		(start 89.171018 -112.98555)
		(end 89.171018 -111.787686)
		(width 0.1397)
		(layer "In2.Cu")
		(net "USB_P1_DP")
	)
	(segment
		(start 85.913976 -140.607796)
		(end 87.49665 -139.025122)
		(width 0.1397)
		(layer "In2.Cu")
		(net "USB_P1_DP")
	)
	(segment
		(start 86.5378 -150.876508)
		(end 86.5378 -147.027138)
		(width 0.1397)
		(layer "In2.Cu")
		(net "USB_P1_DP")
	)
	(segment
		(start 85.913976 -146.403314)
		(end 85.913976 -140.607796)
		(width 0.1397)
		(layer "In2.Cu")
		(net "USB_P1_DP")
	)
	(segment
		(start 88.85555 -52.388516)
		(end 88.85555 -46.47565)
		(width 0.1397)
		(layer "In2.Cu")
		(net "USB_P1_DP")
	)
	(segment
		(start 88.53805 -115.088162)
		(end 88.627204 -114.999008)
		(width 0.1397)
		(layer "In2.Cu")
		(net "USB_P1_DP")
	)
	(segment
		(start 90.64625 -98.62185)
		(end 90.64625 -95.508826)
		(width 0.1397)
		(layer "In2.Cu")
		(net "USB_P1_DP")
	)
	(segment
		(start 87.7824 -152.121108)
		(end 86.5378 -150.876508)
		(width 0.1397)
		(layer "In2.Cu")
		(net "USB_P1_DP")
	)
	(segment
		(start 89.74455 -31.164276)
		(end 99.047554 -21.861272)
		(width 0.1397)
		(layer "In2.Cu")
		(net "USB_P1_DP")
	)
	(segment
		(start 89.74455 -41.797732)
		(end 89.92235 -41.619932)
		(width 0.1397)
		(layer "In2.Cu")
		(net "USB_P1_DP")
	)
	(segment
		(start 87.7824 -153.067766)
		(end 87.7824 -152.121108)
		(width 0.1397)
		(layer "In2.Cu")
		(net "USB_P1_DP")
	)
	(segment
		(start 90.22715 -53.760116)
		(end 88.85555 -52.388516)
		(width 0.1397)
		(layer "In2.Cu")
		(net "USB_P1_DP")
	)
	(segment
		(start 89.74455 -45.58665)
		(end 89.74455 -42.991532)
		(width 0.1397)
		(layer "In2.Cu")
		(net "USB_P1_DP")
	)
	(segment
		(start 88.627204 -113.529364)
		(end 89.171018 -112.98555)
		(width 0.1397)
		(layer "In2.Cu")
		(net "USB_P1_DP")
	)
	(segment
		(start 89.92235 -41.200832)
		(end 89.74455 -41.023032)
		(width 0.1397)
		(layer "In2.Cu")
		(net "USB_P1_DP")
	)
	(segment
		(start 87.386922 -134.088124)
		(end 87.386922 -131.49707)
		(width 0.1397)
		(layer "In2.Cu")
		(net "USB_P1_DP")
	)
	(segment
		(start 89.74455 -39.829232)
		(end 89.74455 -31.164276)
		(width 0.1397)
		(layer "In2.Cu")
		(net "USB_P1_DP")
	)
	(segment
		(start 87.386922 -131.49707)
		(end 87.05215 -131.162298)
		(width 0.1397)
		(layer "In2.Cu")
		(net "USB_P1_DP")
	)
	(segment
		(start 86.090506 -154.75966)
		(end 87.7824 -153.067766)
		(width 0.1397)
		(layer "In2.Cu")
		(net "USB_P1_DP")
	)
	(segment
		(start 90.07475 -94.937326)
		(end 90.07475 -94.0562)
		(width 0.1397)
		(layer "In2.Cu")
		(net "USB_P1_DP")
	)
	(segment
		(start 86.80577 -158.415228)
		(end 86.521798 -158.6992)
		(width 0.1397)
		(layer "In2.Cu")
		(net "USB_P1_DP")
	)
	(segment
		(start 86.5378 -147.027138)
		(end 85.913976 -146.403314)
		(width 0.1397)
		(layer "In2.Cu")
		(net "USB_P1_DP")
	)
	(segment
		(start 86.521798 -158.6992)
		(end 86.305136 -158.6992)
		(width 0.1397)
		(layer "In2.Cu")
		(net "USB_P1_DP")
	)
	(segment
		(start 91.25585 -99.23145)
		(end 90.64625 -98.62185)
		(width 0.1397)
		(layer "In2.Cu")
		(net "USB_P1_DP")
	)
	(segment
		(start 86.090506 -158.48457)
		(end 86.090506 -154.75966)
		(width 0.1397)
		(layer "In2.Cu")
		(net "USB_P1_DP")
	)
	(segment
		(start 90.22715 -93.9038)
		(end 90.22715 -53.760116)
		(width 0.1397)
		(layer "In2.Cu")
		(net "USB_P1_DP")
	)
	(segment
		(start 91.25585 -109.702854)
		(end 91.25585 -99.23145)
		(width 0.1397)
		(layer "In2.Cu")
		(net "USB_P1_DP")
	)
	(segment
		(start 89.92235 -42.813732)
		(end 89.92235 -42.394632)
		(width 0.1397)
		(layer "In2.Cu")
		(net "USB_P1_DP")
	)
	(segment
		(start 89.92235 -41.619932)
		(end 89.92235 -41.200832)
		(width 0.1397)
		(layer "In2.Cu")
		(net "USB_P1_DP")
	)
	(segment
		(start 87.49665 -134.197852)
		(end 87.386922 -134.088124)
		(width 0.1397)
		(layer "In2.Cu")
		(net "USB_P1_DP")
	)
	(segment
		(start 88.079834 -158.36773)
		(end 88.079834 -158.077916)
		(width 0.14605)
		(layer "F.Cu")
		(net "USB_P1_DN")
	)
	(segment
		(start 86.80577 -159.316674)
		(end 87.100918 -159.021526)
		(width 0.14605)
		(layer "F.Cu")
		(net "USB_P1_DN")
	)
	(segment
		(start 88.820498 -157.502098)
		(end 88.923876 -157.605476)
		(width 0.14605)
		(layer "F.Cu")
		(net "USB_P1_DN")
	)
	(segment
		(start 98.80473 -20.769072)
		(end 98.509582 -21.06422)
		(width 0.14605)
		(layer "F.Cu")
		(net "USB_P1_DN")
	)
	(segment
		(start 88.923876 -157.605476)
		(end 89.792556 -157.605476)
		(width 0.14605)
		(layer "F.Cu")
		(net "USB_P1_DN")
	)
	(segment
		(start 88.655652 -157.502098)
		(end 88.820498 -157.502098)
		(width 0.14605)
		(layer "F.Cu")
		(net "USB_P1_DN")
	)
	(segment
		(start 87.100918 -159.021526)
		(end 87.426038 -159.021526)
		(width 0.14605)
		(layer "F.Cu")
		(net "USB_P1_DN")
	)
	(segment
		(start 87.426038 -159.021526)
		(end 88.079834 -158.36773)
		(width 0.14605)
		(layer "F.Cu")
		(net "USB_P1_DN")
	)
	(segment
		(start 98.439732 -19.240246)
		(end 98.439732 -19.913092)
		(width 0.14605)
		(layer "F.Cu")
		(net "USB_P1_DN")
	)
	(segment
		(start 88.079834 -158.077916)
		(end 88.655652 -157.502098)
		(width 0.14605)
		(layer "F.Cu")
		(net "USB_P1_DN")
	)
	(segment
		(start 98.80473 -20.27809)
		(end 98.80473 -20.769072)
		(width 0.14605)
		(layer "F.Cu")
		(net "USB_P1_DN")
	)
	(segment
		(start 98.439732 -19.913092)
		(end 98.80473 -20.27809)
		(width 0.14605)
		(layer "F.Cu")
		(net "USB_P1_DN")
	)
	(via
		(at 98.509582 -21.06422)
		(size 0.508)
		(drill 0.254)
		(layers "F.Cu" "B.Cu")
		(net "USB_P1_DN")
	)
	(via
		(at 86.80577 -159.316674)
		(size 0.508)
		(drill 0.254)
		(layers "F.Cu" "B.Cu")
		(net "USB_P1_DN")
	)
	(segment
		(start 87.056722 -134.22503)
		(end 87.056722 -131.633976)
		(width 0.1397)
		(layer "In2.Cu")
		(net "USB_P1_DN")
	)
	(segment
		(start 89.41435 -31.02737)
		(end 98.717354 -21.724366)
		(width 0.1397)
		(layer "In2.Cu")
		(net "USB_P1_DN")
	)
	(segment
		(start 89.41435 -45.449744)
		(end 89.41435 -31.02737)
		(width 0.1397)
		(layer "In2.Cu")
		(net "USB_P1_DN")
	)
	(segment
		(start 86.518496 -159.0294)
		(end 86.16823 -159.0294)
		(width 0.1397)
		(layer "In2.Cu")
		(net "USB_P1_DN")
	)
	(segment
		(start 98.717354 -21.271992)
		(end 98.509582 -21.06422)
		(width 0.1397)
		(layer "In2.Cu")
		(net "USB_P1_DN")
	)
	(segment
		(start 85.583776 -146.54022)
		(end 85.583776 -140.47089)
		(width 0.1397)
		(layer "In2.Cu")
		(net "USB_P1_DN")
	)
	(segment
		(start 85.760306 -154.622754)
		(end 87.4522 -152.93086)
		(width 0.1397)
		(layer "In2.Cu")
		(net "USB_P1_DN")
	)
	(segment
		(start 88.297004 -114.862102)
		(end 88.297004 -113.392458)
		(width 0.1397)
		(layer "In2.Cu")
		(net "USB_P1_DN")
	)
	(segment
		(start 86.2076 -147.164044)
		(end 85.583776 -146.54022)
		(width 0.1397)
		(layer "In2.Cu")
		(net "USB_P1_DN")
	)
	(segment
		(start 86.16823 -159.0294)
		(end 85.760306 -158.621476)
		(width 0.1397)
		(layer "In2.Cu")
		(net "USB_P1_DN")
	)
	(segment
		(start 98.717354 -21.724366)
		(end 98.717354 -21.271992)
		(width 0.1397)
		(layer "In2.Cu")
		(net "USB_P1_DN")
	)
	(segment
		(start 89.89695 -53.897022)
		(end 88.52535 -52.525422)
		(width 0.1397)
		(layer "In2.Cu")
		(net "USB_P1_DN")
	)
	(segment
		(start 88.52535 -46.338744)
		(end 89.41435 -45.449744)
		(width 0.1397)
		(layer "In2.Cu")
		(net "USB_P1_DN")
	)
	(segment
		(start 88.52535 -52.525422)
		(end 88.52535 -46.338744)
		(width 0.1397)
		(layer "In2.Cu")
		(net "USB_P1_DN")
	)
	(segment
		(start 86.80577 -159.316674)
		(end 86.518496 -159.0294)
		(width 0.1397)
		(layer "In2.Cu")
		(net "USB_P1_DN")
	)
	(segment
		(start 90.92565 -99.368356)
		(end 90.31605 -98.758756)
		(width 0.1397)
		(layer "In2.Cu")
		(net "USB_P1_DN")
	)
	(segment
		(start 90.31605 -98.758756)
		(end 90.31605 -95.645732)
		(width 0.1397)
		(layer "In2.Cu")
		(net "USB_P1_DN")
	)
	(segment
		(start 89.74455 -95.074232)
		(end 89.74455 -93.919294)
		(width 0.1397)
		(layer "In2.Cu")
		(net "USB_P1_DN")
	)
	(segment
		(start 87.056722 -131.633976)
		(end 86.72195 -131.299204)
		(width 0.1397)
		(layer "In2.Cu")
		(net "USB_P1_DN")
	)
	(segment
		(start 89.74455 -93.919294)
		(end 89.89695 -93.766894)
		(width 0.1397)
		(layer "In2.Cu")
		(net "USB_P1_DN")
	)
	(segment
		(start 90.31605 -95.645732)
		(end 89.74455 -95.074232)
		(width 0.1397)
		(layer "In2.Cu")
		(net "USB_P1_DN")
	)
	(segment
		(start 86.2076 -151.013414)
		(end 86.2076 -147.164044)
		(width 0.1397)
		(layer "In2.Cu")
		(net "USB_P1_DN")
	)
	(segment
		(start 88.297004 -113.392458)
		(end 88.840818 -112.848644)
		(width 0.1397)
		(layer "In2.Cu")
		(net "USB_P1_DN")
	)
	(segment
		(start 87.4522 -152.258014)
		(end 86.2076 -151.013414)
		(width 0.1397)
		(layer "In2.Cu")
		(net "USB_P1_DN")
	)
	(segment
		(start 87.16645 -134.334758)
		(end 87.056722 -134.22503)
		(width 0.1397)
		(layer "In2.Cu")
		(net "USB_P1_DN")
	)
	(segment
		(start 87.4522 -152.93086)
		(end 87.4522 -152.258014)
		(width 0.1397)
		(layer "In2.Cu")
		(net "USB_P1_DN")
	)
	(segment
		(start 88.840818 -112.848644)
		(end 88.840818 -111.65078)
		(width 0.1397)
		(layer "In2.Cu")
		(net "USB_P1_DN")
	)
	(segment
		(start 88.20785 -123.62434)
		(end 88.20785 -114.951256)
		(width 0.1397)
		(layer "In2.Cu")
		(net "USB_P1_DN")
	)
	(segment
		(start 85.760306 -158.621476)
		(end 85.760306 -154.622754)
		(width 0.1397)
		(layer "In2.Cu")
		(net "USB_P1_DN")
	)
	(segment
		(start 89.89695 -93.766894)
		(end 89.89695 -53.897022)
		(width 0.1397)
		(layer "In2.Cu")
		(net "USB_P1_DN")
	)
	(segment
		(start 87.16645 -138.888216)
		(end 87.16645 -134.334758)
		(width 0.1397)
		(layer "In2.Cu")
		(net "USB_P1_DN")
	)
	(segment
		(start 86.72195 -131.299204)
		(end 86.72195 -125.11024)
		(width 0.1397)
		(layer "In2.Cu")
		(net "USB_P1_DN")
	)
	(segment
		(start 90.92565 -109.565948)
		(end 90.92565 -99.368356)
		(width 0.1397)
		(layer "In2.Cu")
		(net "USB_P1_DN")
	)
	(segment
		(start 88.20785 -114.951256)
		(end 88.297004 -114.862102)
		(width 0.1397)
		(layer "In2.Cu")
		(net "USB_P1_DN")
	)
	(segment
		(start 86.72195 -125.11024)
		(end 88.20785 -123.62434)
		(width 0.1397)
		(layer "In2.Cu")
		(net "USB_P1_DN")
	)
	(segment
		(start 85.583776 -140.47089)
		(end 87.16645 -138.888216)
		(width 0.1397)
		(layer "In2.Cu")
		(net "USB_P1_DN")
	)
	(segment
		(start 88.840818 -111.65078)
		(end 90.92565 -109.565948)
		(width 0.1397)
		(layer "In2.Cu")
		(net "USB_P1_DN")
	)
	(segment
		(start 86.2076 -70.991984)
		(end 84.806028 -69.590412)
		(width 0.127)
		(layer "F.Cu")
		(net "USB_OCS_N1")
	)
	(segment
		(start 90.59672 -149.634956)
		(end 91.718892 -149.634956)
		(width 0.127)
		(layer "F.Cu")
		(net "USB_OCS_N1")
	)
	(segment
		(start 54.09946 -142.600426)
		(end 53.699918 -142.999968)
		(width 0.127)
		(layer "F.Cu")
		(net "USB_OCS_N1")
	)
	(segment
		(start 91.72448 -149.640544)
		(end 92.108528 -149.640544)
		(width 0.127)
		(layer "F.Cu")
		(net "USB_OCS_N1")
	)
	(segment
		(start 89.408 -27.686)
		(end 89.916 -28.194)
		(width 0.127)
		(layer "F.Cu")
		(net "USB_OCS_N1")
	)
	(segment
		(start 89.0016 -99.9998)
		(end 88.265 -99.9998)
		(width 0.127)
		(layer "F.Cu")
		(net "USB_OCS_N1")
	)
	(segment
		(start 88.265 -99.9998)
		(end 86.2076 -97.9424)
		(width 0.127)
		(layer "F.Cu")
		(net "USB_OCS_N1")
	)
	(segment
		(start 92.25153 -150.951946)
		(end 92.25153 -152.73528)
		(width 0.127)
		(layer "F.Cu")
		(net "USB_OCS_N1")
	)
	(segment
		(start 89.916 -28.194)
		(end 89.916 -28.51404)
		(width 0.127)
		(layer "F.Cu")
		(net "USB_OCS_N1")
	)
	(segment
		(start 86.2076 -97.9424)
		(end 86.2076 -70.991984)
		(width 0.127)
		(layer "F.Cu")
		(net "USB_OCS_N1")
	)
	(segment
		(start 91.718892 -149.634956)
		(end 91.72448 -149.640544)
		(width 0.127)
		(layer "F.Cu")
		(net "USB_OCS_N1")
	)
	(segment
		(start 92.5322 -150.5966)
		(end 92.5322 -150.671276)
		(width 0.127)
		(layer "F.Cu")
		(net "USB_OCS_N1")
	)
	(segment
		(start 92.5322 -150.064216)
		(end 92.5322 -150.5966)
		(width 0.127)
		(layer "F.Cu")
		(net "USB_OCS_N1")
	)
	(segment
		(start 54.099714 -142.600426)
		(end 54.09946 -142.600426)
		(width 0.127)
		(layer "F.Cu")
		(net "USB_OCS_N1")
	)
	(segment
		(start 92.108528 -149.640544)
		(end 92.5322 -150.064216)
		(width 0.127)
		(layer "F.Cu")
		(net "USB_OCS_N1")
	)
	(segment
		(start 92.5322 -150.671276)
		(end 92.25153 -150.951946)
		(width 0.127)
		(layer "F.Cu")
		(net "USB_OCS_N1")
	)
	(segment
		(start 89.003632 -100.001832)
		(end 89.0016 -99.9998)
		(width 0.127)
		(layer "F.Cu")
		(net "USB_OCS_N1")
	)
	(via
		(at 87.728044 -153.643584)
		(size 0.6096)
		(drill 0.3048)
		(layers "F.Cu" "B.Cu")
		(net "USB_OCS_N1")
	)
	(via
		(at 93.1418 -115.5192)
		(size 0.508)
		(drill 0.254)
		(layers "F.Cu" "B.Cu")
		(net "USB_OCS_N1")
	)
	(via
		(at 59.3979 -140.259054)
		(size 0.508)
		(drill 0.254)
		(layers "F.Cu" "B.Cu")
		(net "USB_OCS_N1")
	)
	(via
		(at 84.806028 -69.590412)
		(size 0.508)
		(drill 0.254)
		(layers "F.Cu" "B.Cu")
		(net "USB_OCS_N1")
	)
	(via
		(at 92.5322 -150.5966)
		(size 0.508)
		(drill 0.254)
		(layers "F.Cu" "B.Cu")
		(net "USB_OCS_N1")
	)
	(via
		(at 61.552582 -150.8252)
		(size 0.508)
		(drill 0.254)
		(layers "F.Cu" "B.Cu")
		(net "USB_OCS_N1")
	)
	(via
		(at 89.003632 -100.001832)
		(size 0.508)
		(drill 0.254)
		(layers "F.Cu" "B.Cu")
		(net "USB_OCS_N1")
	)
	(via
		(at 89.408 -27.686)
		(size 0.508)
		(drill 0.254)
		(layers "F.Cu" "B.Cu")
		(net "USB_OCS_N1")
	)
	(via
		(at 54.099714 -142.600426)
		(size 0.4572)
		(drill 0.2032)
		(layers "F.Cu" "B.Cu")
		(net "USB_OCS_N1")
	)
	(segment
		(start 92.5322 -150.097744)
		(end 92.5322 -150.5966)
		(width 0.127)
		(layer "B.Cu")
		(net "USB_OCS_N1")
	)
	(segment
		(start 68.756784 -150.562818)
		(end 62.212982 -150.562818)
		(width 0.127)
		(layer "B.Cu")
		(net "USB_OCS_N1")
	)
	(segment
		(start 87.728044 -153.647902)
		(end 87.050372 -154.325574)
		(width 0.127)
		(layer "B.Cu")
		(net "USB_OCS_N1")
	)
	(segment
		(start 91.68892 -150.62708)
		(end 91.313 -151.003)
		(width 0.127)
		(layer "B.Cu")
		(net "USB_OCS_N1")
	)
	(segment
		(start 84.49437 -154.325574)
		(end 83.778344 -155.0416)
		(width 0.127)
		(layer "B.Cu")
		(net "USB_OCS_N1")
	)
	(segment
		(start 91.313 -151.003)
		(end 90.372946 -151.003)
		(width 0.127)
		(layer "B.Cu")
		(net "USB_OCS_N1")
	)
	(segment
		(start 62.212982 -150.562818)
		(end 61.9506 -150.8252)
		(width 0.127)
		(layer "B.Cu")
		(net "USB_OCS_N1")
	)
	(segment
		(start 91.68892 -149.970744)
		(end 91.68892 -150.62708)
		(width 0.127)
		(layer "B.Cu")
		(net "USB_OCS_N1")
	)
	(segment
		(start 61.9506 -150.8252)
		(end 61.552582 -150.8252)
		(width 0.127)
		(layer "B.Cu")
		(net "USB_OCS_N1")
	)
	(segment
		(start 87.732362 -153.643584)
		(end 87.728044 -153.643584)
		(width 0.127)
		(layer "B.Cu")
		(net "USB_OCS_N1")
	)
	(segment
		(start 91.68892 -149.970744)
		(end 92.4052 -149.970744)
		(width 0.127)
		(layer "B.Cu")
		(net "USB_OCS_N1")
	)
	(segment
		(start 83.778344 -155.0416)
		(end 73.235566 -155.0416)
		(width 0.127)
		(layer "B.Cu")
		(net "USB_OCS_N1")
	)
	(segment
		(start 87.050372 -154.325574)
		(end 84.49437 -154.325574)
		(width 0.127)
		(layer "B.Cu")
		(net "USB_OCS_N1")
	)
	(segment
		(start 87.728044 -153.643584)
		(end 87.728044 -153.647902)
		(width 0.127)
		(layer "B.Cu")
		(net "USB_OCS_N1")
	)
	(segment
		(start 92.4052 -149.970744)
		(end 92.5322 -150.097744)
		(width 0.127)
		(layer "B.Cu")
		(net "USB_OCS_N1")
	)
	(segment
		(start 73.235566 -155.0416)
		(end 68.756784 -150.562818)
		(width 0.127)
		(layer "B.Cu")
		(net "USB_OCS_N1")
	)
	(segment
		(start 90.372946 -151.003)
		(end 87.732362 -153.643584)
		(width 0.127)
		(layer "B.Cu")
		(net "USB_OCS_N1")
	)
	(segment
		(start 94.4499 -131.944618)
		(end 94.4499 -134.265162)
		(width 0.127)
		(layer "In2.Cu")
		(net "USB_OCS_N1")
	)
	(segment
		(start 92.8116 -145.863056)
		(end 92.8116 -148.446744)
		(width 0.127)
		(layer "In2.Cu")
		(net "USB_OCS_N1")
	)
	(segment
		(start 93.2942 -115.6716)
		(end 93.2942 -119.797068)
		(width 0.127)
		(layer "In2.Cu")
		(net "USB_OCS_N1")
	)
	(segment
		(start 94.2467 -138.532362)
		(end 94.678246 -138.963908)
		(width 0.127)
		(layer "In2.Cu")
		(net "USB_OCS_N1")
	)
	(segment
		(start 94.2467 -134.468362)
		(end 94.2467 -138.532362)
		(width 0.127)
		(layer "In2.Cu")
		(net "USB_OCS_N1")
	)
	(segment
		(start 92.8116 -148.446744)
		(end 92.4433 -148.815044)
		(width 0.127)
		(layer "In2.Cu")
		(net "USB_OCS_N1")
	)
	(segment
		(start 93.2942 -119.797068)
		(end 93.5228 -120.025668)
		(width 0.127)
		(layer "In2.Cu")
		(net "USB_OCS_N1")
	)
	(segment
		(start 94.17812 -130.077718)
		(end 94.143576 -130.112262)
		(width 0.127)
		(layer "In2.Cu")
		(net "USB_OCS_N1")
	)
	(segment
		(start 60.57519 -150.8252)
		(end 61.552582 -150.8252)
		(width 0.127)
		(layer "In2.Cu")
		(net "USB_OCS_N1")
	)
	(segment
		(start 59.755278 -140.616432)
		(end 59.755278 -142.756636)
		(width 0.127)
		(layer "In2.Cu")
		(net "USB_OCS_N1")
	)
	(segment
		(start 94.4499 -134.265162)
		(end 94.2467 -134.468362)
		(width 0.127)
		(layer "In2.Cu")
		(net "USB_OCS_N1")
	)
	(segment
		(start 94.143576 -131.638294)
		(end 94.4499 -131.944618)
		(width 0.127)
		(layer "In2.Cu")
		(net "USB_OCS_N1")
	)
	(segment
		(start 92.5322 -150.064216)
		(end 92.5322 -150.5966)
		(width 0.127)
		(layer "In2.Cu")
		(net "USB_OCS_N1")
	)
	(segment
		(start 94.678246 -138.963908)
		(end 94.678246 -143.99641)
		(width 0.127)
		(layer "In2.Cu")
		(net "USB_OCS_N1")
	)
	(segment
		(start 94.17812 -126.84252)
		(end 94.17812 -130.077718)
		(width 0.127)
		(layer "In2.Cu")
		(net "USB_OCS_N1")
	)
	(segment
		(start 59.1947 -143.317214)
		(end 59.1947 -149.44471)
		(width 0.127)
		(layer "In2.Cu")
		(net "USB_OCS_N1")
	)
	(segment
		(start 93.5228 -120.025668)
		(end 93.5228 -126.1872)
		(width 0.127)
		(layer "In2.Cu")
		(net "USB_OCS_N1")
	)
	(segment
		(start 59.1947 -149.44471)
		(end 60.57519 -150.8252)
		(width 0.127)
		(layer "In2.Cu")
		(net "USB_OCS_N1")
	)
	(segment
		(start 93.1418 -115.5192)
		(end 93.2942 -115.6716)
		(width 0.127)
		(layer "In2.Cu")
		(net "USB_OCS_N1")
	)
	(segment
		(start 59.755278 -142.756636)
		(end 59.1947 -143.317214)
		(width 0.127)
		(layer "In2.Cu")
		(net "USB_OCS_N1")
	)
	(segment
		(start 93.5228 -126.1872)
		(end 94.17812 -126.84252)
		(width 0.127)
		(layer "In2.Cu")
		(net "USB_OCS_N1")
	)
	(segment
		(start 92.4433 -149.975316)
		(end 92.5322 -150.064216)
		(width 0.127)
		(layer "In2.Cu")
		(net "USB_OCS_N1")
	)
	(segment
		(start 94.678246 -143.99641)
		(end 92.8116 -145.863056)
		(width 0.127)
		(layer "In2.Cu")
		(net "USB_OCS_N1")
	)
	(segment
		(start 92.4433 -148.815044)
		(end 92.4433 -149.975316)
		(width 0.127)
		(layer "In2.Cu")
		(net "USB_OCS_N1")
	)
	(segment
		(start 59.3979 -140.259054)
		(end 59.755278 -140.616432)
		(width 0.127)
		(layer "In2.Cu")
		(net "USB_OCS_N1")
	)
	(segment
		(start 94.143576 -130.112262)
		(end 94.143576 -131.638294)
		(width 0.127)
		(layer "In2.Cu")
		(net "USB_OCS_N1")
	)
	(segment
		(start 83.4644 -44.446444)
		(end 83.4644 -49.889156)
		(width 0.127)
		(layer "In5.Cu")
		(net "USB_OCS_N1")
	)
	(segment
		(start 93.345 -115.07343)
		(end 93.1418 -115.27663)
		(width 0.127)
		(layer "In5.Cu")
		(net "USB_OCS_N1")
	)
	(segment
		(start 55.063136 -141.39418)
		(end 54.748938 -141.39418)
		(width 0.127)
		(layer "In5.Cu")
		(net "USB_OCS_N1")
	)
	(segment
		(start 54.506114 -141.951202)
		(end 54.099714 -142.357602)
		(width 0.127)
		(layer "In5.Cu")
		(net "USB_OCS_N1")
	)
	(segment
		(start 54.506114 -141.637004)
		(end 54.506114 -141.951202)
		(width 0.127)
		(layer "In5.Cu")
		(net "USB_OCS_N1")
	)
	(segment
		(start 54.748938 -141.39418)
		(end 54.506114 -141.637004)
		(width 0.127)
		(layer "In5.Cu")
		(net "USB_OCS_N1")
	)
	(segment
		(start 89.0016 -100.003864)
		(end 89.0016 -100.1522)
		(width 0.127)
		(layer "In5.Cu")
		(net "USB_OCS_N1")
	)
	(segment
		(start 87.701374 -29.392626)
		(end 87.701374 -40.20947)
		(width 0.127)
		(layer "In5.Cu")
		(net "USB_OCS_N1")
	)
	(segment
		(start 84.051394 -59.95289)
		(end 83.5152 -60.489084)
		(width 0.127)
		(layer "In5.Cu")
		(net "USB_OCS_N1")
	)
	(segment
		(start 58.712354 -140.9446)
		(end 55.512716 -140.9446)
		(width 0.127)
		(layer "In5.Cu")
		(net "USB_OCS_N1")
	)
	(segment
		(start 93.1418 -115.27663)
		(end 93.1418 -115.5192)
		(width 0.127)
		(layer "In5.Cu")
		(net "USB_OCS_N1")
	)
	(segment
		(start 83.5152 -68.299584)
		(end 84.806028 -69.590412)
		(width 0.127)
		(layer "In5.Cu")
		(net "USB_OCS_N1")
	)
	(segment
		(start 93.345 -104.4956)
		(end 93.345 -115.07343)
		(width 0.127)
		(layer "In5.Cu")
		(net "USB_OCS_N1")
	)
	(segment
		(start 87.701374 -40.20947)
		(end 83.4644 -44.446444)
		(width 0.127)
		(layer "In5.Cu")
		(net "USB_OCS_N1")
	)
	(segment
		(start 83.5152 -60.489084)
		(end 83.5152 -68.299584)
		(width 0.127)
		(layer "In5.Cu")
		(net "USB_OCS_N1")
	)
	(segment
		(start 89.003632 -100.001832)
		(end 89.0016 -100.003864)
		(width 0.127)
		(layer "In5.Cu")
		(net "USB_OCS_N1")
	)
	(segment
		(start 54.099714 -142.357602)
		(end 54.099714 -142.600426)
		(width 0.127)
		(layer "In5.Cu")
		(net "USB_OCS_N1")
	)
	(segment
		(start 89.0016 -100.1522)
		(end 93.345 -104.4956)
		(width 0.127)
		(layer "In5.Cu")
		(net "USB_OCS_N1")
	)
	(segment
		(start 89.408 -27.686)
		(end 87.701374 -29.392626)
		(width 0.127)
		(layer "In5.Cu")
		(net "USB_OCS_N1")
	)
	(segment
		(start 59.3979 -140.259054)
		(end 58.712354 -140.9446)
		(width 0.127)
		(layer "In5.Cu")
		(net "USB_OCS_N1")
	)
	(segment
		(start 55.512716 -140.9446)
		(end 55.063136 -141.39418)
		(width 0.127)
		(layer "In5.Cu")
		(net "USB_OCS_N1")
	)
	(segment
		(start 84.051394 -50.47615)
		(end 84.051394 -59.95289)
		(width 0.127)
		(layer "In5.Cu")
		(net "USB_OCS_N1")
	)
	(segment
		(start 83.4644 -49.889156)
		(end 84.051394 -50.47615)
		(width 0.127)
		(layer "In5.Cu")
		(net "USB_OCS_N1")
	)
	(segment
		(start 42.100246 -138.599926)
		(end 42.500042 -138.999722)
		(width 0.127)
		(layer "F.Cu")
		(net "TP_BMC_GPIOR5")
	)
	(segment
		(start 42.500042 -138.999722)
		(end 42.500042 -138.999976)
		(width 0.127)
		(layer "F.Cu")
		(net "TP_BMC_GPIOR5")
	)
	(via
		(at 42.100246 -138.599926)
		(size 0.4572)
		(drill 0.2032)
		(layers "F.Cu" "B.Cu")
		(net "TP_BMC_GPIOR5")
	)
	(segment
		(start 42.493946 -138.206226)
		(end 42.100246 -138.599926)
		(width 0.127)
		(layer "B.Cu")
		(net "TP_BMC_GPIOR5")
	)
	(segment
		(start 43.050714 -138.206226)
		(end 42.493946 -138.206226)
		(width 0.127)
		(layer "B.Cu")
		(net "TP_BMC_GPIOR5")
	)
	(segment
		(start 43.331638 -137.122408)
		(end 43.293792 -137.160254)
		(width 0.127)
		(layer "B.Cu")
		(net "TP_BMC_GPIOR5")
	)
	(segment
		(start 43.293792 -137.160254)
		(end 43.293792 -137.963148)
		(width 0.127)
		(layer "B.Cu")
		(net "TP_BMC_GPIOR5")
	)
	(segment
		(start 43.293792 -137.963148)
		(end 43.050714 -138.206226)
		(width 0.127)
		(layer "B.Cu")
		(net "TP_BMC_GPIOR5")
	)
	(segment
		(start 41.699942 -138.999976)
		(end 41.300146 -138.599926)
		(width 0.127)
		(layer "F.Cu")
		(net "TP_BMC_GPIOR4")
	)
	(via
		(at 41.300146 -138.599926)
		(size 0.4572)
		(drill 0.2032)
		(layers "F.Cu" "B.Cu")
		(net "TP_BMC_GPIOR4")
	)
	(segment
		(start 40.679878 -136.439656)
		(end 40.906446 -136.666224)
		(width 0.127)
		(layer "B.Cu")
		(net "TP_BMC_GPIOR4")
	)
	(segment
		(start 40.906446 -138.206226)
		(end 41.300146 -138.599926)
		(width 0.127)
		(layer "B.Cu")
		(net "TP_BMC_GPIOR4")
	)
	(segment
		(start 40.906446 -136.666224)
		(end 40.906446 -138.206226)
		(width 0.127)
		(layer "B.Cu")
		(net "TP_BMC_GPIOR4")
	)
	(segment
		(start 40.500046 -138.600434)
		(end 40.5003 -138.600434)
		(width 0.127)
		(layer "F.Cu")
		(net "TP_BMC_GPIOR3")
	)
	(segment
		(start 40.5003 -138.600434)
		(end 40.899842 -138.999976)
		(width 0.127)
		(layer "F.Cu")
		(net "TP_BMC_GPIOR3")
	)
	(via
		(at 40.500046 -138.600434)
		(size 0.4572)
		(drill 0.2032)
		(layers "F.Cu" "B.Cu")
		(net "TP_BMC_GPIOR3")
	)
	(segment
		(start 40.500046 -138.600434)
		(end 40.095678 -138.196066)
		(width 0.127)
		(layer "B.Cu")
		(net "TP_BMC_GPIOR3")
	)
	(segment
		(start 40.095678 -138.196066)
		(end 38.381686 -138.196066)
		(width 0.127)
		(layer "B.Cu")
		(net "TP_BMC_GPIOR3")
	)
	(segment
		(start 38.381686 -138.196066)
		(end 38.055296 -137.869676)
		(width 0.127)
		(layer "B.Cu")
		(net "TP_BMC_GPIOR3")
	)
	(segment
		(start 44.099988 -140.599922)
		(end 43.699938 -140.20038)
		(width 0.127)
		(layer "F.Cu")
		(net "TP_BMC_GPIOR2")
	)
	(via
		(at 43.699938 -140.20038)
		(size 0.4572)
		(drill 0.2032)
		(layers "F.Cu" "B.Cu")
		(net "TP_BMC_GPIOR2")
	)
	(segment
		(start 44.5008 -140.97)
		(end 44.469558 -140.97)
		(width 0.127)
		(layer "B.Cu")
		(net "TP_BMC_GPIOR2")
	)
	(segment
		(start 44.469558 -140.97)
		(end 43.699938 -140.20038)
		(width 0.127)
		(layer "B.Cu")
		(net "TP_BMC_GPIOR2")
	)
	(segment
		(start 44.099988 -138.999976)
		(end 43.699938 -138.599926)
		(width 0.127)
		(layer "F.Cu")
		(net "TP_BMC_GPIOR1")
	)
	(via
		(at 43.699938 -138.599926)
		(size 0.4572)
		(drill 0.2032)
		(layers "F.Cu" "B.Cu")
		(net "TP_BMC_GPIOR1")
	)
	(segment
		(start 44.093638 -139.597638)
		(end 44.290234 -139.794234)
		(width 0.127)
		(layer "B.Cu")
		(net "TP_BMC_GPIOR1")
	)
	(segment
		(start 46.500034 -139.794234)
		(end 46.9138 -140.208)
		(width 0.127)
		(layer "B.Cu")
		(net "TP_BMC_GPIOR1")
	)
	(segment
		(start 44.290234 -139.794234)
		(end 46.500034 -139.794234)
		(width 0.127)
		(layer "B.Cu")
		(net "TP_BMC_GPIOR1")
	)
	(segment
		(start 44.093638 -138.993626)
		(end 44.093638 -139.597638)
		(width 0.127)
		(layer "B.Cu")
		(net "TP_BMC_GPIOR1")
	)
	(segment
		(start 43.699938 -138.599926)
		(end 44.093638 -138.993626)
		(width 0.127)
		(layer "B.Cu")
		(net "TP_BMC_GPIOR1")
	)
	(segment
		(start 55.755032 -143.3449)
		(end 55.299864 -143.800068)
		(width 0.127)
		(layer "F.Cu")
		(net "TP_BMC_GPIOA7")
	)
	(segment
		(start 59.069986 -141.149578)
		(end 56.874664 -143.3449)
		(width 0.127)
		(layer "F.Cu")
		(net "TP_BMC_GPIOA7")
	)
	(segment
		(start 56.874664 -143.3449)
		(end 55.755032 -143.3449)
		(width 0.127)
		(layer "F.Cu")
		(net "TP_BMC_GPIOA7")
	)
	(segment
		(start 60.44692 -141.149578)
		(end 59.069986 -141.149578)
		(width 0.127)
		(layer "F.Cu")
		(net "TP_BMC_GPIOA7")
	)
	(segment
		(start 54.899814 -143.400526)
		(end 54.500272 -143.800068)
		(width 0.127)
		(layer "F.Cu")
		(net "TP_BMC_GPIOA6")
	)
	(segment
		(start 54.500272 -143.800068)
		(end 54.500018 -143.800068)
		(width 0.127)
		(layer "F.Cu")
		(net "TP_BMC_GPIOA6")
	)
	(via
		(at 54.899814 -143.400526)
		(size 0.4572)
		(drill 0.2032)
		(layers "F.Cu" "B.Cu")
		(net "TP_BMC_GPIOA6")
	)
	(segment
		(start 55.27294 -143.0274)
		(end 54.899814 -143.400526)
		(width 0.127)
		(layer "B.Cu")
		(net "TP_BMC_GPIOA6")
	)
	(segment
		(start 55.8038 -143.0274)
		(end 55.27294 -143.0274)
		(width 0.127)
		(layer "B.Cu")
		(net "TP_BMC_GPIOA6")
	)
	(segment
		(start 52.8574 -131.2164)
		(end 53.5051 -131.8641)
		(width 0.127)
		(layer "F.Cu")
		(net "TP_BMC0_LPC_LAD3")
	)
	(segment
		(start 53.5051 -135.458962)
		(end 52.899818 -136.064244)
		(width 0.127)
		(layer "F.Cu")
		(net "TP_BMC0_LPC_LAD3")
	)
	(segment
		(start 52.899818 -136.064244)
		(end 52.899818 -136.59993)
		(width 0.127)
		(layer "F.Cu")
		(net "TP_BMC0_LPC_LAD3")
	)
	(segment
		(start 52.8574 -130.8608)
		(end 52.8574 -131.2164)
		(width 0.127)
		(layer "F.Cu")
		(net "TP_BMC0_LPC_LAD3")
	)
	(segment
		(start 53.5051 -131.8641)
		(end 53.5051 -135.458962)
		(width 0.127)
		(layer "F.Cu")
		(net "TP_BMC0_LPC_LAD3")
	)
	(segment
		(start 55.152036 -132.360162)
		(end 55.152036 -135.147812)
		(width 0.127)
		(layer "F.Cu")
		(net "TP_BMC0_LPC_LAD2")
	)
	(segment
		(start 55.152036 -135.147812)
		(end 53.699918 -136.59993)
		(width 0.127)
		(layer "F.Cu")
		(net "TP_BMC0_LPC_LAD2")
	)
	(segment
		(start 52.072032 -136.94283)
		(end 52.242212 -136.94283)
		(width 0.127)
		(layer "F.Cu")
		(net "TP_BMC0_LPC_LAD1")
	)
	(segment
		(start 51.299872 -138.199876)
		(end 51.669696 -137.830052)
		(width 0.127)
		(layer "F.Cu")
		(net "TP_BMC0_LPC_LAD1")
	)
	(segment
		(start 52.442872 -134.162292)
		(end 52.832 -133.773164)
		(width 0.127)
		(layer "F.Cu")
		(net "TP_BMC0_LPC_LAD1")
	)
	(segment
		(start 52.242212 -136.94283)
		(end 52.442872 -136.74217)
		(width 0.127)
		(layer "F.Cu")
		(net "TP_BMC0_LPC_LAD1")
	)
	(segment
		(start 51.669696 -137.345166)
		(end 52.072032 -136.94283)
		(width 0.127)
		(layer "F.Cu")
		(net "TP_BMC0_LPC_LAD1")
	)
	(segment
		(start 52.832 -133.773164)
		(end 52.832 -132.207)
		(width 0.127)
		(layer "F.Cu")
		(net "TP_BMC0_LPC_LAD1")
	)
	(segment
		(start 52.442872 -136.74217)
		(end 52.442872 -134.162292)
		(width 0.127)
		(layer "F.Cu")
		(net "TP_BMC0_LPC_LAD1")
	)
	(segment
		(start 51.669696 -137.830052)
		(end 51.669696 -137.345166)
		(width 0.127)
		(layer "F.Cu")
		(net "TP_BMC0_LPC_LAD1")
	)
	(segment
		(start 51.1175 -129.9591)
		(end 51.1175 -133.2357)
		(width 0.127)
		(layer "F.Cu")
		(net "TP_BMC0_LPC_LAD0")
	)
	(segment
		(start 50.2285 -135.043418)
		(end 51.642772 -136.45769)
		(width 0.127)
		(layer "F.Cu")
		(net "TP_BMC0_LPC_LAD0")
	)
	(segment
		(start 51.642772 -137.013442)
		(end 51.299872 -137.356342)
		(width 0.127)
		(layer "F.Cu")
		(net "TP_BMC0_LPC_LAD0")
	)
	(segment
		(start 51.642772 -136.45769)
		(end 51.642772 -137.013442)
		(width 0.127)
		(layer "F.Cu")
		(net "TP_BMC0_LPC_LAD0")
	)
	(segment
		(start 51.1175 -133.2357)
		(end 50.8762 -133.477)
		(width 0.127)
		(layer "F.Cu")
		(net "TP_BMC0_LPC_LAD0")
	)
	(segment
		(start 50.2285 -134.1247)
		(end 50.2285 -135.043418)
		(width 0.127)
		(layer "F.Cu")
		(net "TP_BMC0_LPC_LAD0")
	)
	(segment
		(start 51.299872 -137.356342)
		(end 51.299872 -137.40003)
		(width 0.127)
		(layer "F.Cu")
		(net "TP_BMC0_LPC_LAD0")
	)
	(segment
		(start 51.5112 -129.5654)
		(end 51.1175 -129.9591)
		(width 0.127)
		(layer "F.Cu")
		(net "TP_BMC0_LPC_LAD0")
	)
	(segment
		(start 50.8762 -133.477)
		(end 50.2285 -134.1247)
		(width 0.127)
		(layer "F.Cu")
		(net "TP_BMC0_LPC_LAD0")
	)
	(via
		(at 50.8762 -133.477)
		(size 0.6604)
		(drill 0.3302)
		(layers "F.Cu" "B.Cu")
		(net "TP_BMC0_LPC_LAD0")
	)
	(segment
		(start 202.527916 -103.06939)
		(end 202.527916 -101.461316)
		(width 0.127)
		(layer "F.Cu")
		(net "TEMP_2_SDA")
	)
	(segment
		(start 202.2094 -99.8855)
		(end 202.2094 -101.1428)
		(width 0.127)
		(layer "F.Cu")
		(net "TEMP_2_SDA")
	)
	(segment
		(start 202.527916 -101.461316)
		(end 202.2094 -101.1428)
		(width 0.127)
		(layer "F.Cu")
		(net "TEMP_2_SDA")
	)
	(via
		(at 202.2094 -101.1428)
		(size 0.6604)
		(drill 0.3302)
		(layers "F.Cu" "B.Cu")
		(net "TEMP_2_SDA")
	)
	(segment
		(start 203.5048 -101.1174)
		(end 203.4794 -101.1428)
		(width 0.127)
		(layer "F.Cu")
		(net "TEMP_2_SCL")
	)
	(segment
		(start 203.5048 -99.8855)
		(end 203.5048 -101.1174)
		(width 0.127)
		(layer "F.Cu")
		(net "TEMP_2_SCL")
	)
	(segment
		(start 203.178156 -101.444044)
		(end 203.4794 -101.1428)
		(width 0.127)
		(layer "F.Cu")
		(net "TEMP_2_SCL")
	)
	(segment
		(start 203.178156 -103.06939)
		(end 203.178156 -101.444044)
		(width 0.127)
		(layer "F.Cu")
		(net "TEMP_2_SCL")
	)
	(via
		(at 203.4794 -101.1428)
		(size 0.6604)
		(drill 0.3302)
		(layers "F.Cu" "B.Cu")
		(net "TEMP_2_SCL")
	)
	(segment
		(start 203.828396 -102.109524)
		(end 203.828396 -103.06939)
		(width 0.127)
		(layer "F.Cu")
		(net "TEMP_2_ALERT")
	)
	(segment
		(start 205.0034 -100.93452)
		(end 203.828396 -102.109524)
		(width 0.127)
		(layer "F.Cu")
		(net "TEMP_2_ALERT")
	)
	(segment
		(start 206.1972 -108.1532)
		(end 207.4291 -108.1532)
		(width 0.127)
		(layer "F.Cu")
		(net "TEMP_2_A2")
	)
	(segment
		(start 207.4291 -108.1532)
		(end 207.4291 -109.22)
		(width 0.127)
		(layer "F.Cu")
		(net "TEMP_2_A2")
	)
	(segment
		(start 204.851 -108.1532)
		(end 206.1972 -108.1532)
		(width 0.127)
		(layer "F.Cu")
		(net "TEMP_2_A2")
	)
	(segment
		(start 204.478636 -107.780836)
		(end 204.851 -108.1532)
		(width 0.127)
		(layer "F.Cu")
		(net "TEMP_2_A2")
	)
	(segment
		(start 204.478636 -107.17911)
		(end 204.478636 -107.780836)
		(width 0.127)
		(layer "F.Cu")
		(net "TEMP_2_A2")
	)
	(via
		(at 206.1972 -108.1532)
		(size 0.6604)
		(drill 0.3302)
		(layers "F.Cu" "B.Cu")
		(net "TEMP_2_A2")
	)
	(segment
		(start 204.216 -110.3249)
		(end 205.2574 -110.3249)
		(width 0.127)
		(layer "F.Cu")
		(net "TEMP_2_A1")
	)
	(segment
		(start 203.828396 -108.705396)
		(end 204.216 -109.093)
		(width 0.127)
		(layer "F.Cu")
		(net "TEMP_2_A1")
	)
	(segment
		(start 203.828396 -107.17911)
		(end 203.828396 -108.705396)
		(width 0.127)
		(layer "F.Cu")
		(net "TEMP_2_A1")
	)
	(segment
		(start 204.216 -110.3249)
		(end 204.216 -109.093)
		(width 0.127)
		(layer "F.Cu")
		(net "TEMP_2_A1")
	)
	(via
		(at 204.216 -109.093)
		(size 0.6604)
		(drill 0.3302)
		(layers "F.Cu" "B.Cu")
		(net "TEMP_2_A1")
	)
	(segment
		(start 202.946 -110.3249)
		(end 202.946 -109.093)
		(width 0.127)
		(layer "F.Cu")
		(net "TEMP_2_A0")
	)
	(segment
		(start 202.946 -110.3249)
		(end 201.9046 -110.3249)
		(width 0.127)
		(layer "F.Cu")
		(net "TEMP_2_A0")
	)
	(segment
		(start 203.178156 -108.860844)
		(end 202.946 -109.093)
		(width 0.127)
		(layer "F.Cu")
		(net "TEMP_2_A0")
	)
	(segment
		(start 203.178156 -107.17911)
		(end 203.178156 -108.860844)
		(width 0.127)
		(layer "F.Cu")
		(net "TEMP_2_A0")
	)
	(via
		(at 202.946 -109.093)
		(size 0.6604)
		(drill 0.3302)
		(layers "F.Cu" "B.Cu")
		(net "TEMP_2_A0")
	)
	(segment
		(start 181.1528 -100.1395)
		(end 181.1528 -101.3968)
		(width 0.127)
		(layer "F.Cu")
		(net "TEMP_1_SDA")
	)
	(segment
		(start 181.471316 -101.715316)
		(end 181.1528 -101.3968)
		(width 0.127)
		(layer "F.Cu")
		(net "TEMP_1_SDA")
	)
	(segment
		(start 181.471316 -103.32339)
		(end 181.471316 -101.715316)
		(width 0.127)
		(layer "F.Cu")
		(net "TEMP_1_SDA")
	)
	(via
		(at 181.1528 -101.3968)
		(size 0.6604)
		(drill 0.3302)
		(layers "F.Cu" "B.Cu")
		(net "TEMP_1_SDA")
	)
	(segment
		(start 182.121556 -103.32339)
		(end 182.121556 -101.698044)
		(width 0.127)
		(layer "F.Cu")
		(net "TEMP_1_SCL")
	)
	(segment
		(start 182.4482 -100.1395)
		(end 182.4482 -101.3714)
		(width 0.127)
		(layer "F.Cu")
		(net "TEMP_1_SCL")
	)
	(segment
		(start 182.121556 -101.698044)
		(end 182.4228 -101.3968)
		(width 0.127)
		(layer "F.Cu")
		(net "TEMP_1_SCL")
	)
	(segment
		(start 182.4482 -101.3714)
		(end 182.4228 -101.3968)
		(width 0.127)
		(layer "F.Cu")
		(net "TEMP_1_SCL")
	)
	(via
		(at 182.4228 -101.3968)
		(size 0.6604)
		(drill 0.3302)
		(layers "F.Cu" "B.Cu")
		(net "TEMP_1_SCL")
	)
	(segment
		(start 182.771796 -108.959396)
		(end 183.1594 -109.347)
		(width 0.127)
		(layer "F.Cu")
		(net "TEMP_1_A1")
	)
	(segment
		(start 183.1594 -110.5789)
		(end 183.1594 -109.347)
		(width 0.127)
		(layer "F.Cu")
		(net "TEMP_1_A1")
	)
	(segment
		(start 183.1594 -110.5789)
		(end 184.2008 -110.5789)
		(width 0.127)
		(layer "F.Cu")
		(net "TEMP_1_A1")
	)
	(segment
		(start 182.771796 -107.43311)
		(end 182.771796 -108.959396)
		(width 0.127)
		(layer "F.Cu")
		(net "TEMP_1_A1")
	)
	(via
		(at 183.1594 -109.347)
		(size 0.6604)
		(drill 0.3302)
		(layers "F.Cu" "B.Cu")
		(net "TEMP_1_A1")
	)
	(segment
		(start 182.121556 -107.43311)
		(end 182.121556 -109.114844)
		(width 0.127)
		(layer "F.Cu")
		(net "TEMP_1_A0")
	)
	(segment
		(start 182.121556 -109.114844)
		(end 181.8894 -109.347)
		(width 0.127)
		(layer "F.Cu")
		(net "TEMP_1_A0")
	)
	(segment
		(start 181.8894 -110.5789)
		(end 181.8894 -109.347)
		(width 0.127)
		(layer "F.Cu")
		(net "TEMP_1_A0")
	)
	(segment
		(start 181.8894 -110.5789)
		(end 180.848 -110.5789)
		(width 0.127)
		(layer "F.Cu")
		(net "TEMP_1_A0")
	)
	(via
		(at 181.8894 -109.347)
		(size 0.6604)
		(drill 0.3302)
		(layers "F.Cu" "B.Cu")
		(net "TEMP_1_A0")
	)
	(segment
		(start 72.26173 -142.670276)
		(end 72.975724 -142.670276)
		(width 0.127)
		(layer "F.Cu")
		(net "PWRBTN_OUT_N")
	)
	(segment
		(start 72.975724 -142.670276)
		(end 73.152 -142.494)
		(width 0.127)
		(layer "F.Cu")
		(net "PWRBTN_OUT_N")
	)
	(via
		(at 74.5744 -131.6736)
		(size 0.508)
		(drill 0.254)
		(layers "F.Cu" "B.Cu")
		(net "PWRBTN_OUT_N")
	)
	(via
		(at 73.152 -142.494)
		(size 0.508)
		(drill 0.254)
		(layers "F.Cu" "B.Cu")
		(net "PWRBTN_OUT_N")
	)
	(via
		(at 51.71694 -134.466838)
		(size 0.508)
		(drill 0.254)
		(layers "F.Cu" "B.Cu")
		(net "PWRBTN_OUT_N")
	)
	(segment
		(start 51.71694 -134.466838)
		(end 51.898296 -134.466838)
		(width 0.127)
		(layer "B.Cu")
		(net "PWRBTN_OUT_N")
	)
	(segment
		(start 51.898296 -134.466838)
		(end 52.648612 -135.217154)
		(width 0.127)
		(layer "B.Cu")
		(net "PWRBTN_OUT_N")
	)
	(segment
		(start 73.8632 -131.6736)
		(end 73.6092 -131.9276)
		(width 0.127)
		(layer "In2.Cu")
		(net "PWRBTN_OUT_N")
	)
	(segment
		(start 73.6092 -131.9276)
		(end 73.6092 -135.5344)
		(width 0.127)
		(layer "In2.Cu")
		(net "PWRBTN_OUT_N")
	)
	(segment
		(start 73.152 -135.9916)
		(end 73.152 -142.494)
		(width 0.127)
		(layer "In2.Cu")
		(net "PWRBTN_OUT_N")
	)
	(segment
		(start 74.5744 -131.6736)
		(end 73.8632 -131.6736)
		(width 0.127)
		(layer "In2.Cu")
		(net "PWRBTN_OUT_N")
	)
	(segment
		(start 73.6092 -135.5344)
		(end 73.152 -135.9916)
		(width 0.127)
		(layer "In2.Cu")
		(net "PWRBTN_OUT_N")
	)
	(segment
		(start 52.275994 -133.907784)
		(end 51.71694 -134.466838)
		(width 0.127)
		(layer "In5.Cu")
		(net "PWRBTN_OUT_N")
	)
	(segment
		(start 73.8632 -131.6736)
		(end 73.4822 -132.0546)
		(width 0.127)
		(layer "In5.Cu")
		(net "PWRBTN_OUT_N")
	)
	(segment
		(start 74.5744 -131.6736)
		(end 73.8632 -131.6736)
		(width 0.127)
		(layer "In5.Cu")
		(net "PWRBTN_OUT_N")
	)
	(segment
		(start 73.4822 -132.0546)
		(end 60.035694 -132.0546)
		(width 0.127)
		(layer "In5.Cu")
		(net "PWRBTN_OUT_N")
	)
	(segment
		(start 58.18251 -133.907784)
		(end 52.275994 -133.907784)
		(width 0.127)
		(layer "In5.Cu")
		(net "PWRBTN_OUT_N")
	)
	(segment
		(start 60.035694 -132.0546)
		(end 58.18251 -133.907784)
		(width 0.127)
		(layer "In5.Cu")
		(net "PWRBTN_OUT_N")
	)
	(segment
		(start 68.0593 -116.3828)
		(end 67.31 -116.3828)
		(width 0.127)
		(layer "F.Cu")
		(net "PU_IBMC_BT_HOLD_N")
	)
	(segment
		(start 66.7766 -116.9162)
		(end 65.806066 -116.9162)
		(width 0.127)
		(layer "F.Cu")
		(net "PU_IBMC_BT_HOLD_N")
	)
	(segment
		(start 67.31 -116.3828)
		(end 66.7766 -116.9162)
		(width 0.127)
		(layer "F.Cu")
		(net "PU_IBMC_BT_HOLD_N")
	)
	(segment
		(start 27.502358 -144.932654)
		(end 27.315668 -144.745964)
		(width 0.127)
		(layer "F.Cu")
		(net "PD_ZQ")
	)
	(segment
		(start 24.883364 -144.745964)
		(end 24.69896 -144.56156)
		(width 0.127)
		(layer "F.Cu")
		(net "PD_ZQ")
	)
	(segment
		(start 24.69896 -144.56156)
		(end 23.234396 -144.56156)
		(width 0.127)
		(layer "F.Cu")
		(net "PD_ZQ")
	)
	(segment
		(start 27.315668 -144.745964)
		(end 24.883364 -144.745964)
		(width 0.127)
		(layer "F.Cu")
		(net "PD_ZQ")
	)
	(segment
		(start 48.50003 -138.599926)
		(end 48.09998 -138.199876)
		(width 0.127)
		(layer "F.Cu")
		(net "PD_PERST_N")
	)
	(via
		(at 47.675546 -137.992866)
		(size 0.6096)
		(drill 0.3048)
		(layers "F.Cu" "B.Cu")
		(net "PD_PERST_N")
	)
	(via
		(at 48.50003 -138.599926)
		(size 0.4572)
		(drill 0.2032)
		(layers "F.Cu" "B.Cu")
		(net "PD_PERST_N")
	)
	(segment
		(start 48.282606 -138.599926)
		(end 47.675546 -137.992866)
		(width 0.127)
		(layer "B.Cu")
		(net "PD_PERST_N")
	)
	(segment
		(start 48.50003 -138.599926)
		(end 48.282606 -138.599926)
		(width 0.127)
		(layer "B.Cu")
		(net "PD_PERST_N")
	)
	(segment
		(start 47.571152 -136.169654)
		(end 47.571152 -137.888472)
		(width 0.127)
		(layer "B.Cu")
		(net "PD_PERST_N")
	)
	(segment
		(start 47.571152 -137.888472)
		(end 47.675546 -137.992866)
		(width 0.127)
		(layer "B.Cu")
		(net "PD_PERST_N")
	)
	(via
		(at 86.3346 -31.4198)
		(size 0.6604)
		(drill 0.3302)
		(layers "F.Cu" "B.Cu")
		(net "P5V_USB")
	)
	(segment
		(start 217.023188 -36.833556)
		(end 217.607388 -36.833556)
		(width 0.254)
		(layer "F.Cu")
		(net "P5V_STBY")
	)
	(segment
		(start 73.561448 -168.904666)
		(end 73.561448 -169.471848)
		(width 0.508)
		(layer "F.Cu")
		(net "P5V_STBY")
	)
	(segment
		(start 88.3031 -124.544074)
		(end 88.645238 -124.886212)
		(width 0.508)
		(layer "F.Cu")
		(net "P5V_STBY")
	)
	(segment
		(start 88.3031 -119.0879)
		(end 88.3031 -124.544074)
		(width 0.508)
		(layer "F.Cu")
		(net "P5V_STBY")
	)
	(segment
		(start 92.441268 -114.949732)
		(end 88.3031 -119.0879)
		(width 0.508)
		(layer "F.Cu")
		(net "P5V_STBY")
	)
	(segment
		(start 217.607388 -36.833556)
		(end 217.861388 -37.087556)
		(width 0.254)
		(layer "F.Cu")
		(net "P5V_STBY")
	)
	(segment
		(start 194.98691 -5.96011)
		(end 194.6148 -5.588)
		(width 0.3556)
		(layer "F.Cu")
		(net "P5V_STBY")
	)
	(segment
		(start 73.05548 -187.33008)
		(end 72.95388 -187.43168)
		(width 0.508)
		(layer "F.Cu")
		(net "P5V_STBY")
	)
	(segment
		(start 195.59016 -5.96011)
		(end 194.98691 -5.96011)
		(width 0.3556)
		(layer "F.Cu")
		(net "P5V_STBY")
	)
	(segment
		(start 66.802 -172.5295)
		(end 67.665092 -172.5295)
		(width 0.508)
		(layer "F.Cu")
		(net "P5V_STBY")
	)
	(segment
		(start 92.441268 -114.450114)
		(end 92.441268 -114.949732)
		(width 0.508)
		(layer "F.Cu")
		(net "P5V_STBY")
	)
	(segment
		(start 217.861388 -37.087556)
		(end 223.779588 -37.087556)
		(width 0.254)
		(layer "F.Cu")
		(net "P5V_STBY")
	)
	(segment
		(start 224.185988 -36.681156)
		(end 224.185988 -32.855662)
		(width 0.254)
		(layer "F.Cu")
		(net "P5V_STBY")
	)
	(segment
		(start 66.926714 -172.654214)
		(end 66.802 -172.5295)
		(width 0.4064)
		(layer "F.Cu")
		(net "P5V_STBY")
	)
	(segment
		(start 73.561448 -169.471848)
		(end 73.8124 -169.7228)
		(width 0.508)
		(layer "F.Cu")
		(net "P5V_STBY")
	)
	(segment
		(start 73.05548 -186.35218)
		(end 73.05548 -187.33008)
		(width 0.508)
		(layer "F.Cu")
		(net "P5V_STBY")
	)
	(segment
		(start 229.682548 -18.22831)
		(end 229.682548 -18.915888)
		(width 0.1016)
		(layer "F.Cu")
		(net "P5V_STBY")
	)
	(segment
		(start 66.926714 -174.262796)
		(end 66.926714 -172.654214)
		(width 0.4064)
		(layer "F.Cu")
		(net "P5V_STBY")
	)
	(segment
		(start 223.779588 -37.087556)
		(end 224.185988 -36.681156)
		(width 0.254)
		(layer "F.Cu")
		(net "P5V_STBY")
	)
	(segment
		(start 85.895942 -172.077888)
		(end 85.895942 -171.20489)
		(width 0.508)
		(layer "F.Cu")
		(net "P5V_STBY")
	)
	(segment
		(start 183.8452 -5.5753)
		(end 183.8452 -4.7244)
		(width 0.508)
		(layer "F.Cu")
		(net "P5V_STBY")
	)
	(segment
		(start 20.809712 -176.095406)
		(end 20.809712 -177.174906)
		(width 0.508)
		(layer "F.Cu")
		(net "P5V_STBY")
	)
	(segment
		(start 85.895942 -171.20489)
		(end 85.928454 -171.172378)
		(width 0.508)
		(layer "F.Cu")
		(net "P5V_STBY")
	)
	(via
		(at 227.9015 -24.36114)
		(size 0.7112)
		(drill 0.4064)
		(layers "F.Cu" "B.Cu")
		(net "P5V_STBY")
	)
	(via
		(at 77.635354 -50.617882)
		(size 0.508)
		(drill 0.254)
		(layers "F.Cu" "B.Cu")
		(net "P5V_STBY")
	)
	(via
		(at 194.6148 -5.588)
		(size 0.508)
		(drill 0.254)
		(layers "F.Cu" "B.Cu")
		(net "P5V_STBY")
	)
	(via
		(at 85.928454 -171.172378)
		(size 0.508)
		(drill 0.254)
		(layers "F.Cu" "B.Cu")
		(net "P5V_STBY")
	)
	(via
		(at 229.1207 -23.14194)
		(size 0.7112)
		(drill 0.4064)
		(layers "F.Cu" "B.Cu")
		(net "P5V_STBY")
	)
	(via
		(at 81.580228 -50.234596)
		(size 0.7112)
		(drill 0.4064)
		(layers "F.Cu" "B.Cu")
		(net "P5V_STBY")
	)
	(via
		(at 67.665092 -172.5295)
		(size 0.508)
		(drill 0.254)
		(layers "F.Cu" "B.Cu")
		(net "P5V_STBY")
	)
	(via
		(at 92.2274 -31.6484)
		(size 0.508)
		(drill 0.254)
		(layers "F.Cu" "B.Cu")
		(net "P5V_STBY")
	)
	(via
		(at 229.1207 -20.70354)
		(size 0.7112)
		(drill 0.4064)
		(layers "F.Cu" "B.Cu")
		(net "P5V_STBY")
	)
	(via
		(at 229.1207 -24.36114)
		(size 0.7112)
		(drill 0.4064)
		(layers "F.Cu" "B.Cu")
		(net "P5V_STBY")
	)
	(via
		(at 90.3478 -147.146518)
		(size 0.508)
		(drill 0.254)
		(layers "F.Cu" "B.Cu")
		(net "P5V_STBY")
	)
	(via
		(at 57.583832 -164.050726)
		(size 0.508)
		(drill 0.254)
		(layers "F.Cu" "B.Cu")
		(net "P5V_STBY")
	)
	(via
		(at 92.441268 -114.450114)
		(size 0.508)
		(drill 0.254)
		(layers "F.Cu" "B.Cu")
		(net "P5V_STBY")
	)
	(via
		(at 229.1207 -21.92274)
		(size 0.7112)
		(drill 0.4064)
		(layers "F.Cu" "B.Cu")
		(net "P5V_STBY")
	)
	(via
		(at 60.8076 -172.1104)
		(size 0.508)
		(drill 0.254)
		(layers "F.Cu" "B.Cu")
		(net "P5V_STBY")
	)
	(via
		(at 229.55377 -25.434798)
		(size 0.6604)
		(drill 0.3302)
		(layers "F.Cu" "B.Cu")
		(net "P5V_STBY")
	)
	(via
		(at 72.95388 -187.43168)
		(size 0.508)
		(drill 0.254)
		(layers "F.Cu" "B.Cu")
		(net "P5V_STBY")
	)
	(via
		(at 227.9015 -21.92274)
		(size 0.7112)
		(drill 0.4064)
		(layers "F.Cu" "B.Cu")
		(net "P5V_STBY")
	)
	(via
		(at 73.8124 -169.7228)
		(size 0.508)
		(drill 0.254)
		(layers "F.Cu" "B.Cu")
		(net "P5V_STBY")
	)
	(via
		(at 227.9015 -23.14194)
		(size 0.7112)
		(drill 0.4064)
		(layers "F.Cu" "B.Cu")
		(net "P5V_STBY")
	)
	(via
		(at 93.091 -31.6738)
		(size 0.508)
		(drill 0.254)
		(layers "F.Cu" "B.Cu")
		(net "P5V_STBY")
	)
	(via
		(at 69.1642 -169.0878)
		(size 0.508)
		(drill 0.254)
		(layers "F.Cu" "B.Cu")
		(net "P5V_STBY")
	)
	(via
		(at 81.580228 -51.453796)
		(size 0.7112)
		(drill 0.4064)
		(layers "F.Cu" "B.Cu")
		(net "P5V_STBY")
	)
	(via
		(at 20.809712 -177.174906)
		(size 0.508)
		(drill 0.254)
		(layers "F.Cu" "B.Cu")
		(net "P5V_STBY")
	)
	(via
		(at 183.8452 -4.7244)
		(size 0.508)
		(drill 0.254)
		(layers "F.Cu" "B.Cu")
		(net "P5V_STBY")
	)
	(via
		(at 88.645238 -124.886212)
		(size 0.508)
		(drill 0.254)
		(layers "F.Cu" "B.Cu")
		(net "P5V_STBY")
	)
	(via
		(at 227.9015 -20.70354)
		(size 0.7112)
		(drill 0.4064)
		(layers "F.Cu" "B.Cu")
		(net "P5V_STBY")
	)
	(segment
		(start 22.961346 -177.02149)
		(end 22.38121 -177.601626)
		(width 0.508)
		(layer "B.Cu")
		(net "P5V_STBY")
	)
	(segment
		(start 27.456892 -175.354488)
		(end 25.78989 -177.02149)
		(width 0.508)
		(layer "B.Cu")
		(net "P5V_STBY")
	)
	(segment
		(start 88.44661 -135.486902)
		(end 88.44661 -140.689838)
		(width 0.508)
		(layer "B.Cu")
		(net "P5V_STBY")
	)
	(segment
		(start 47.130716 -172.03928)
		(end 43.782234 -175.387762)
		(width 0.508)
		(layer "B.Cu")
		(net "P5V_STBY")
	)
	(segment
		(start 38.62832 -174.758858)
		(end 33.77692 -174.758858)
		(width 0.508)
		(layer "B.Cu")
		(net "P5V_STBY")
	)
	(segment
		(start 33.18129 -175.354488)
		(end 27.456892 -175.354488)
		(width 0.508)
		(layer "B.Cu")
		(net "P5V_STBY")
	)
	(segment
		(start 88.645238 -124.886212)
		(end 88.8746 -125.115574)
		(width 0.508)
		(layer "B.Cu")
		(net "P5V_STBY")
	)
	(segment
		(start 25.78989 -177.02149)
		(end 22.961346 -177.02149)
		(width 0.508)
		(layer "B.Cu")
		(net "P5V_STBY")
	)
	(segment
		(start 88.35136 -130.11658)
		(end 87.068406 -131.399534)
		(width 0.508)
		(layer "B.Cu")
		(net "P5V_STBY")
	)
	(segment
		(start 57.287668 -163.754562)
		(end 57.583832 -164.050726)
		(width 0.508)
		(layer "B.Cu")
		(net "P5V_STBY")
	)
	(segment
		(start 60.07608 -172.03928)
		(end 47.130716 -172.03928)
		(width 0.508)
		(layer "B.Cu")
		(net "P5V_STBY")
	)
	(segment
		(start 39.257224 -175.387762)
		(end 38.62832 -174.758858)
		(width 0.508)
		(layer "B.Cu")
		(net "P5V_STBY")
	)
	(segment
		(start 88.8746 -125.115574)
		(end 88.8746 -126.888748)
		(width 0.508)
		(layer "B.Cu")
		(net "P5V_STBY")
	)
	(segment
		(start 87.06866 -134.108952)
		(end 88.44661 -135.486902)
		(width 0.508)
		(layer "B.Cu")
		(net "P5V_STBY")
	)
	(segment
		(start 21.236432 -177.601626)
		(end 20.809712 -177.174906)
		(width 0.508)
		(layer "B.Cu")
		(net "P5V_STBY")
	)
	(segment
		(start 60.1472 -172.1104)
		(end 60.07608 -172.03928)
		(width 0.508)
		(layer "B.Cu")
		(net "P5V_STBY")
	)
	(segment
		(start 60.8076 -172.1104)
		(end 60.1472 -172.1104)
		(width 0.508)
		(layer "B.Cu")
		(net "P5V_STBY")
	)
	(segment
		(start 43.782234 -175.387762)
		(end 39.257224 -175.387762)
		(width 0.508)
		(layer "B.Cu")
		(net "P5V_STBY")
	)
	(segment
		(start 88.44661 -140.689838)
		(end 89.898982 -142.14221)
		(width 0.508)
		(layer "B.Cu")
		(net "P5V_STBY")
	)
	(segment
		(start 88.8746 -126.888748)
		(end 88.35136 -127.411988)
		(width 0.508)
		(layer "B.Cu")
		(net "P5V_STBY")
	)
	(segment
		(start 87.068406 -131.399534)
		(end 87.068406 -132.60959)
		(width 0.508)
		(layer "B.Cu")
		(net "P5V_STBY")
	)
	(segment
		(start 22.38121 -177.601626)
		(end 21.236432 -177.601626)
		(width 0.508)
		(layer "B.Cu")
		(net "P5V_STBY")
	)
	(segment
		(start 33.77692 -174.758858)
		(end 33.18129 -175.354488)
		(width 0.508)
		(layer "B.Cu")
		(net "P5V_STBY")
	)
	(segment
		(start 90.3478 -146.202146)
		(end 90.3478 -147.146518)
		(width 0.508)
		(layer "B.Cu")
		(net "P5V_STBY")
	)
	(segment
		(start 87.06866 -132.609844)
		(end 87.06866 -134.108952)
		(width 0.508)
		(layer "B.Cu")
		(net "P5V_STBY")
	)
	(segment
		(start 57.287668 -163.069524)
		(end 57.287668 -163.754562)
		(width 0.508)
		(layer "B.Cu")
		(net "P5V_STBY")
	)
	(segment
		(start 89.898982 -145.753328)
		(end 90.3478 -146.202146)
		(width 0.508)
		(layer "B.Cu")
		(net "P5V_STBY")
	)
	(segment
		(start 87.068406 -132.60959)
		(end 87.06866 -132.609844)
		(width 0.508)
		(layer "B.Cu")
		(net "P5V_STBY")
	)
	(segment
		(start 88.35136 -127.411988)
		(end 88.35136 -130.11658)
		(width 0.508)
		(layer "B.Cu")
		(net "P5V_STBY")
	)
	(segment
		(start 89.898982 -142.14221)
		(end 89.898982 -145.753328)
		(width 0.508)
		(layer "B.Cu")
		(net "P5V_STBY")
	)
	(segment
		(start 183.8452 -4.7244)
		(end 193.7512 -4.7244)
		(width 0.508)
		(layer "In2.Cu")
		(net "P5V_STBY")
	)
	(segment
		(start 75.17765 -184.215278)
		(end 75.17765 -184.897522)
		(width 0.508)
		(layer "In2.Cu")
		(net "P5V_STBY")
	)
	(segment
		(start 219.1004 -17.1196)
		(end 209.7024 -7.7216)
		(width 0.508)
		(layer "In2.Cu")
		(net "P5V_STBY")
	)
	(segment
		(start 90.4494 -152.940512)
		(end 90.492326 -152.897586)
		(width 0.508)
		(layer "In2.Cu")
		(net "P5V_STBY")
	)
	(segment
		(start 89.29751 -165.239446)
		(end 89.97696 -164.559996)
		(width 0.508)
		(layer "In2.Cu")
		(net "P5V_STBY")
	)
	(segment
		(start 74.388726 -175.783748)
		(end 73.10628 -177.066194)
		(width 0.508)
		(layer "In2.Cu")
		(net "P5V_STBY")
	)
	(segment
		(start 193.7512 -4.7244)
		(end 194.6148 -5.588)
		(width 0.508)
		(layer "In2.Cu")
		(net "P5V_STBY")
	)
	(segment
		(start 89.97696 -161.419032)
		(end 90.4494 -160.946592)
		(width 0.508)
		(layer "In2.Cu")
		(net "P5V_STBY")
	)
	(segment
		(start 198.7804 -5.588)
		(end 194.6148 -5.588)
		(width 0.508)
		(layer "In2.Cu")
		(net "P5V_STBY")
	)
	(segment
		(start 73.356216 -187.029344)
		(end 72.95388 -187.43168)
		(width 0.508)
		(layer "In2.Cu")
		(net "P5V_STBY")
	)
	(segment
		(start 73.10628 -177.066194)
		(end 73.10628 -182.143908)
		(width 0.508)
		(layer "In2.Cu")
		(net "P5V_STBY")
	)
	(segment
		(start 90.3478 -151.086566)
		(end 90.3478 -147.146518)
		(width 0.508)
		(layer "In2.Cu")
		(net "P5V_STBY")
	)
	(segment
		(start 57.583832 -168.684956)
		(end 57.583832 -164.050726)
		(width 0.508)
		(layer "In2.Cu")
		(net "P5V_STBY")
	)
	(segment
		(start 89.29751 -168.119044)
		(end 89.29751 -165.239446)
		(width 0.508)
		(layer "In2.Cu")
		(net "P5V_STBY")
	)
	(segment
		(start 69.1642 -169.0878)
		(end 68.199 -169.0878)
		(width 0.508)
		(layer "In2.Cu")
		(net "P5V_STBY")
	)
	(segment
		(start 224.31756 -17.1196)
		(end 219.1004 -17.1196)
		(width 0.508)
		(layer "In2.Cu")
		(net "P5V_STBY")
	)
	(segment
		(start 200.914 -7.7216)
		(end 198.7804 -5.588)
		(width 0.508)
		(layer "In2.Cu")
		(net "P5V_STBY")
	)
	(segment
		(start 60.8076 -171.908724)
		(end 57.583832 -168.684956)
		(width 0.508)
		(layer "In2.Cu")
		(net "P5V_STBY")
	)
	(segment
		(start 90.179906 -151.25446)
		(end 90.3478 -151.086566)
		(width 0.508)
		(layer "In2.Cu")
		(net "P5V_STBY")
	)
	(segment
		(start 90.4494 -160.946592)
		(end 90.4494 -152.940512)
		(width 0.508)
		(layer "In2.Cu")
		(net "P5V_STBY")
	)
	(segment
		(start 67.5767 -172.5295)
		(end 67.665092 -172.5295)
		(width 0.508)
		(layer "In2.Cu")
		(net "P5V_STBY")
	)
	(segment
		(start 67.0052 -170.2816)
		(end 67.0052 -171.958)
		(width 0.508)
		(layer "In2.Cu")
		(net "P5V_STBY")
	)
	(segment
		(start 90.492326 -152.897586)
		(end 90.492326 -152.349962)
		(width 0.508)
		(layer "In2.Cu")
		(net "P5V_STBY")
	)
	(segment
		(start 60.8076 -172.1104)
		(end 60.8076 -171.908724)
		(width 0.508)
		(layer "In2.Cu")
		(net "P5V_STBY")
	)
	(segment
		(start 73.356216 -186.718956)
		(end 73.356216 -187.029344)
		(width 0.508)
		(layer "In2.Cu")
		(net "P5V_STBY")
	)
	(segment
		(start 67.0052 -171.958)
		(end 67.5767 -172.5295)
		(width 0.508)
		(layer "In2.Cu")
		(net "P5V_STBY")
	)
	(segment
		(start 73.8124 -169.7228)
		(end 74.388726 -170.299126)
		(width 0.508)
		(layer "In2.Cu")
		(net "P5V_STBY")
	)
	(segment
		(start 90.492326 -152.349962)
		(end 90.179906 -152.037542)
		(width 0.508)
		(layer "In2.Cu")
		(net "P5V_STBY")
	)
	(segment
		(start 75.17765 -184.897522)
		(end 73.356216 -186.718956)
		(width 0.508)
		(layer "In2.Cu")
		(net "P5V_STBY")
	)
	(segment
		(start 209.7024 -7.7216)
		(end 200.914 -7.7216)
		(width 0.508)
		(layer "In2.Cu")
		(net "P5V_STBY")
	)
	(segment
		(start 86.2457 -171.170854)
		(end 89.29751 -168.119044)
		(width 0.508)
		(layer "In2.Cu")
		(net "P5V_STBY")
	)
	(segment
		(start 89.97696 -164.559996)
		(end 89.97696 -161.419032)
		(width 0.508)
		(layer "In2.Cu")
		(net "P5V_STBY")
	)
	(segment
		(start 74.388726 -170.299126)
		(end 74.388726 -175.783748)
		(width 0.508)
		(layer "In2.Cu")
		(net "P5V_STBY")
	)
	(segment
		(start 73.10628 -182.143908)
		(end 75.17765 -184.215278)
		(width 0.508)
		(layer "In2.Cu")
		(net "P5V_STBY")
	)
	(segment
		(start 85.928454 -171.172378)
		(end 85.929978 -171.170854)
		(width 0.508)
		(layer "In2.Cu")
		(net "P5V_STBY")
	)
	(segment
		(start 85.929978 -171.170854)
		(end 86.2457 -171.170854)
		(width 0.508)
		(layer "In2.Cu")
		(net "P5V_STBY")
	)
	(segment
		(start 90.179906 -152.037542)
		(end 90.179906 -151.25446)
		(width 0.508)
		(layer "In2.Cu")
		(net "P5V_STBY")
	)
	(segment
		(start 68.199 -169.0878)
		(end 67.0052 -170.2816)
		(width 0.508)
		(layer "In2.Cu")
		(net "P5V_STBY")
	)
	(segment
		(start 227.9015 -20.70354)
		(end 224.31756 -17.1196)
		(width 0.508)
		(layer "In2.Cu")
		(net "P5V_STBY")
	)
	(segment
		(start 79.1083 -92.510102)
		(end 79.3115 -92.306902)
		(width 0.508)
		(layer "In5.Cu")
		(net "P5V_STBY")
	)
	(segment
		(start 61.087 -171.811442)
		(end 61.087 -171.831)
		(width 0.508)
		(layer "In5.Cu")
		(net "P5V_STBY")
	)
	(segment
		(start 79.1083 -97.2312)
		(end 79.1083 -92.510102)
		(width 0.508)
		(layer "In5.Cu")
		(net "P5V_STBY")
	)
	(segment
		(start 69.91477 -169.100754)
		(end 73.190354 -169.100754)
		(width 0.508)
		(layer "In5.Cu")
		(net "P5V_STBY")
	)
	(segment
		(start 85.926422 -171.172378)
		(end 85.928454 -171.172378)
		(width 0.508)
		(layer "In5.Cu")
		(net "P5V_STBY")
	)
	(segment
		(start 67.665092 -172.5295)
		(end 66.605912 -172.5295)
		(width 0.508)
		(layer "In5.Cu")
		(net "P5V_STBY")
	)
	(segment
		(start 87.055452 -99.7331)
		(end 81.6102 -99.7331)
		(width 0.508)
		(layer "In5.Cu")
		(net "P5V_STBY")
	)
	(segment
		(start 78.295754 -50.617882)
		(end 77.635354 -50.617882)
		(width 0.508)
		(layer "In5.Cu")
		(net "P5V_STBY")
	)
	(segment
		(start 74.676 -170.5864)
		(end 78.143862 -170.5864)
		(width 0.508)
		(layer "In5.Cu")
		(net "P5V_STBY")
	)
	(segment
		(start 81.088992 -172.94098)
		(end 82.507582 -171.52239)
		(width 0.508)
		(layer "In5.Cu")
		(net "P5V_STBY")
	)
	(segment
		(start 69.901816 -169.0878)
		(end 69.91477 -169.100754)
		(width 0.508)
		(layer "In5.Cu")
		(net "P5V_STBY")
	)
	(segment
		(start 66.605912 -172.5295)
		(end 65.056512 -170.9801)
		(width 0.508)
		(layer "In5.Cu")
		(net "P5V_STBY")
	)
	(segment
		(start 73.8124 -169.7228)
		(end 74.676 -170.5864)
		(width 0.508)
		(layer "In5.Cu")
		(net "P5V_STBY")
	)
	(segment
		(start 79.3115 -92.306902)
		(end 79.3115 -58.135012)
		(width 0.508)
		(layer "In5.Cu")
		(net "P5V_STBY")
	)
	(segment
		(start 78.7654 -51.087528)
		(end 78.295754 -50.617882)
		(width 0.508)
		(layer "In5.Cu")
		(net "P5V_STBY")
	)
	(segment
		(start 73.190354 -169.100754)
		(end 73.8124 -169.7228)
		(width 0.508)
		(layer "In5.Cu")
		(net "P5V_STBY")
	)
	(segment
		(start 80.498442 -172.94098)
		(end 81.088992 -172.94098)
		(width 0.508)
		(layer "In5.Cu")
		(net "P5V_STBY")
	)
	(segment
		(start 78.143862 -170.5864)
		(end 80.498442 -172.94098)
		(width 0.508)
		(layer "In5.Cu")
		(net "P5V_STBY")
	)
	(segment
		(start 69.1642 -169.0878)
		(end 69.901816 -169.0878)
		(width 0.508)
		(layer "In5.Cu")
		(net "P5V_STBY")
	)
	(segment
		(start 65.056512 -170.9801)
		(end 61.918342 -170.9801)
		(width 0.508)
		(layer "In5.Cu")
		(net "P5V_STBY")
	)
	(segment
		(start 61.918342 -170.9801)
		(end 61.087 -171.811442)
		(width 0.508)
		(layer "In5.Cu")
		(net "P5V_STBY")
	)
	(segment
		(start 81.6102 -99.7331)
		(end 79.1083 -97.2312)
		(width 0.508)
		(layer "In5.Cu")
		(net "P5V_STBY")
	)
	(segment
		(start 78.7654 -57.588912)
		(end 78.7654 -51.087528)
		(width 0.508)
		(layer "In5.Cu")
		(net "P5V_STBY")
	)
	(segment
		(start 91.6686 -104.346248)
		(end 87.055452 -99.7331)
		(width 0.508)
		(layer "In5.Cu")
		(net "P5V_STBY")
	)
	(segment
		(start 85.57641 -171.52239)
		(end 85.926422 -171.172378)
		(width 0.508)
		(layer "In5.Cu")
		(net "P5V_STBY")
	)
	(segment
		(start 92.441268 -114.450114)
		(end 91.6686 -113.677446)
		(width 0.508)
		(layer "In5.Cu")
		(net "P5V_STBY")
	)
	(segment
		(start 79.3115 -58.135012)
		(end 78.7654 -57.588912)
		(width 0.508)
		(layer "In5.Cu")
		(net "P5V_STBY")
	)
	(segment
		(start 91.6686 -113.677446)
		(end 91.6686 -104.346248)
		(width 0.508)
		(layer "In5.Cu")
		(net "P5V_STBY")
	)
	(segment
		(start 61.087 -171.831)
		(end 60.8076 -172.1104)
		(width 0.508)
		(layer "In5.Cu")
		(net "P5V_STBY")
	)
	(segment
		(start 82.507582 -171.52239)
		(end 85.57641 -171.52239)
		(width 0.508)
		(layer "In5.Cu")
		(net "P5V_STBY")
	)
	(segment
		(start 75.25131 -150.579074)
		(end 74.401172 -150.579074)
		(width 0.508)
		(layer "F.Cu")
		(net "P3V3_STBY")
	)
	(segment
		(start 64.0461 -145.6944)
		(end 64.0461 -146.8882)
		(width 0.508)
		(layer "F.Cu")
		(net "P3V3_STBY")
	)
	(segment
		(start 58.407808 -160.769808)
		(end 58.407808 -159.98952)
		(width 0.508)
		(layer "F.Cu")
		(net "P3V3_STBY")
	)
	(segment
		(start 13.478764 -172.474636)
		(end 14.2494 -171.704)
		(width 0.508)
		(layer "F.Cu")
		(net "P3V3_STBY")
	)
	(segment
		(start 166.023036 -130.494278)
		(end 166.023036 -131.458716)
		(width 0.508)
		(layer "F.Cu")
		(net "P3V3_STBY")
	)
	(segment
		(start 61.8998 -140.2207)
		(end 61.8998 -139.5984)
		(width 0.508)
		(layer "F.Cu")
		(net "P3V3_STBY")
	)
	(segment
		(start 52.099972 -146.19986)
		(end 52.099464 -146.19986)
		(width 0.254)
		(layer "F.Cu")
		(net "P3V3_STBY")
	)
	(segment
		(start 90.75166 -158.56458)
		(end 89.84742 -158.56458)
		(width 0.3048)
		(layer "F.Cu")
		(net "P3V3_STBY")
	)
	(segment
		(start 50.899822 -140.20038)
		(end 50.899568 -140.20038)
		(width 0.3048)
		(layer "F.Cu")
		(net "P3V3_STBY")
	)
	(segment
		(start 95.0722 -176.96688)
		(end 96.42348 -176.96688)
		(width 0.3048)
		(layer "F.Cu")
		(net "P3V3_STBY")
	)
	(segment
		(start 180.848 -111.4679)
		(end 180.848 -112.2934)
		(width 0.508)
		(layer "F.Cu")
		(net "P3V3_STBY")
	)
	(segment
		(start 63.9826 -156.6799)
		(end 64.7065 -156.6799)
		(width 0.508)
		(layer "F.Cu")
		(net "P3V3_STBY")
	)
	(segment
		(start 52.099972 -145.400268)
		(end 52.099972 -145.400014)
		(width 0.3048)
		(layer "F.Cu")
		(net "P3V3_STBY")
	)
	(segment
		(start 32.2453 -134.6962)
		(end 31.3182 -134.6962)
		(width 0.508)
		(layer "F.Cu")
		(net "P3V3_STBY")
	)
	(segment
		(start 210.954874 -91.843606)
		(end 211.279486 -91.518994)
		(width 0.508)
		(layer "F.Cu")
		(net "P3V3_STBY")
	)
	(segment
		(start 85.046058 -132.233162)
		(end 85.99551 -132.233162)
		(width 0.508)
		(layer "F.Cu")
		(net "P3V3_STBY")
	)
	(segment
		(start 85.1154 -57.941718)
		(end 85.1408 -57.916318)
		(width 0.508)
		(layer "F.Cu")
		(net "P3V3_STBY")
	)
	(segment
		(start 46.44898 -130.513328)
		(end 46.847252 -130.513328)
		(width 0.508)
		(layer "F.Cu")
		(net "P3V3_STBY")
	)
	(segment
		(start 70.8152 -117.475)
		(end 69.723 -116.3828)
		(width 0.508)
		(layer "F.Cu")
		(net "P3V3_STBY")
	)
	(segment
		(start 29.8831 -158.8389)
		(end 30.3784 -158.8389)
		(width 0.508)
		(layer "F.Cu")
		(net "P3V3_STBY")
	)
	(segment
		(start 66.980308 -164.846)
		(end 66.537586 -164.846)
		(width 0.508)
		(layer "F.Cu")
		(net "P3V3_STBY")
	)
	(segment
		(start 91.308174 -123.930664)
		(end 91.308174 -124.429774)
		(width 0.508)
		(layer "F.Cu")
		(net "P3V3_STBY")
	)
	(segment
		(start 40.400732 -162.847528)
		(end 39.994332 -162.441128)
		(width 0.508)
		(layer "F.Cu")
		(net "P3V3_STBY")
	)
	(segment
		(start 50.899568 -140.20038)
		(end 50.500026 -140.599922)
		(width 0.3048)
		(layer "F.Cu")
		(net "P3V3_STBY")
	)
	(segment
		(start 81.556352 -150.711154)
		(end 81.8515 -151.006302)
		(width 0.381)
		(layer "F.Cu")
		(net "P3V3_STBY")
	)
	(segment
		(start 74.0918 -186.3471)
		(end 74.0918 -187.198)
		(width 0.508)
		(layer "F.Cu")
		(net "P3V3_STBY")
	)
	(segment
		(start 86.994238 -132.235194)
		(end 86.245954 -132.235194)
		(width 0.508)
		(layer "F.Cu")
		(net "P3V3_STBY")
	)
	(segment
		(start 71.05523 -155.452826)
		(end 71.05523 -154.432)
		(width 0.508)
		(layer "F.Cu")
		(net "P3V3_STBY")
	)
	(segment
		(start 98.3996 -139.1666)
		(end 98.3996 -139.065)
		(width 0.508)
		(layer "F.Cu")
		(net "P3V3_STBY")
	)
	(segment
		(start 74.718418 -147.921472)
		(end 75.632818 -147.921472)
		(width 0.508)
		(layer "F.Cu")
		(net "P3V3_STBY")
	)
	(segment
		(start 73.26503 -146.421602)
		(end 73.26503 -145.72107)
		(width 0.508)
		(layer "F.Cu")
		(net "P3V3_STBY")
	)
	(segment
		(start 65.11798 -143.251428)
		(end 64.885824 -143.019272)
		(width 0.508)
		(layer "F.Cu")
		(net "P3V3_STBY")
	)
	(segment
		(start 69.723 -116.3828)
		(end 68.9483 -116.3828)
		(width 0.508)
		(layer "F.Cu")
		(net "P3V3_STBY")
	)
	(segment
		(start 96.288352 -136.877552)
		(end 96.288352 -136.621774)
		(width 0.508)
		(layer "F.Cu")
		(net "P3V3_STBY")
	)
	(segment
		(start 43.27652 -131.3053)
		(end 42.23512 -131.3053)
		(width 0.508)
		(layer "F.Cu")
		(net "P3V3_STBY")
	)
	(segment
		(start 69.342 -119.4562)
		(end 69.8754 -119.9896)
		(width 0.508)
		(layer "F.Cu")
		(net "P3V3_STBY")
	)
	(segment
		(start 49.299622 -148.999702)
		(end 48.899826 -148.599906)
		(width 0.3556)
		(layer "F.Cu")
		(net "P3V3_STBY")
	)
	(segment
		(start 36.068 -129.18186)
		(end 36.06292 -129.18186)
		(width 0.508)
		(layer "F.Cu")
		(net "P3V3_STBY")
	)
	(segment
		(start 83.402424 -172.384466)
		(end 83.725258 -172.7073)
		(width 0.508)
		(layer "F.Cu")
		(net "P3V3_STBY")
	)
	(segment
		(start 88.402414 -155.60548)
		(end 89.881456 -155.60548)
		(width 0.254)
		(layer "F.Cu")
		(net "P3V3_STBY")
	)
	(segment
		(start 95.165926 -129.811526)
		(end 95.945706 -129.811526)
		(width 0.3048)
		(layer "F.Cu")
		(net "P3V3_STBY")
	)
	(segment
		(start 52.499514 -143.400526)
		(end 52.099972 -143.800068)
		(width 0.3556)
		(layer "F.Cu")
		(net "P3V3_STBY")
	)
	(segment
		(start 65.641474 -179.901596)
		(end 65.641474 -180.890926)
		(width 0.508)
		(layer "F.Cu")
		(net "P3V3_STBY")
	)
	(segment
		(start 59.11215 -167.4114)
		(end 58.801 -167.4114)
		(width 0.508)
		(layer "F.Cu")
		(net "P3V3_STBY")
	)
	(segment
		(start 46.970696 -126.320296)
		(end 47.14621 -126.49581)
		(width 0.508)
		(layer "F.Cu")
		(net "P3V3_STBY")
	)
	(segment
		(start 30.2006 -153.8478)
		(end 30.2006 -154.9146)
		(width 0.508)
		(layer "F.Cu")
		(net "P3V3_STBY")
	)
	(segment
		(start 70.8152 -118.745)
		(end 70.8152 -117.475)
		(width 0.508)
		(layer "F.Cu")
		(net "P3V3_STBY")
	)
	(segment
		(start 45.300392 -140.20038)
		(end 45.699934 -140.599922)
		(width 0.3556)
		(layer "F.Cu")
		(net "P3V3_STBY")
	)
	(segment
		(start 64.56045 -144.08404)
		(end 64.56045 -143.922242)
		(width 0.508)
		(layer "F.Cu")
		(net "P3V3_STBY")
	)
	(segment
		(start 44.100242 -142.199868)
		(end 44.099988 -142.199868)
		(width 0.3048)
		(layer "F.Cu")
		(net "P3V3_STBY")
	)
	(segment
		(start 57.58688 -159.98952)
		(end 58.407808 -159.98952)
		(width 0.508)
		(layer "F.Cu")
		(net "P3V3_STBY")
	)
	(segment
		(start 97.5106 -180.721)
		(end 97.4344 -180.7972)
		(width 0.508)
		(layer "F.Cu")
		(net "P3V3_STBY")
	)
	(segment
		(start 52.959 -124.8918)
		(end 52.92598 -124.85878)
		(width 0.508)
		(layer "F.Cu")
		(net "P3V3_STBY")
	)
	(segment
		(start 37.145468 -130.984244)
		(end 37.145468 -130.342132)
		(width 0.508)
		(layer "F.Cu")
		(net "P3V3_STBY")
	)
	(segment
		(start 92.809568 -62.359032)
		(end 92.412312 -61.961776)
		(width 0.508)
		(layer "F.Cu")
		(net "P3V3_STBY")
	)
	(segment
		(start 86.9061 -172.4533)
		(end 86.9061 -170.688)
		(width 0.508)
		(layer "F.Cu")
		(net "P3V3_STBY")
	)
	(segment
		(start 94.6658 -129.35585)
		(end 94.6658 -129.3114)
		(width 0.3048)
		(layer "F.Cu")
		(net "P3V3_STBY")
	)
	(segment
		(start 92.6084 -124.9553)
		(end 92.68968 -124.9553)
		(width 0.3556)
		(layer "F.Cu")
		(net "P3V3_STBY")
	)
	(segment
		(start 83.3755 -149.107652)
		(end 83.3755 -148.59)
		(width 0.381)
		(layer "F.Cu")
		(net "P3V3_STBY")
	)
	(segment
		(start 85.504274 -173.171104)
		(end 86.188296 -173.171104)
		(width 0.508)
		(layer "F.Cu")
		(net "P3V3_STBY")
	)
	(segment
		(start 47.9044 -176.9872)
		(end 47.879 -176.9618)
		(width 0.508)
		(layer "F.Cu")
		(net "P3V3_STBY")
	)
	(segment
		(start 31.3055 -152.146)
		(end 31.3055 -152.7429)
		(width 0.508)
		(layer "F.Cu")
		(net "P3V3_STBY")
	)
	(segment
		(start 179.7431 -107.6452)
		(end 180.6702 -107.6452)
		(width 0.508)
		(layer "F.Cu")
		(net "P3V3_STBY")
	)
	(segment
		(start 31.3055 -152.7429)
		(end 30.2006 -153.8478)
		(width 0.508)
		(layer "F.Cu")
		(net "P3V3_STBY")
	)
	(segment
		(start 37.145468 -132.000244)
		(end 37.145468 -130.984244)
		(width 0.508)
		(layer "F.Cu")
		(net "P3V3_STBY")
	)
	(segment
		(start 52.499514 -142.600426)
		(end 52.099972 -142.999968)
		(width 0.3556)
		(layer "F.Cu")
		(net "P3V3_STBY")
	)
	(segment
		(start 97.1677 -177.292)
		(end 97.1677 -179.080922)
		(width 0.508)
		(layer "F.Cu")
		(net "P3V3_STBY")
	)
	(segment
		(start 63.7921 -148.7678)
		(end 64.42075 -148.7678)
		(width 0.508)
		(layer "F.Cu")
		(net "P3V3_STBY")
	)
	(segment
		(start 47.879 -176.9618)
		(end 47.879 -176.1617)
		(width 0.508)
		(layer "F.Cu")
		(net "P3V3_STBY")
	)
	(segment
		(start 94.8436 -180.4416)
		(end 94.5134 -180.7718)
		(width 0.508)
		(layer "F.Cu")
		(net "P3V3_STBY")
	)
	(segment
		(start 51.699668 -141.00048)
		(end 51.300126 -141.400022)
		(width 0.3556)
		(layer "F.Cu")
		(net "P3V3_STBY")
	)
	(segment
		(start 94.6658 -129.3114)
		(end 95.165926 -129.811526)
		(width 0.3048)
		(layer "F.Cu")
		(net "P3V3_STBY")
	)
	(segment
		(start 97.1677 -179.080922)
		(end 97.5106 -179.423822)
		(width 0.508)
		(layer "F.Cu")
		(net "P3V3_STBY")
	)
	(segment
		(start 44.899834 -149.400006)
		(end 44.900088 -149.400006)
		(width 0.3556)
		(layer "F.Cu")
		(net "P3V3_STBY")
	)
	(segment
		(start 64.938402 -157.641798)
		(end 64.938402 -156.911802)
		(width 0.508)
		(layer "F.Cu")
		(net "P3V3_STBY")
	)
	(segment
		(start 84.309712 -172.7073)
		(end 84.494116 -172.891704)
		(width 0.508)
		(layer "F.Cu")
		(net "P3V3_STBY")
	)
	(segment
		(start 87.269828 -46.209712)
		(end 86.835488 -46.209712)
		(width 0.508)
		(layer "F.Cu")
		(net "P3V3_STBY")
	)
	(segment
		(start 86.6902 -136.1948)
		(end 87.6427 -136.1948)
		(width 0.508)
		(layer "F.Cu")
		(net "P3V3_STBY")
	)
	(segment
		(start 63.215012 -136.31164)
		(end 63.36284 -136.31164)
		(width 0.508)
		(layer "F.Cu")
		(net "P3V3_STBY")
	)
	(segment
		(start 69.0499 -124.333)
		(end 69.8246 -124.333)
		(width 0.508)
		(layer "F.Cu")
		(net "P3V3_STBY")
	)
	(segment
		(start 66.800984 -140.245084)
		(end 66.800984 -139.384278)
		(width 0.508)
		(layer "F.Cu")
		(net "P3V3_STBY")
	)
	(segment
		(start 84.494116 -172.891704)
		(end 85.224874 -172.891704)
		(width 0.508)
		(layer "F.Cu")
		(net "P3V3_STBY")
	)
	(segment
		(start 97.6122 -140.1699)
		(end 97.77349 -140.33119)
		(width 0.508)
		(layer "F.Cu")
		(net "P3V3_STBY")
	)
	(segment
		(start 64.8716 -147.193)
		(end 64.5668 -146.8882)
		(width 0.508)
		(layer "F.Cu")
		(net "P3V3_STBY")
	)
	(segment
		(start 63.734696 -158.270956)
		(end 64.309244 -158.270956)
		(width 0.508)
		(layer "F.Cu")
		(net "P3V3_STBY")
	)
	(segment
		(start 86.835488 -46.209712)
		(end 86.073488 -46.971712)
		(width 0.508)
		(layer "F.Cu")
		(net "P3V3_STBY")
	)
	(segment
		(start 201.93889 -107.17911)
		(end 201.7268 -107.3912)
		(width 0.254)
		(layer "F.Cu")
		(net "P3V3_STBY")
	)
	(segment
		(start 51.699922 -145.800318)
		(end 52.099972 -145.400268)
		(width 0.3048)
		(layer "F.Cu")
		(net "P3V3_STBY")
	)
	(segment
		(start 41.184576 -118.1862)
		(end 42.584624 -118.1862)
		(width 0.508)
		(layer "F.Cu")
		(net "P3V3_STBY")
	)
	(segment
		(start 31.950152 -132.346192)
		(end 31.457392 -132.346192)
		(width 0.508)
		(layer "F.Cu")
		(net "P3V3_STBY")
	)
	(segment
		(start 83.963002 -52.842414)
		(end 83.963002 -48.043338)
		(width 0.508)
		(layer "F.Cu")
		(net "P3V3_STBY")
	)
	(segment
		(start 47.69993 -141.00048)
		(end 48.099472 -141.400022)
		(width 0.3048)
		(layer "F.Cu")
		(net "P3V3_STBY")
	)
	(segment
		(start 44.47921 -117.795294)
		(end 45.488098 -117.795294)
		(width 0.508)
		(layer "F.Cu")
		(net "P3V3_STBY")
	)
	(segment
		(start 45.300138 -140.20038)
		(end 45.300392 -140.20038)
		(width 0.3556)
		(layer "F.Cu")
		(net "P3V3_STBY")
	)
	(segment
		(start 75.747626 -133.918706)
		(end 75.747626 -133.316726)
		(width 0.3048)
		(layer "F.Cu")
		(net "P3V3_STBY")
	)
	(segment
		(start 52.9971 -125.8062)
		(end 52.959 -125.7681)
		(width 0.508)
		(layer "F.Cu")
		(net "P3V3_STBY")
	)
	(segment
		(start 57.399936 -167.384222)
		(end 57.40654 -167.377618)
		(width 0.508)
		(layer "F.Cu")
		(net "P3V3_STBY")
	)
	(segment
		(start 96.7486 -177.292)
		(end 97.1677 -177.292)
		(width 0.3048)
		(layer "F.Cu")
		(net "P3V3_STBY")
	)
	(segment
		(start 191.7192 -134.7343)
		(end 191.7192 -135.636)
		(width 0.508)
		(layer "F.Cu")
		(net "P3V3_STBY")
	)
	(segment
		(start 59.944 -163.2331)
		(end 59.944 -164.1094)
		(width 0.508)
		(layer "F.Cu")
		(net "P3V3_STBY")
	)
	(segment
		(start 86.671404 -136.176004)
		(end 86.6902 -136.1948)
		(width 0.508)
		(layer "F.Cu")
		(net "P3V3_STBY")
	)
	(segment
		(start 44.500292 -140.20038)
		(end 44.899834 -140.599922)
		(width 0.3556)
		(layer "F.Cu")
		(net "P3V3_STBY")
	)
	(segment
		(start 84.201 -53.080412)
		(end 83.963002 -52.842414)
		(width 0.508)
		(layer "F.Cu")
		(net "P3V3_STBY")
	)
	(segment
		(start 46.358302 -119.34952)
		(end 47.493428 -119.34952)
		(width 0.508)
		(layer "F.Cu")
		(net "P3V3_STBY")
	)
	(segment
		(start 166.021512 -131.46024)
		(end 165.187884 -132.293868)
		(width 0.508)
		(layer "F.Cu")
		(net "P3V3_STBY")
	)
	(segment
		(start 92.68968 -124.9553)
		(end 93.14688 -125.4125)
		(width 0.3556)
		(layer "F.Cu")
		(net "P3V3_STBY")
	)
	(segment
		(start 64.0207 -145.669)
		(end 64.0461 -145.6944)
		(width 0.508)
		(layer "F.Cu")
		(net "P3V3_STBY")
	)
	(segment
		(start 98.676206 -139.443206)
		(end 98.3996 -139.1666)
		(width 0.508)
		(layer "F.Cu")
		(net "P3V3_STBY")
	)
	(segment
		(start 70.6501 -163.721288)
		(end 70.6501 -164.684202)
		(width 0.508)
		(layer "F.Cu")
		(net "P3V3_STBY")
	)
	(segment
		(start 73.26503 -145.72107)
		(end 73.42378 -145.56232)
		(width 0.508)
		(layer "F.Cu")
		(net "P3V3_STBY")
	)
	(segment
		(start 76.7842 -147.828)
		(end 75.72629 -147.828)
		(width 0.508)
		(layer "F.Cu")
		(net "P3V3_STBY")
	)
	(segment
		(start 75.475084 -52.95011)
		(end 77.295502 -52.95011)
		(width 0.508)
		(layer "F.Cu")
		(net "P3V3_STBY")
	)
	(segment
		(start 39.994332 -162.441128)
		(end 39.994332 -161.869628)
		(width 0.508)
		(layer "F.Cu")
		(net "P3V3_STBY")
	)
	(segment
		(start 69.8246 -124.333)
		(end 70.0278 -124.5362)
		(width 0.508)
		(layer "F.Cu")
		(net "P3V3_STBY")
	)
	(segment
		(start 88.343994 -128.989074)
		(end 87.587074 -128.989074)
		(width 0.508)
		(layer "F.Cu")
		(net "P3V3_STBY")
	)
	(segment
		(start 12.2428 -172.474636)
		(end 13.478764 -172.474636)
		(width 0.508)
		(layer "F.Cu")
		(net "P3V3_STBY")
	)
	(segment
		(start 68.89496 -175.9839)
		(end 68.89496 -177.53584)
		(width 0.4064)
		(layer "F.Cu")
		(net "P3V3_STBY")
	)
	(segment
		(start 52.280058 -174.994824)
		(end 52.280058 -176.53)
		(width 0.508)
		(layer "F.Cu")
		(net "P3V3_STBY")
	)
	(segment
		(start 75.25131 -150.579074)
		(end 75.25131 -150.196296)
		(width 0.508)
		(layer "F.Cu")
		(net "P3V3_STBY")
	)
	(segment
		(start 29.5656 -159.1564)
		(end 29.8831 -158.8389)
		(width 0.508)
		(layer "F.Cu")
		(net "P3V3_STBY")
	)
	(segment
		(start 82.210148 -152.146)
		(end 81.8515 -152.146)
		(width 0.508)
		(layer "F.Cu")
		(net "P3V3_STBY")
	)
	(segment
		(start 72.0344 -136.980676)
		(end 73.69683 -136.980676)
		(width 0.508)
		(layer "F.Cu")
		(net "P3V3_STBY")
	)
	(segment
		(start 58.7502 -161.1122)
		(end 58.407808 -160.769808)
		(width 0.508)
		(layer "F.Cu")
		(net "P3V3_STBY")
	)
	(segment
		(start 66.7258 -118.1862)
		(end 67.2592 -118.7196)
		(width 0.508)
		(layer "F.Cu")
		(net "P3V3_STBY")
	)
	(segment
		(start 82.5246 -147.7264)
		(end 83.323176 -147.7264)
		(width 0.508)
		(layer "F.Cu")
		(net "P3V3_STBY")
	)
	(segment
		(start 46.392592 -127.763016)
		(end 45.238416 -127.763016)
		(width 0.508)
		(layer "F.Cu")
		(net "P3V3_STBY")
	)
	(segment
		(start 61.8998 -139.5984)
		(end 61.6458 -139.3444)
		(width 0.508)
		(layer "F.Cu")
		(net "P3V3_STBY")
	)
	(segment
		(start 65.829942 -164.138356)
		(end 65.532 -164.138356)
		(width 0.508)
		(layer "F.Cu")
		(net "P3V3_STBY")
	)
	(segment
		(start 74.190098 -150.368)
		(end 73.0504 -150.368)
		(width 0.508)
		(layer "F.Cu")
		(net "P3V3_STBY")
	)
	(segment
		(start 52.499768 -141.800326)
		(end 52.499514 -141.800326)
		(width 0.3556)
		(layer "F.Cu")
		(net "P3V3_STBY")
	)
	(segment
		(start 165.187884 -132.293868)
		(end 165.187884 -132.494782)
		(width 0.508)
		(layer "F.Cu")
		(net "P3V3_STBY")
	)
	(segment
		(start 44.900088 -149.400006)
		(end 45.300138 -149.800056)
		(width 0.3556)
		(layer "F.Cu")
		(net "P3V3_STBY")
	)
	(segment
		(start 72.0217 -132.6007)
		(end 72.0217 -132.7912)
		(width 0.508)
		(layer "F.Cu")
		(net "P3V3_STBY")
	)
	(segment
		(start 75.25131 -150.196296)
		(end 74.804778 -149.749764)
		(width 0.508)
		(layer "F.Cu")
		(net "P3V3_STBY")
	)
	(segment
		(start 83.963002 -48.043338)
		(end 85.034628 -46.971712)
		(width 0.508)
		(layer "F.Cu")
		(net "P3V3_STBY")
	)
	(segment
		(start 82.743548 -151.6126)
		(end 82.210148 -152.146)
		(width 0.508)
		(layer "F.Cu")
		(net "P3V3_STBY")
	)
	(segment
		(start 201.9046 -111.2139)
		(end 201.9046 -112.0394)
		(width 0.508)
		(layer "F.Cu")
		(net "P3V3_STBY")
	)
	(segment
		(start 71.9963 -133.9342)
		(end 71.9963 -132.8166)
		(width 0.508)
		(layer "F.Cu")
		(net "P3V3_STBY")
	)
	(segment
		(start 58.767218 -167.377618)
		(end 58.801 -167.4114)
		(width 0.508)
		(layer "F.Cu")
		(net "P3V3_STBY")
	)
	(segment
		(start 77.295502 -52.95011)
		(end 77.688948 -53.343556)
		(width 0.508)
		(layer "F.Cu")
		(net "P3V3_STBY")
	)
	(segment
		(start 49.299622 -148.999956)
		(end 49.299622 -148.999702)
		(width 0.3556)
		(layer "F.Cu")
		(net "P3V3_STBY")
	)
	(segment
		(start 75.72629 -147.828)
		(end 75.632818 -147.921472)
		(width 0.508)
		(layer "F.Cu")
		(net "P3V3_STBY")
	)
	(segment
		(start 208.3181 -109.22)
		(end 208.3181 -110.2106)
		(width 0.508)
		(layer "F.Cu")
		(net "P3V3_STBY")
	)
	(segment
		(start 202.527916 -107.17911)
		(end 201.93889 -107.17911)
		(width 0.254)
		(layer "F.Cu")
		(net "P3V3_STBY")
	)
	(segment
		(start 83.725258 -172.7073)
		(end 84.309712 -172.7073)
		(width 0.508)
		(layer "F.Cu")
		(net "P3V3_STBY")
	)
	(segment
		(start 64.309244 -158.270956)
		(end 64.938402 -157.641798)
		(width 0.508)
		(layer "F.Cu")
		(net "P3V3_STBY")
	)
	(segment
		(start 94.19336 -180.45176)
		(end 94.5134 -180.7718)
		(width 0.4572)
		(layer "F.Cu")
		(net "P3V3_STBY")
	)
	(segment
		(start 89.84742 -158.56458)
		(end 89.789 -158.623)
		(width 0.3048)
		(layer "F.Cu")
		(net "P3V3_STBY")
	)
	(segment
		(start 46.847252 -130.513328)
		(end 47.380398 -131.046474)
		(width 0.508)
		(layer "F.Cu")
		(net "P3V3_STBY")
	)
	(segment
		(start 63.7032 -171.6659)
		(end 64.7573 -171.6659)
		(width 0.508)
		(layer "F.Cu")
		(net "P3V3_STBY")
	)
	(segment
		(start 93.1672 -180.45176)
		(end 94.19336 -180.45176)
		(width 0.4572)
		(layer "F.Cu")
		(net "P3V3_STBY")
	)
	(segment
		(start 90.21572 -148.364956)
		(end 89.52992 -148.364956)
		(width 0.508)
		(layer "F.Cu")
		(net "P3V3_STBY")
	)
	(segment
		(start 52.959 -125.7681)
		(end 52.959 -124.8918)
		(width 0.508)
		(layer "F.Cu")
		(net "P3V3_STBY")
	)
	(segment
		(start 23.756874 -125.194314)
		(end 24.656796 -125.194314)
		(width 0.508)
		(layer "F.Cu")
		(net "P3V3_STBY")
	)
	(segment
		(start 31.457392 -132.346192)
		(end 30.7721 -131.6609)
		(width 0.508)
		(layer "F.Cu")
		(net "P3V3_STBY")
	)
	(segment
		(start 64.370204 -174.313596)
		(end 64.6684 -174.0154)
		(width 0.4064)
		(layer "F.Cu")
		(net "P3V3_STBY")
	)
	(segment
		(start 90.59672 -148.745956)
		(end 90.21572 -148.364956)
		(width 0.508)
		(layer "F.Cu")
		(net "P3V3_STBY")
	)
	(segment
		(start 95.621856 -155.60548)
		(end 97.12452 -155.60548)
		(width 0.254)
		(layer "F.Cu")
		(net "P3V3_STBY")
	)
	(segment
		(start 94.25178 -159.798004)
		(end 94.25178 -158.47568)
		(width 0.254)
		(layer "F.Cu")
		(net "P3V3_STBY")
	)
	(segment
		(start 83.323176 -147.7264)
		(end 83.3755 -147.674076)
		(width 0.508)
		(layer "F.Cu")
		(net "P3V3_STBY")
	)
	(segment
		(start 64.56045 -143.922242)
		(end 65.231264 -143.251428)
		(width 0.508)
		(layer "F.Cu")
		(net "P3V3_STBY")
	)
	(segment
		(start 52.499768 -148.20011)
		(end 52.099972 -148.599906)
		(width 0.3048)
		(layer "F.Cu")
		(net "P3V3_STBY")
	)
	(segment
		(start 65.806066 -118.1862)
		(end 66.7258 -118.1862)
		(width 0.508)
		(layer "F.Cu")
		(net "P3V3_STBY")
	)
	(segment
		(start 59.801506 -168.100756)
		(end 59.11215 -167.4114)
		(width 0.508)
		(layer "F.Cu")
		(net "P3V3_STBY")
	)
	(segment
		(start 166.023036 -131.458716)
		(end 166.021512 -131.46024)
		(width 0.508)
		(layer "F.Cu")
		(net "P3V3_STBY")
	)
	(segment
		(start 9.779 -13.5255)
		(end 9.779 -14.351)
		(width 0.508)
		(layer "F.Cu")
		(net "P3V3_STBY")
	)
	(segment
		(start 75.946 -168.0337)
		(end 75.946 -168.5798)
		(width 0.508)
		(layer "F.Cu")
		(net "P3V3_STBY")
	)
	(segment
		(start 57.3786 -160.270952)
		(end 57.3786 -160.1978)
		(width 0.508)
		(layer "F.Cu")
		(net "P3V3_STBY")
	)
	(segment
		(start 86.073488 -46.971712)
		(end 85.034628 -46.971712)
		(width 0.508)
		(layer "F.Cu")
		(net "P3V3_STBY")
	)
	(segment
		(start 93.251782 -152.73528)
		(end 93.251782 -151.401018)
		(width 0.254)
		(layer "F.Cu")
		(net "P3V3_STBY")
	)
	(segment
		(start 64.885824 -143.019272)
		(end 63.887858 -143.019272)
		(width 0.508)
		(layer "F.Cu")
		(net "P3V3_STBY")
	)
	(segment
		(start 74.804778 -149.749764)
		(end 74.599038 -149.749764)
		(width 0.508)
		(layer "F.Cu")
		(net "P3V3_STBY")
	)
	(segment
		(start 72.8218 -156.199332)
		(end 72.822562 -156.200094)
		(width 0.508)
		(layer "F.Cu")
		(net "P3V3_STBY")
	)
	(segment
		(start 67.2592 -118.7196)
		(end 67.7672 -118.2116)
		(width 0.508)
		(layer "F.Cu")
		(net "P3V3_STBY")
	)
	(segment
		(start 93.75013 -51.701446)
		(end 94.338902 -51.701446)
		(width 0.381)
		(layer "F.Cu")
		(net "P3V3_STBY")
	)
	(segment
		(start 52.499768 -144.200118)
		(end 52.099972 -144.599914)
		(width 0.3556)
		(layer "F.Cu")
		(net "P3V3_STBY")
	)
	(segment
		(start 181.471316 -107.43311)
		(end 180.88229 -107.43311)
		(width 0.254)
		(layer "F.Cu")
		(net "P3V3_STBY")
	)
	(segment
		(start 211.279486 -91.518994)
		(end 212.385402 -91.518994)
		(width 0.508)
		(layer "F.Cu")
		(net "P3V3_STBY")
	)
	(segment
		(start 83.3755 -148.59)
		(end 83.028028 -148.59)
		(width 0.508)
		(layer "F.Cu")
		(net "P3V3_STBY")
	)
	(segment
		(start 64.42075 -148.7678)
		(end 64.619632 -148.966682)
		(width 0.508)
		(layer "F.Cu")
		(net "P3V3_STBY")
	)
	(segment
		(start 97.9297 -137.7569)
		(end 97.9297 -137.4394)
		(width 0.508)
		(layer "F.Cu")
		(net "P3V3_STBY")
	)
	(segment
		(start 57.3786 -160.1978)
		(end 57.58688 -159.98952)
		(width 0.508)
		(layer "F.Cu")
		(net "P3V3_STBY")
	)
	(segment
		(start 93.27642 -62.359032)
		(end 92.809568 -62.359032)
		(width 0.508)
		(layer "F.Cu")
		(net "P3V3_STBY")
	)
	(segment
		(start 47.540418 -126.890018)
		(end 47.540418 -127.745236)
		(width 0.508)
		(layer "F.Cu")
		(net "P3V3_STBY")
	)
	(segment
		(start 68.9483 -119.4562)
		(end 69.342 -119.4562)
		(width 0.508)
		(layer "F.Cu")
		(net "P3V3_STBY")
	)
	(segment
		(start 86.188296 -173.171104)
		(end 86.9061 -172.4533)
		(width 0.508)
		(layer "F.Cu")
		(net "P3V3_STBY")
	)
	(segment
		(start 66.537586 -164.846)
		(end 65.829942 -164.138356)
		(width 0.508)
		(layer "F.Cu")
		(net "P3V3_STBY")
	)
	(segment
		(start 72.136 -172.2882)
		(end 72.136 -172.6692)
		(width 0.508)
		(layer "F.Cu")
		(net "P3V3_STBY")
	)
	(segment
		(start 73.025 -131.572)
		(end 73.025 -131.5974)
		(width 0.508)
		(layer "F.Cu")
		(net "P3V3_STBY")
	)
	(segment
		(start 46.970696 -125.272292)
		(end 46.970696 -126.320296)
		(width 0.508)
		(layer "F.Cu")
		(net "P3V3_STBY")
	)
	(segment
		(start 46.100238 -149.800056)
		(end 46.100238 -149.799802)
		(width 0.3556)
		(layer "F.Cu")
		(net "P3V3_STBY")
	)
	(segment
		(start 36.213288 -161.844228)
		(end 36.213288 -162.644328)
		(width 0.508)
		(layer "F.Cu")
		(net "P3V3_STBY")
	)
	(segment
		(start 30.2006 -155.0924)
		(end 30.061662 -155.231338)
		(width 0.508)
		(layer "F.Cu")
		(net "P3V3_STBY")
	)
	(segment
		(start 52.499514 -141.800326)
		(end 52.099972 -142.199868)
		(width 0.3556)
		(layer "F.Cu")
		(net "P3V3_STBY")
	)
	(segment
		(start 36.068 -130.0607)
		(end 36.068 -129.18186)
		(width 0.508)
		(layer "F.Cu")
		(net "P3V3_STBY")
	)
	(segment
		(start 45.300138 -149.799802)
		(end 45.699934 -149.400006)
		(width 0.3556)
		(layer "F.Cu")
		(net "P3V3_STBY")
	)
	(segment
		(start 67.0433 -140.4874)
		(end 66.800984 -140.245084)
		(width 0.508)
		(layer "F.Cu")
		(net "P3V3_STBY")
	)
	(segment
		(start 86.671404 -135.117586)
		(end 86.671404 -136.176004)
		(width 0.508)
		(layer "F.Cu")
		(net "P3V3_STBY")
	)
	(segment
		(start 59.801506 -168.317418)
		(end 59.801506 -168.100756)
		(width 0.508)
		(layer "F.Cu")
		(net "P3V3_STBY")
	)
	(segment
		(start 68.8848 -170.3832)
		(end 69.3166 -169.9514)
		(width 0.508)
		(layer "F.Cu")
		(net "P3V3_STBY")
	)
	(segment
		(start 82.5246 -148.086572)
		(end 82.5246 -147.7264)
		(width 0.508)
		(layer "F.Cu")
		(net "P3V3_STBY")
	)
	(segment
		(start 64.7827 -171.6405)
		(end 65.659 -171.6405)
		(width 0.508)
		(layer "F.Cu")
		(net "P3V3_STBY")
	)
	(segment
		(start 93.14688 -125.4125)
		(end 94.01556 -125.4125)
		(width 0.3556)
		(layer "F.Cu")
		(net "P3V3_STBY")
	)
	(segment
		(start 94.338902 -51.701446)
		(end 94.760542 -51.279806)
		(width 0.381)
		(layer "F.Cu")
		(net "P3V3_STBY")
	)
	(segment
		(start 46.348396 -131.379214)
		(end 46.348396 -130.613912)
		(width 0.508)
		(layer "F.Cu")
		(net "P3V3_STBY")
	)
	(segment
		(start 89.831926 -152.623774)
		(end 89.854532 -152.64638)
		(width 0.254)
		(layer "F.Cu")
		(net "P3V3_STBY")
	)
	(segment
		(start 97.77349 -140.33119)
		(end 98.676206 -140.33119)
		(width 0.508)
		(layer "F.Cu")
		(net "P3V3_STBY")
	)
	(segment
		(start 96.42348 -176.96688)
		(end 96.7486 -177.292)
		(width 0.3048)
		(layer "F.Cu")
		(net "P3V3_STBY")
	)
	(segment
		(start 52.499768 -143.400526)
		(end 52.499514 -143.400526)
		(width 0.3556)
		(layer "F.Cu")
		(net "P3V3_STBY")
	)
	(segment
		(start 45.300138 -149.800056)
		(end 45.300138 -149.799802)
		(width 0.3556)
		(layer "F.Cu")
		(net "P3V3_STBY")
	)
	(segment
		(start 87.587074 -128.989074)
		(end 87.5284 -128.9304)
		(width 0.508)
		(layer "F.Cu")
		(net "P3V3_STBY")
	)
	(segment
		(start 205.2574 -111.2139)
		(end 205.2574 -112.0394)
		(width 0.508)
		(layer "F.Cu")
		(net "P3V3_STBY")
	)
	(segment
		(start 72.136 -172.6692)
		(end 71.7804 -173.0248)
		(width 0.508)
		(layer "F.Cu")
		(net "P3V3_STBY")
	)
	(segment
		(start 57.40654 -167.377618)
		(end 58.767218 -167.377618)
		(width 0.508)
		(layer "F.Cu")
		(net "P3V3_STBY")
	)
	(segment
		(start 64.5668 -146.8882)
		(end 64.0461 -146.8882)
		(width 0.508)
		(layer "F.Cu")
		(net "P3V3_STBY")
	)
	(segment
		(start 69.65823 -139.546076)
		(end 68.585334 -139.546076)
		(width 0.4064)
		(layer "F.Cu")
		(net "P3V3_STBY")
	)
	(segment
		(start 89.527888 -147.574)
		(end 88.3285 -147.574)
		(width 0.508)
		(layer "F.Cu")
		(net "P3V3_STBY")
	)
	(segment
		(start 52.499768 -144.1704)
		(end 52.499768 -144.200118)
		(width 0.3556)
		(layer "F.Cu")
		(net "P3V3_STBY")
	)
	(segment
		(start 63.777114 -174.313596)
		(end 64.370204 -174.313596)
		(width 0.4064)
		(layer "F.Cu")
		(net "P3V3_STBY")
	)
	(segment
		(start 75.747626 -133.316726)
		(end 75.6539 -133.223)
		(width 0.3048)
		(layer "F.Cu")
		(net "P3V3_STBY")
	)
	(segment
		(start 47.59452 -116.78412)
		(end 48.1838 -117.3734)
		(width 0.508)
		(layer "F.Cu")
		(net "P3V3_STBY")
	)
	(segment
		(start 64.7573 -171.6659)
		(end 64.7827 -171.6405)
		(width 0.508)
		(layer "F.Cu")
		(net "P3V3_STBY")
	)
	(segment
		(start 44.500038 -140.20038)
		(end 44.500292 -140.20038)
		(width 0.3556)
		(layer "F.Cu")
		(net "P3V3_STBY")
	)
	(segment
		(start 27.559 -121.6025)
		(end 27.559 -120.777)
		(width 0.508)
		(layer "F.Cu")
		(net "P3V3_STBY")
	)
	(segment
		(start 38.321488 -161.844228)
		(end 38.321488 -162.644328)
		(width 0.508)
		(layer "F.Cu")
		(net "P3V3_STBY")
	)
	(segment
		(start 53.299614 -151.400002)
		(end 53.299614 -151.399748)
		(width 0.3048)
		(layer "F.Cu")
		(net "P3V3_STBY")
	)
	(segment
		(start 83.3755 -147.462494)
		(end 82.593688 -146.680682)
		(width 0.3048)
		(layer "F.Cu")
		(net "P3V3_STBY")
	)
	(segment
		(start 69.18325 -136.59485)
		(end 69.1134 -136.525)
		(width 0.508)
		(layer "F.Cu")
		(net "P3V3_STBY")
	)
	(segment
		(start 47.14621 -126.49581)
		(end 47.540418 -126.890018)
		(width 0.508)
		(layer "F.Cu")
		(net "P3V3_STBY")
	)
	(segment
		(start 197.485 -8.763)
		(end 196.89064 -8.16864)
		(width 0.3556)
		(layer "F.Cu")
		(net "P3V3_STBY")
	)
	(segment
		(start 70.6501 -164.684202)
		(end 71.105776 -164.684202)
		(width 0.508)
		(layer "F.Cu")
		(net "P3V3_STBY")
	)
	(segment
		(start 196.89064 -8.16864)
		(end 196.89064 -8.00989)
		(width 0.3556)
		(layer "F.Cu")
		(net "P3V3_STBY")
	)
	(segment
		(start 88.392 -155.615894)
		(end 88.402414 -155.60548)
		(width 0.254)
		(layer "F.Cu")
		(net "P3V3_STBY")
	)
	(segment
		(start 46.100238 -149.799802)
		(end 46.500034 -149.400006)
		(width 0.3556)
		(layer "F.Cu")
		(net "P3V3_STBY")
	)
	(segment
		(start 71.9963 -132.8166)
		(end 72.0217 -132.7912)
		(width 0.508)
		(layer "F.Cu")
		(net "P3V3_STBY")
	)
	(segment
		(start 85.99551 -132.233162)
		(end 86.121748 -132.3594)
		(width 0.508)
		(layer "F.Cu")
		(net "P3V3_STBY")
	)
	(segment
		(start 19.880072 -16.13027)
		(end 19.880072 -16.95577)
		(width 0.508)
		(layer "F.Cu")
		(net "P3V3_STBY")
	)
	(segment
		(start 97.5106 -179.423822)
		(end 97.5106 -180.721)
		(width 0.508)
		(layer "F.Cu")
		(net "P3V3_STBY")
	)
	(segment
		(start 63.841884 -141.468094)
		(end 63.867284 -141.493494)
		(width 0.508)
		(layer "F.Cu")
		(net "P3V3_STBY")
	)
	(segment
		(start 89.527888 -147.574)
		(end 89.527888 -148.362924)
		(width 0.508)
		(layer "F.Cu")
		(net "P3V3_STBY")
	)
	(segment
		(start 71.203566 -164.586412)
		(end 71.78548 -164.586412)
		(width 0.508)
		(layer "F.Cu")
		(net "P3V3_STBY")
	)
	(segment
		(start 68.8848 -170.8531)
		(end 68.8848 -170.3832)
		(width 0.508)
		(layer "F.Cu")
		(net "P3V3_STBY")
	)
	(segment
		(start 71.7804 -173.0248)
		(end 71.7804 -173.2661)
		(width 0.508)
		(layer "F.Cu")
		(net "P3V3_STBY")
	)
	(segment
		(start 69.08038 -182.73268)
		(end 68.20408 -182.73268)
		(width 0.508)
		(layer "F.Cu")
		(net "P3V3_STBY")
	)
	(segment
		(start 53.299614 -151.399748)
		(end 52.899818 -150.999952)
		(width 0.3048)
		(layer "F.Cu")
		(net "P3V3_STBY")
	)
	(segment
		(start 30.3022 -131.6609)
		(end 30.3022 -132.4864)
		(width 0.508)
		(layer "F.Cu")
		(net "P3V3_STBY")
	)
	(segment
		(start 165.187884 -132.494782)
		(end 165.175184 -132.507482)
		(width 0.508)
		(layer "F.Cu")
		(net "P3V3_STBY")
	)
	(segment
		(start 83.028028 -148.59)
		(end 82.5246 -148.086572)
		(width 0.508)
		(layer "F.Cu")
		(net "P3V3_STBY")
	)
	(segment
		(start 48.099472 -141.400022)
		(end 48.09998 -141.400022)
		(width 0.3048)
		(layer "F.Cu")
		(net "P3V3_STBY")
	)
	(segment
		(start 30.061662 -155.231338)
		(end 30.061662 -155.909772)
		(width 0.508)
		(layer "F.Cu")
		(net "P3V3_STBY")
	)
	(segment
		(start 48.1838 -117.3734)
		(end 48.1838 -117.729)
		(width 0.508)
		(layer "F.Cu")
		(net "P3V3_STBY")
	)
	(segment
		(start 69.18325 -137.444734)
		(end 69.18325 -136.59485)
		(width 0.508)
		(layer "F.Cu")
		(net "P3V3_STBY")
	)
	(segment
		(start 75.946 -168.5798)
		(end 75.6666 -168.8592)
		(width 0.508)
		(layer "F.Cu")
		(net "P3V3_STBY")
	)
	(segment
		(start 46.100492 -140.20038)
		(end 46.500034 -140.599922)
		(width 0.3556)
		(layer "F.Cu")
		(net "P3V3_STBY")
	)
	(segment
		(start 67.7672 -118.2116)
		(end 68.1609 -118.2116)
		(width 0.508)
		(layer "F.Cu")
		(net "P3V3_STBY")
	)
	(segment
		(start 200.7997 -107.3912)
		(end 201.7268 -107.3912)
		(width 0.508)
		(layer "F.Cu")
		(net "P3V3_STBY")
	)
	(segment
		(start 46.348396 -130.613912)
		(end 46.44898 -130.513328)
		(width 0.508)
		(layer "F.Cu")
		(net "P3V3_STBY")
	)
	(segment
		(start 95.4913 -180.4416)
		(end 94.8436 -180.4416)
		(width 0.508)
		(layer "F.Cu")
		(net "P3V3_STBY")
	)
	(segment
		(start 98.676206 -140.33119)
		(end 98.676206 -139.443206)
		(width 0.508)
		(layer "F.Cu")
		(net "P3V3_STBY")
	)
	(segment
		(start 98.3996 -139.065)
		(end 98.3996 -138.2268)
		(width 0.508)
		(layer "F.Cu")
		(net "P3V3_STBY")
	)
	(segment
		(start 85.224874 -172.891704)
		(end 85.504274 -173.171104)
		(width 0.508)
		(layer "F.Cu")
		(net "P3V3_STBY")
	)
	(segment
		(start 85.1408 -57.916318)
		(end 86.435692 -57.916318)
		(width 0.508)
		(layer "F.Cu")
		(net "P3V3_STBY")
	)
	(segment
		(start 73.025 -131.5974)
		(end 72.0217 -132.6007)
		(width 0.508)
		(layer "F.Cu")
		(net "P3V3_STBY")
	)
	(segment
		(start 83.3755 -147.674076)
		(end 83.3755 -147.462494)
		(width 0.3048)
		(layer "F.Cu")
		(net "P3V3_STBY")
	)
	(segment
		(start 46.100238 -140.20038)
		(end 46.100492 -140.20038)
		(width 0.3556)
		(layer "F.Cu")
		(net "P3V3_STBY")
	)
	(segment
		(start 82.593688 -146.680682)
		(end 81.616296 -146.680682)
		(width 0.3048)
		(layer "F.Cu")
		(net "P3V3_STBY")
	)
	(segment
		(start 59.0931 -161.1122)
		(end 58.7502 -161.1122)
		(width 0.508)
		(layer "F.Cu")
		(net "P3V3_STBY")
	)
	(segment
		(start 97.9297 -137.4394)
		(end 96.8502 -137.4394)
		(width 0.508)
		(layer "F.Cu")
		(net "P3V3_STBY")
	)
	(segment
		(start 52.099464 -146.19986)
		(end 51.699922 -145.800318)
		(width 0.254)
		(layer "F.Cu")
		(net "P3V3_STBY")
	)
	(segment
		(start 94.27972 -159.825944)
		(end 94.25178 -159.798004)
		(width 0.254)
		(layer "F.Cu")
		(net "P3V3_STBY")
	)
	(segment
		(start 45.238416 -127.763016)
		(end 44.4246 -126.9492)
		(width 0.508)
		(layer "F.Cu")
		(net "P3V3_STBY")
	)
	(segment
		(start 96.8502 -137.4394)
		(end 96.288352 -136.877552)
		(width 0.508)
		(layer "F.Cu")
		(net "P3V3_STBY")
	)
	(segment
		(start 30.3022 -132.4864)
		(end 30.3276 -132.5118)
		(width 0.508)
		(layer "F.Cu")
		(net "P3V3_STBY")
	)
	(segment
		(start 61.907674 -179.279296)
		(end 61.907674 -180.1114)
		(width 0.508)
		(layer "F.Cu")
		(net "P3V3_STBY")
	)
	(segment
		(start 63.36284 -136.31164)
		(end 64.1096 -137.0584)
		(width 0.508)
		(layer "F.Cu")
		(net "P3V3_STBY")
	)
	(segment
		(start 64.7065 -156.6799)
		(end 64.938402 -156.911802)
		(width 0.508)
		(layer "F.Cu")
		(net "P3V3_STBY")
	)
	(segment
		(start 84.1375 -150.22576)
		(end 84.1375 -149.869652)
		(width 0.381)
		(layer "F.Cu")
		(net "P3V3_STBY")
	)
	(segment
		(start 54.899814 -148.999956)
		(end 54.899814 -148.999702)
		(width 0.3556)
		(layer "F.Cu")
		(net "P3V3_STBY")
	)
	(segment
		(start 80.965548 -150.711154)
		(end 81.556352 -150.711154)
		(width 0.381)
		(layer "F.Cu")
		(net "P3V3_STBY")
	)
	(segment
		(start 63.841884 -140.7414)
		(end 63.841884 -141.468094)
		(width 0.508)
		(layer "F.Cu")
		(net "P3V3_STBY")
	)
	(segment
		(start 57.3786 -160.1978)
		(end 57.3786 -159.2961)
		(width 0.508)
		(layer "F.Cu")
		(net "P3V3_STBY")
	)
	(segment
		(start 21.851112 -176.895506)
		(end 21.851112 -176.070006)
		(width 0.508)
		(layer "F.Cu")
		(net "P3V3_STBY")
	)
	(segment
		(start 51.300126 -141.400022)
		(end 51.299872 -141.400022)
		(width 0.3556)
		(layer "F.Cu")
		(net "P3V3_STBY")
	)
	(segment
		(start 91.308174 -124.429774)
		(end 91.7575 -124.8791)
		(width 0.508)
		(layer "F.Cu")
		(net "P3V3_STBY")
	)
	(segment
		(start 180.88229 -107.43311)
		(end 180.6702 -107.6452)
		(width 0.254)
		(layer "F.Cu")
		(net "P3V3_STBY")
	)
	(segment
		(start 91.8337 -124.9553)
		(end 91.7575 -124.8791)
		(width 0.508)
		(layer "F.Cu")
		(net "P3V3_STBY")
	)
	(segment
		(start 54.899814 -148.999702)
		(end 54.500018 -148.599906)
		(width 0.3556)
		(layer "F.Cu")
		(net "P3V3_STBY")
	)
	(segment
		(start 65.231264 -143.251428)
		(end 65.11798 -143.251428)
		(width 0.508)
		(layer "F.Cu")
		(net "P3V3_STBY")
	)
	(segment
		(start 52.099972 -147.800314)
		(end 52.499768 -148.20011)
		(width 0.3048)
		(layer "F.Cu")
		(net "P3V3_STBY")
	)
	(segment
		(start 37.145468 -130.342132)
		(end 37.3126 -130.175)
		(width 0.508)
		(layer "F.Cu")
		(net "P3V3_STBY")
	)
	(segment
		(start 72.8218 -155.425394)
		(end 72.8218 -156.199332)
		(width 0.508)
		(layer "F.Cu")
		(net "P3V3_STBY")
	)
	(segment
		(start 94.669356 -129.35585)
		(end 94.6658 -129.35585)
		(width 0.3048)
		(layer "F.Cu")
		(net "P3V3_STBY")
	)
	(segment
		(start 89.854532 -152.64638)
		(end 90.75166 -152.64638)
		(width 0.254)
		(layer "F.Cu")
		(net "P3V3_STBY")
	)
	(segment
		(start 86.245954 -132.235194)
		(end 86.121748 -132.3594)
		(width 0.508)
		(layer "F.Cu")
		(net "P3V3_STBY")
	)
	(segment
		(start 74.401172 -150.579074)
		(end 74.190098 -150.368)
		(width 0.508)
		(layer "F.Cu")
		(net "P3V3_STBY")
	)
	(segment
		(start 44.499784 -141.800326)
		(end 44.100242 -142.199868)
		(width 0.3048)
		(layer "F.Cu")
		(net "P3V3_STBY")
	)
	(segment
		(start 43.27652 -130.53568)
		(end 43.27652 -131.3053)
		(width 0.508)
		(layer "F.Cu")
		(net "P3V3_STBY")
	)
	(segment
		(start 43.3578 -130.4544)
		(end 43.27652 -130.53568)
		(width 0.508)
		(layer "F.Cu")
		(net "P3V3_STBY")
	)
	(segment
		(start 89.527888 -148.362924)
		(end 89.52992 -148.364956)
		(width 0.508)
		(layer "F.Cu")
		(net "P3V3_STBY")
	)
	(segment
		(start 191.7192 -135.636)
		(end 191.4652 -135.89)
		(width 0.508)
		(layer "F.Cu")
		(net "P3V3_STBY")
	)
	(segment
		(start 67.0052 -164.821108)
		(end 66.980308 -164.846)
		(width 0.508)
		(layer "F.Cu")
		(net "P3V3_STBY")
	)
	(segment
		(start 47.493428 -119.34952)
		(end 47.931832 -118.911116)
		(width 0.508)
		(layer "F.Cu")
		(net "P3V3_STBY")
	)
	(segment
		(start 98.3996 -138.2268)
		(end 97.9297 -137.7569)
		(width 0.508)
		(layer "F.Cu")
		(net "P3V3_STBY")
	)
	(segment
		(start 84.1375 -149.869652)
		(end 83.3755 -149.107652)
		(width 0.381)
		(layer "F.Cu")
		(net "P3V3_STBY")
	)
	(segment
		(start 52.499768 -142.600426)
		(end 52.499514 -142.600426)
		(width 0.3556)
		(layer "F.Cu")
		(net "P3V3_STBY")
	)
	(segment
		(start 81.8515 -151.006302)
		(end 81.8515 -152.146)
		(width 0.381)
		(layer "F.Cu")
		(net "P3V3_STBY")
	)
	(segment
		(start 30.2006 -154.9146)
		(end 30.2006 -155.0924)
		(width 0.508)
		(layer "F.Cu")
		(net "P3V3_STBY")
	)
	(segment
		(start 92.6084 -124.9553)
		(end 91.8337 -124.9553)
		(width 0.508)
		(layer "F.Cu")
		(net "P3V3_STBY")
	)
	(segment
		(start 52.099972 -147.80006)
		(end 52.099972 -147.800314)
		(width 0.3048)
		(layer "F.Cu")
		(net "P3V3_STBY")
	)
	(segment
		(start 87.6427 -136.1948)
		(end 87.6554 -136.1821)
		(width 0.508)
		(layer "F.Cu")
		(net "P3V3_STBY")
	)
	(segment
		(start 184.2008 -111.4679)
		(end 184.2008 -112.2934)
		(width 0.508)
		(layer "F.Cu")
		(net "P3V3_STBY")
	)
	(segment
		(start 187.2615 -109.474)
		(end 188.087 -109.474)
		(width 0.508)
		(layer "F.Cu")
		(net "P3V3_STBY")
	)
	(segment
		(start 46.358302 -116.78412)
		(end 47.59452 -116.78412)
		(width 0.508)
		(layer "F.Cu")
		(net "P3V3_STBY")
	)
	(segment
		(start 30.7721 -131.6609)
		(end 30.3022 -131.6609)
		(width 0.508)
		(layer "F.Cu")
		(net "P3V3_STBY")
	)
	(segment
		(start 71.105776 -164.684202)
		(end 71.203566 -164.586412)
		(width 0.508)
		(layer "F.Cu")
		(net "P3V3_STBY")
	)
	(via
		(at 180.6702 -107.6452)
		(size 0.508)
		(drill 0.254)
		(layers "F.Cu" "B.Cu")
		(net "P3V3_STBY")
	)
	(via
		(at 85.105494 -56.534812)
		(size 0.7112)
		(drill 0.4064)
		(layers "F.Cu" "B.Cu")
		(net "P3V3_STBY")
	)
	(via
		(at 58.7248 -146.5072)
		(size 0.508)
		(drill 0.254)
		(layers "F.Cu" "B.Cu")
		(net "P3V3_STBY")
	)
	(via
		(at 52.92598 -124.85878)
		(size 0.508)
		(drill 0.254)
		(layers "F.Cu" "B.Cu")
		(net "P3V3_STBY")
	)
	(via
		(at 49.299622 -148.999956)
		(size 0.4572)
		(drill 0.2032)
		(layers "F.Cu" "B.Cu")
		(net "P3V3_STBY")
	)
	(via
		(at 75.6666 -168.8592)
		(size 0.508)
		(drill 0.254)
		(layers "F.Cu" "B.Cu")
		(net "P3V3_STBY")
	)
	(via
		(at 27.559 -120.777)
		(size 0.508)
		(drill 0.254)
		(layers "F.Cu" "B.Cu")
		(net "P3V3_STBY")
	)
	(via
		(at 68.585334 -139.546076)
		(size 0.508)
		(drill 0.254)
		(layers "F.Cu" "B.Cu")
		(net "P3V3_STBY")
	)
	(via
		(at 66.9036 -135.001)
		(size 0.508)
		(drill 0.254)
		(layers "F.Cu" "B.Cu")
		(net "P3V3_STBY")
	)
	(via
		(at 88.392 -155.615894)
		(size 0.508)
		(drill 0.254)
		(layers "F.Cu" "B.Cu")
		(net "P3V3_STBY")
	)
	(via
		(at 69.1134 -136.525)
		(size 0.508)
		(drill 0.254)
		(layers "F.Cu" "B.Cu")
		(net "P3V3_STBY")
	)
	(via
		(at 180.848 -112.2934)
		(size 0.508)
		(drill 0.254)
		(layers "F.Cu" "B.Cu")
		(net "P3V3_STBY")
	)
	(via
		(at 53.9242 -134.366)
		(size 0.508)
		(drill 0.254)
		(layers "F.Cu" "B.Cu")
		(net "P3V3_STBY")
	)
	(via
		(at 52.499768 -142.600426)
		(size 0.4572)
		(drill 0.2032)
		(layers "F.Cu" "B.Cu")
		(net "P3V3_STBY")
	)
	(via
		(at 73.42378 -145.56232)
		(size 0.508)
		(drill 0.254)
		(layers "F.Cu" "B.Cu")
		(net "P3V3_STBY")
	)
	(via
		(at 54.899814 -148.999956)
		(size 0.4572)
		(drill 0.2032)
		(layers "F.Cu" "B.Cu")
		(net "P3V3_STBY")
	)
	(via
		(at 210.954874 -91.843606)
		(size 0.508)
		(drill 0.254)
		(layers "F.Cu" "B.Cu")
		(net "P3V3_STBY")
	)
	(via
		(at 63.2968 -182.5498)
		(size 0.7112)
		(drill 0.4064)
		(layers "F.Cu" "B.Cu")
		(net "P3V3_STBY")
	)
	(via
		(at 72.8218 -155.425394)
		(size 0.508)
		(drill 0.254)
		(layers "F.Cu" "B.Cu")
		(net "P3V3_STBY")
	)
	(via
		(at 93.251782 -151.401018)
		(size 0.508)
		(drill 0.254)
		(layers "F.Cu" "B.Cu")
		(net "P3V3_STBY")
	)
	(via
		(at 53.299614 -151.400002)
		(size 0.4572)
		(drill 0.2032)
		(layers "F.Cu" "B.Cu")
		(net "P3V3_STBY")
	)
	(via
		(at 47.0662 -162.4838)
		(size 0.508)
		(drill 0.254)
		(layers "F.Cu" "B.Cu")
		(net "P3V3_STBY")
	)
	(via
		(at 24.9936 -120.1928)
		(size 0.508)
		(drill 0.254)
		(layers "F.Cu" "B.Cu")
		(net "P3V3_STBY")
	)
	(via
		(at 92.412312 -61.961776)
		(size 0.508)
		(drill 0.254)
		(layers "F.Cu" "B.Cu")
		(net "P3V3_STBY")
	)
	(via
		(at 79.2226 -130.7846)
		(size 0.508)
		(drill 0.254)
		(layers "F.Cu" "B.Cu")
		(net "P3V3_STBY")
	)
	(via
		(at 98.3996 -139.065)
		(size 0.508)
		(drill 0.254)
		(layers "F.Cu" "B.Cu")
		(net "P3V3_STBY")
	)
	(via
		(at 197.485 -8.763)
		(size 0.508)
		(drill 0.254)
		(layers "F.Cu" "B.Cu")
		(net "P3V3_STBY")
	)
	(via
		(at 42.626534 -124.028454)
		(size 0.508)
		(drill 0.254)
		(layers "F.Cu" "B.Cu")
		(net "P3V3_STBY")
	)
	(via
		(at 66.800984 -139.384278)
		(size 0.508)
		(drill 0.254)
		(layers "F.Cu" "B.Cu")
		(net "P3V3_STBY")
	)
	(via
		(at 63.2968 -187.579)
		(size 0.7112)
		(drill 0.4064)
		(layers "F.Cu" "B.Cu")
		(net "P3V3_STBY")
	)
	(via
		(at 48.133 -162.4838)
		(size 0.508)
		(drill 0.254)
		(layers "F.Cu" "B.Cu")
		(net "P3V3_STBY")
	)
	(via
		(at 76.073 -184.2516)
		(size 0.7112)
		(drill 0.4064)
		(layers "F.Cu" "B.Cu")
		(net "P3V3_STBY")
	)
	(via
		(at 206.0702 -100.5586)
		(size 0.508)
		(drill 0.254)
		(layers "F.Cu" "B.Cu")
		(net "P3V3_STBY")
	)
	(via
		(at 49.1236 -162.4838)
		(size 0.508)
		(drill 0.254)
		(layers "F.Cu" "B.Cu")
		(net "P3V3_STBY")
	)
	(via
		(at 177.36185 -111.32947)
		(size 0.7112)
		(drill 0.4064)
		(layers "F.Cu" "B.Cu")
		(net "P3V3_STBY")
	)
	(via
		(at 47.14621 -126.49581)
		(size 0.508)
		(drill 0.254)
		(layers "F.Cu" "B.Cu")
		(net "P3V3_STBY")
	)
	(via
		(at 52.499768 -143.400526)
		(size 0.4572)
		(drill 0.2032)
		(layers "F.Cu" "B.Cu")
		(net "P3V3_STBY")
	)
	(via
		(at 38.321488 -162.644328)
		(size 0.508)
		(drill 0.254)
		(layers "F.Cu" "B.Cu")
		(net "P3V3_STBY")
	)
	(via
		(at 72.0344 -136.980676)
		(size 0.508)
		(drill 0.254)
		(layers "F.Cu" "B.Cu")
		(net "P3V3_STBY")
	)
	(via
		(at 85.1154 -55.468012)
		(size 0.7112)
		(drill 0.4064)
		(layers "F.Cu" "B.Cu")
		(net "P3V3_STBY")
	)
	(via
		(at 44.4246 -126.9492)
		(size 0.508)
		(drill 0.254)
		(layers "F.Cu" "B.Cu")
		(net "P3V3_STBY")
	)
	(via
		(at 44.500038 -140.20038)
		(size 0.4572)
		(drill 0.2032)
		(layers "F.Cu" "B.Cu")
		(net "P3V3_STBY")
	)
	(via
		(at 24.656796 -125.194314)
		(size 0.508)
		(drill 0.254)
		(layers "F.Cu" "B.Cu")
		(net "P3V3_STBY")
	)
	(via
		(at 64.6684 -174.0154)
		(size 0.508)
		(drill 0.254)
		(layers "F.Cu" "B.Cu")
		(net "P3V3_STBY")
	)
	(via
		(at 47.9044 -176.9872)
		(size 0.508)
		(drill 0.254)
		(layers "F.Cu" "B.Cu")
		(net "P3V3_STBY")
	)
	(via
		(at 58.674 -145.2626)
		(size 0.508)
		(drill 0.254)
		(layers "F.Cu" "B.Cu")
		(net "P3V3_STBY")
	)
	(via
		(at 86.59368 -146.109436)
		(size 0.508)
		(drill 0.254)
		(layers "F.Cu" "B.Cu")
		(net "P3V3_STBY")
	)
	(via
		(at 64.938402 -156.911802)
		(size 0.508)
		(drill 0.254)
		(layers "F.Cu" "B.Cu")
		(net "P3V3_STBY")
	)
	(via
		(at 85.034628 -46.971712)
		(size 0.7112)
		(drill 0.4064)
		(layers "F.Cu" "B.Cu")
		(net "P3V3_STBY")
	)
	(via
		(at 74.127106 -146.861022)
		(size 0.508)
		(drill 0.254)
		(layers "F.Cu" "B.Cu")
		(net "P3V3_STBY")
	)
	(via
		(at 45.300138 -140.20038)
		(size 0.4572)
		(drill 0.2032)
		(layers "F.Cu" "B.Cu")
		(net "P3V3_STBY")
	)
	(via
		(at 85.344 -97.6376)
		(size 0.508)
		(drill 0.254)
		(layers "F.Cu" "B.Cu")
		(net "P3V3_STBY")
	)
	(via
		(at 76.7842 -147.828)
		(size 0.508)
		(drill 0.254)
		(layers "F.Cu" "B.Cu")
		(net "P3V3_STBY")
	)
	(via
		(at 37.3126 -130.175)
		(size 0.508)
		(drill 0.254)
		(layers "F.Cu" "B.Cu")
		(net "P3V3_STBY")
	)
	(via
		(at 97.386394 -146.564096)
		(size 0.508)
		(drill 0.254)
		(layers "F.Cu" "B.Cu")
		(net "P3V3_STBY")
	)
	(via
		(at 45.300138 -149.800056)
		(size 0.4572)
		(drill 0.2032)
		(layers "F.Cu" "B.Cu")
		(net "P3V3_STBY")
	)
	(via
		(at 44.9834 -162.6616)
		(size 0.508)
		(drill 0.254)
		(layers "F.Cu" "B.Cu")
		(net "P3V3_STBY")
	)
	(via
		(at 69.8754 -119.9896)
		(size 0.508)
		(drill 0.254)
		(layers "F.Cu" "B.Cu")
		(net "P3V3_STBY")
	)
	(via
		(at 72.136 -172.2882)
		(size 0.508)
		(drill 0.254)
		(layers "F.Cu" "B.Cu")
		(net "P3V3_STBY")
	)
	(via
		(at 85.40242 -95.9612)
		(size 0.508)
		(drill 0.254)
		(layers "F.Cu" "B.Cu")
		(net "P3V3_STBY")
	)
	(via
		(at 94.669356 -129.35585)
		(size 0.508)
		(drill 0.254)
		(layers "F.Cu" "B.Cu")
		(net "P3V3_STBY")
	)
	(via
		(at 69.6214 -150.114)
		(size 0.508)
		(drill 0.254)
		(layers "F.Cu" "B.Cu")
		(net "P3V3_STBY")
	)
	(via
		(at 28.631388 -125.468634)
		(size 0.508)
		(drill 0.254)
		(layers "F.Cu" "B.Cu")
		(net "P3V3_STBY")
	)
	(via
		(at 47.69993 -141.00048)
		(size 0.4572)
		(drill 0.2032)
		(layers "F.Cu" "B.Cu")
		(net "P3V3_STBY")
	)
	(via
		(at 188.087 -109.474)
		(size 0.508)
		(drill 0.254)
		(layers "F.Cu" "B.Cu")
		(net "P3V3_STBY")
	)
	(via
		(at 49.299876 -146.600164)
		(size 0.4572)
		(drill 0.2032)
		(layers "F.Cu" "B.Cu")
		(net "P3V3_STBY")
	)
	(via
		(at 97.12452 -155.60548)
		(size 0.508)
		(drill 0.254)
		(layers "F.Cu" "B.Cu")
		(net "P3V3_STBY")
	)
	(via
		(at 184.2008 -112.2934)
		(size 0.508)
		(drill 0.254)
		(layers "F.Cu" "B.Cu")
		(net "P3V3_STBY")
	)
	(via
		(at 70.199504 -145.829528)
		(size 0.508)
		(drill 0.254)
		(layers "F.Cu" "B.Cu")
		(net "P3V3_STBY")
	)
	(via
		(at 29.5656 -159.1564)
		(size 0.508)
		(drill 0.254)
		(layers "F.Cu" "B.Cu")
		(net "P3V3_STBY")
	)
	(via
		(at 59.944 -164.1094)
		(size 0.508)
		(drill 0.254)
		(layers "F.Cu" "B.Cu")
		(net "P3V3_STBY")
	)
	(via
		(at 205.2574 -112.0394)
		(size 0.508)
		(drill 0.254)
		(layers "F.Cu" "B.Cu")
		(net "P3V3_STBY")
	)
	(via
		(at 64.8716 -147.193)
		(size 0.508)
		(drill 0.254)
		(layers "F.Cu" "B.Cu")
		(net "P3V3_STBY")
	)
	(via
		(at 82.743548 -151.6126)
		(size 0.508)
		(drill 0.254)
		(layers "F.Cu" "B.Cu")
		(net "P3V3_STBY")
	)
	(via
		(at 47.931832 -118.911116)
		(size 0.508)
		(drill 0.254)
		(layers "F.Cu" "B.Cu")
		(net "P3V3_STBY")
	)
	(via
		(at 21.851112 -176.895506)
		(size 0.508)
		(drill 0.254)
		(layers "F.Cu" "B.Cu")
		(net "P3V3_STBY")
	)
	(via
		(at 50.4698 -162.4838)
		(size 0.508)
		(drill 0.254)
		(layers "F.Cu" "B.Cu")
		(net "P3V3_STBY")
	)
	(via
		(at 70.0278 -124.5362)
		(size 0.508)
		(drill 0.254)
		(layers "F.Cu" "B.Cu")
		(net "P3V3_STBY")
	)
	(via
		(at 9.779 -14.351)
		(size 0.508)
		(drill 0.254)
		(layers "F.Cu" "B.Cu")
		(net "P3V3_STBY")
	)
	(via
		(at 47.625 -133.0198)
		(size 0.508)
		(drill 0.254)
		(layers "F.Cu" "B.Cu")
		(net "P3V3_STBY")
	)
	(via
		(at 51.699668 -141.00048)
		(size 0.4572)
		(drill 0.2032)
		(layers "F.Cu" "B.Cu")
		(net "P3V3_STBY")
	)
	(via
		(at 30.2006 -154.9146)
		(size 0.508)
		(drill 0.254)
		(layers "F.Cu" "B.Cu")
		(net "P3V3_STBY")
	)
	(via
		(at 65.641474 -180.890926)
		(size 0.508)
		(drill 0.254)
		(layers "F.Cu" "B.Cu")
		(net "P3V3_STBY")
	)
	(via
		(at 201.7268 -107.3912)
		(size 0.508)
		(drill 0.254)
		(layers "F.Cu" "B.Cu")
		(net "P3V3_STBY")
	)
	(via
		(at 43.942 -162.6616)
		(size 0.508)
		(drill 0.254)
		(layers "F.Cu" "B.Cu")
		(net "P3V3_STBY")
	)
	(via
		(at 58.801 -167.4114)
		(size 0.508)
		(drill 0.254)
		(layers "F.Cu" "B.Cu")
		(net "P3V3_STBY")
	)
	(via
		(at 42.584624 -118.1862)
		(size 0.508)
		(drill 0.254)
		(layers "F.Cu" "B.Cu")
		(net "P3V3_STBY")
	)
	(via
		(at 68.89496 -177.53584)
		(size 0.508)
		(drill 0.254)
		(layers "F.Cu" "B.Cu")
		(net "P3V3_STBY")
	)
	(via
		(at 75.6539 -133.223)
		(size 0.508)
		(drill 0.254)
		(layers "F.Cu" "B.Cu")
		(net "P3V3_STBY")
	)
	(via
		(at 77.611986 -183.127142)
		(size 0.7112)
		(drill 0.4064)
		(layers "F.Cu" "B.Cu")
		(net "P3V3_STBY")
	)
	(via
		(at 48.1838 -117.729)
		(size 0.508)
		(drill 0.254)
		(layers "F.Cu" "B.Cu")
		(net "P3V3_STBY")
	)
	(via
		(at 70.6501 -164.684202)
		(size 0.508)
		(drill 0.254)
		(layers "F.Cu" "B.Cu")
		(net "P3V3_STBY")
	)
	(via
		(at 52.499768 -148.20011)
		(size 0.4572)
		(drill 0.2032)
		(layers "F.Cu" "B.Cu")
		(net "P3V3_STBY")
	)
	(via
		(at 46.100238 -149.800056)
		(size 0.4572)
		(drill 0.2032)
		(layers "F.Cu" "B.Cu")
		(net "P3V3_STBY")
	)
	(via
		(at 30.3276 -132.5118)
		(size 0.508)
		(drill 0.254)
		(layers "F.Cu" "B.Cu")
		(net "P3V3_STBY")
	)
	(via
		(at 86.121748 -132.3594)
		(size 0.508)
		(drill 0.254)
		(layers "F.Cu" "B.Cu")
		(net "P3V3_STBY")
	)
	(via
		(at 40.400732 -162.847528)
		(size 0.508)
		(drill 0.254)
		(layers "F.Cu" "B.Cu")
		(net "P3V3_STBY")
	)
	(via
		(at 31.3182 -134.6962)
		(size 0.508)
		(drill 0.254)
		(layers "F.Cu" "B.Cu")
		(net "P3V3_STBY")
	)
	(via
		(at 89.641934 -136.276334)
		(size 0.508)
		(drill 0.254)
		(layers "F.Cu" "B.Cu")
		(net "P3V3_STBY")
	)
	(via
		(at 14.2494 -171.704)
		(size 0.508)
		(drill 0.254)
		(layers "F.Cu" "B.Cu")
		(net "P3V3_STBY")
	)
	(via
		(at 174.220378 -7.777988)
		(size 0.508)
		(drill 0.254)
		(layers "F.Cu" "B.Cu")
		(net "P3V3_STBY")
	)
	(via
		(at 36.4998 -119.126)
		(size 0.508)
		(drill 0.254)
		(layers "F.Cu" "B.Cu")
		(net "P3V3_STBY")
	)
	(via
		(at 82.166968 -54.415436)
		(size 0.7112)
		(drill 0.4064)
		(layers "F.Cu" "B.Cu")
		(net "P3V3_STBY")
	)
	(via
		(at 77.688948 -53.343556)
		(size 0.7112)
		(drill 0.4064)
		(layers "F.Cu" "B.Cu")
		(net "P3V3_STBY")
	)
	(via
		(at 63.2968 -186.3598)
		(size 0.7112)
		(drill 0.4064)
		(layers "F.Cu" "B.Cu")
		(net "P3V3_STBY")
	)
	(via
		(at 63.841884 -140.7414)
		(size 0.508)
		(drill 0.254)
		(layers "F.Cu" "B.Cu")
		(net "P3V3_STBY")
	)
	(via
		(at 73.025 -131.572)
		(size 0.508)
		(drill 0.254)
		(layers "F.Cu" "B.Cu")
		(net "P3V3_STBY")
	)
	(via
		(at 47.0154 -156.0322)
		(size 0.508)
		(drill 0.254)
		(layers "F.Cu" "B.Cu")
		(net "P3V3_STBY")
	)
	(via
		(at 52.280058 -176.53)
		(size 0.508)
		(drill 0.254)
		(layers "F.Cu" "B.Cu")
		(net "P3V3_STBY")
	)
	(via
		(at 63.2968 -185.0898)
		(size 0.7112)
		(drill 0.4064)
		(layers "F.Cu" "B.Cu")
		(net "P3V3_STBY")
	)
	(via
		(at 80.38211 -181.880002)
		(size 0.508)
		(drill 0.254)
		(layers "F.Cu" "B.Cu")
		(net "P3V3_STBY")
	)
	(via
		(at 191.4652 -135.89)
		(size 0.5588)
		(drill 0.3048)
		(layers "F.Cu" "B.Cu")
		(net "P3V3_STBY")
	)
	(via
		(at 69.3166 -169.9514)
		(size 0.508)
		(drill 0.254)
		(layers "F.Cu" "B.Cu")
		(net "P3V3_STBY")
	)
	(via
		(at 64.619632 -148.966682)
		(size 0.508)
		(drill 0.254)
		(layers "F.Cu" "B.Cu")
		(net "P3V3_STBY")
	)
	(via
		(at 61.907674 -180.1114)
		(size 0.508)
		(drill 0.254)
		(layers "F.Cu" "B.Cu")
		(net "P3V3_STBY")
	)
	(via
		(at 38.5572 -156.3116)
		(size 0.508)
		(drill 0.254)
		(layers "F.Cu" "B.Cu")
		(net "P3V3_STBY")
	)
	(via
		(at 87.5284 -128.9304)
		(size 0.508)
		(drill 0.254)
		(layers "F.Cu" "B.Cu")
		(net "P3V3_STBY")
	)
	(via
		(at 85.1154 -57.941718)
		(size 0.508)
		(drill 0.254)
		(layers "F.Cu" "B.Cu")
		(net "P3V3_STBY")
	)
	(via
		(at 46.100238 -140.20038)
		(size 0.4572)
		(drill 0.2032)
		(layers "F.Cu" "B.Cu")
		(net "P3V3_STBY")
	)
	(via
		(at 74.599038 -149.749764)
		(size 0.508)
		(drill 0.254)
		(layers "F.Cu" "B.Cu")
		(net "P3V3_STBY")
	)
	(via
		(at 52.499768 -141.800326)
		(size 0.4572)
		(drill 0.2032)
		(layers "F.Cu" "B.Cu")
		(net "P3V3_STBY")
	)
	(via
		(at 44.499784 -141.800326)
		(size 0.4572)
		(drill 0.2032)
		(layers "F.Cu" "B.Cu")
		(net "P3V3_STBY")
	)
	(via
		(at 53.676296 -124.431044)
		(size 0.508)
		(drill 0.254)
		(layers "F.Cu" "B.Cu")
		(net "P3V3_STBY")
	)
	(via
		(at 33.1216 -137.1346)
		(size 0.6096)
		(drill 0.3048)
		(layers "F.Cu" "B.Cu")
		(net "P3V3_STBY")
	)
	(via
		(at 40.193214 -130.21945)
		(size 0.508)
		(drill 0.254)
		(layers "F.Cu" "B.Cu")
		(net "P3V3_STBY")
	)
	(via
		(at 68.20408 -182.73268)
		(size 0.508)
		(drill 0.254)
		(layers "F.Cu" "B.Cu")
		(net "P3V3_STBY")
	)
	(via
		(at 50.899822 -140.20038)
		(size 0.4572)
		(drill 0.2032)
		(layers "F.Cu" "B.Cu")
		(net "P3V3_STBY")
	)
	(via
		(at 89.527888 -147.574)
		(size 0.508)
		(drill 0.254)
		(layers "F.Cu" "B.Cu")
		(net "P3V3_STBY")
	)
	(via
		(at 64.7827 -171.6405)
		(size 0.508)
		(drill 0.254)
		(layers "F.Cu" "B.Cu")
		(net "P3V3_STBY")
	)
	(via
		(at 46.44898 -130.513328)
		(size 0.508)
		(drill 0.254)
		(layers "F.Cu" "B.Cu")
		(net "P3V3_STBY")
	)
	(via
		(at 67.2592 -118.7196)
		(size 0.508)
		(drill 0.254)
		(layers "F.Cu" "B.Cu")
		(net "P3V3_STBY")
	)
	(via
		(at 57.3786 -160.270952)
		(size 0.508)
		(drill 0.254)
		(layers "F.Cu" "B.Cu")
		(net "P3V3_STBY")
	)
	(via
		(at 69.01561 -141.39926)
		(size 0.508)
		(drill 0.254)
		(layers "F.Cu" "B.Cu")
		(net "P3V3_STBY")
	)
	(via
		(at 91.7575 -124.8791)
		(size 0.508)
		(drill 0.254)
		(layers "F.Cu" "B.Cu")
		(net "P3V3_STBY")
	)
	(via
		(at 89.789 -158.623)
		(size 0.508)
		(drill 0.254)
		(layers "F.Cu" "B.Cu")
		(net "P3V3_STBY")
	)
	(via
		(at 83.402424 -172.384466)
		(size 0.508)
		(drill 0.254)
		(layers "F.Cu" "B.Cu")
		(net "P3V3_STBY")
	)
	(via
		(at 63.2968 -183.8198)
		(size 0.7112)
		(drill 0.4064)
		(layers "F.Cu" "B.Cu")
		(net "P3V3_STBY")
	)
	(via
		(at 74.0918 -187.198)
		(size 0.508)
		(drill 0.254)
		(layers "F.Cu" "B.Cu")
		(net "P3V3_STBY")
	)
	(via
		(at 82.5246 -147.7264)
		(size 0.508)
		(drill 0.254)
		(layers "F.Cu" "B.Cu")
		(net "P3V3_STBY")
	)
	(via
		(at 19.880072 -16.95577)
		(size 0.508)
		(drill 0.254)
		(layers "F.Cu" "B.Cu")
		(net "P3V3_STBY")
	)
	(via
		(at 59.6138 -147.7264)
		(size 0.508)
		(drill 0.254)
		(layers "F.Cu" "B.Cu")
		(net "P3V3_STBY")
	)
	(via
		(at 61.6458 -139.3444)
		(size 0.508)
		(drill 0.254)
		(layers "F.Cu" "B.Cu")
		(net "P3V3_STBY")
	)
	(via
		(at 77.611986 -184.397142)
		(size 0.7112)
		(drill 0.4064)
		(layers "F.Cu" "B.Cu")
		(net "P3V3_STBY")
	)
	(via
		(at 76.8858 -140.0302)
		(size 0.508)
		(drill 0.254)
		(layers "F.Cu" "B.Cu")
		(net "P3V3_STBY")
	)
	(via
		(at 36.06292 -129.18186)
		(size 0.508)
		(drill 0.254)
		(layers "F.Cu" "B.Cu")
		(net "P3V3_STBY")
	)
	(via
		(at 71.535544 -149.554184)
		(size 0.508)
		(drill 0.254)
		(layers "F.Cu" "B.Cu")
		(net "P3V3_STBY")
	)
	(via
		(at 58.436002 -157.141418)
		(size 0.508)
		(drill 0.254)
		(layers "F.Cu" "B.Cu")
		(net "P3V3_STBY")
	)
	(via
		(at 67.0052 -164.821108)
		(size 0.508)
		(drill 0.254)
		(layers "F.Cu" "B.Cu")
		(net "P3V3_STBY")
	)
	(via
		(at 92.456 -133.477)
		(size 0.508)
		(drill 0.254)
		(layers "F.Cu" "B.Cu")
		(net "P3V3_STBY")
	)
	(via
		(at 164.99586 -28.965144)
		(size 0.7112)
		(drill 0.4064)
		(layers "F.Cu" "B.Cu")
		(net "P3V3_STBY")
	)
	(via
		(at 45.6438 -156.2862)
		(size 0.508)
		(drill 0.254)
		(layers "F.Cu" "B.Cu")
		(net "P3V3_STBY")
	)
	(via
		(at 70.8152 -118.745)
		(size 0.508)
		(drill 0.254)
		(layers "F.Cu" "B.Cu")
		(net "P3V3_STBY")
	)
	(via
		(at 51.699922 -145.800318)
		(size 0.4572)
		(drill 0.2032)
		(layers "F.Cu" "B.Cu")
		(net "P3V3_STBY")
	)
	(via
		(at 94.5134 -180.7718)
		(size 0.508)
		(drill 0.254)
		(layers "F.Cu" "B.Cu")
		(net "P3V3_STBY")
	)
	(via
		(at 78.881986 -183.127142)
		(size 0.7112)
		(drill 0.4064)
		(layers "F.Cu" "B.Cu")
		(net "P3V3_STBY")
	)
	(via
		(at 71.05523 -154.432)
		(size 0.508)
		(drill 0.254)
		(layers "F.Cu" "B.Cu")
		(net "P3V3_STBY")
	)
	(via
		(at 36.213288 -162.644328)
		(size 0.508)
		(drill 0.254)
		(layers "F.Cu" "B.Cu")
		(net "P3V3_STBY")
	)
	(via
		(at 52.499768 -144.1704)
		(size 0.4572)
		(drill 0.2032)
		(layers "F.Cu" "B.Cu")
		(net "P3V3_STBY")
	)
	(via
		(at 50.86604 -118.3386)
		(size 0.508)
		(drill 0.254)
		(layers "F.Cu" "B.Cu")
		(net "P3V3_STBY")
	)
	(via
		(at 201.9046 -112.0394)
		(size 0.508)
		(drill 0.254)
		(layers "F.Cu" "B.Cu")
		(net "P3V3_STBY")
	)
	(via
		(at 86.6902 -136.1948)
		(size 0.508)
		(drill 0.254)
		(layers "F.Cu" "B.Cu")
		(net "P3V3_STBY")
	)
	(via
		(at 58.7883 -143.002)
		(size 0.508)
		(drill 0.254)
		(layers "F.Cu" "B.Cu")
		(net "P3V3_STBY")
	)
	(via
		(at 64.1096 -137.0584)
		(size 0.508)
		(drill 0.254)
		(layers "F.Cu" "B.Cu")
		(net "P3V3_STBY")
	)
	(via
		(at 89.831926 -152.623774)
		(size 0.508)
		(drill 0.254)
		(layers "F.Cu" "B.Cu")
		(net "P3V3_STBY")
	)
	(via
		(at 39.30142 -130.226816)
		(size 0.508)
		(drill 0.254)
		(layers "F.Cu" "B.Cu")
		(net "P3V3_STBY")
	)
	(via
		(at 94.27972 -159.825944)
		(size 0.508)
		(drill 0.254)
		(layers "F.Cu" "B.Cu")
		(net "P3V3_STBY")
	)
	(via
		(at 78.881986 -184.397142)
		(size 0.7112)
		(drill 0.4064)
		(layers "F.Cu" "B.Cu")
		(net "P3V3_STBY")
	)
	(via
		(at 44.47921 -117.795294)
		(size 0.508)
		(drill 0.254)
		(layers "F.Cu" "B.Cu")
		(net "P3V3_STBY")
	)
	(via
		(at 97.4344 -180.7972)
		(size 0.508)
		(drill 0.254)
		(layers "F.Cu" "B.Cu")
		(net "P3V3_STBY")
	)
	(via
		(at 98.100896 -147.453096)
		(size 0.508)
		(drill 0.254)
		(layers "F.Cu" "B.Cu")
		(net "P3V3_STBY")
	)
	(via
		(at 166.023036 -130.494278)
		(size 0.508)
		(drill 0.254)
		(layers "F.Cu" "B.Cu")
		(net "P3V3_STBY")
	)
	(via
		(at 208.3181 -110.2106)
		(size 0.508)
		(drill 0.254)
		(layers "F.Cu" "B.Cu")
		(net "P3V3_STBY")
	)
	(via
		(at 92.0115 -145.00225)
		(size 0.508)
		(drill 0.254)
		(layers "F.Cu" "B.Cu")
		(net "P3V3_STBY")
	)
	(via
		(at 43.3578 -130.4544)
		(size 0.508)
		(drill 0.254)
		(layers "F.Cu" "B.Cu")
		(net "P3V3_STBY")
	)
	(via
		(at 65.231264 -143.251428)
		(size 0.508)
		(drill 0.254)
		(layers "F.Cu" "B.Cu")
		(net "P3V3_STBY")
	)
	(via
		(at 45.974 -162.4838)
		(size 0.508)
		(drill 0.254)
		(layers "F.Cu" "B.Cu")
		(net "P3V3_STBY")
	)
	(via
		(at 94.760542 -51.279806)
		(size 0.7112)
		(drill 0.4064)
		(layers "F.Cu" "B.Cu")
		(net "P3V3_STBY")
	)
	(segment
		(start 57.8485 -148.8186)
		(end 58.5216 -148.8186)
		(width 0.508)
		(layer "B.Cu")
		(net "P3V3_STBY")
	)
	(segment
		(start 164.99586 -24.61514)
		(end 164.99586 -28.965144)
		(width 0.508)
		(layer "B.Cu")
		(net "P3V3_STBY")
	)
	(segment
		(start 57.7723 -145.2626)
		(end 58.674 -145.2626)
		(width 0.508)
		(layer "B.Cu")
		(net "P3V3_STBY")
	)
	(segment
		(start 206.103474 -100.591874)
		(end 206.0702 -100.5586)
		(width 0.508)
		(layer "B.Cu")
		(net "P3V3_STBY")
	)
	(segment
		(start 82.837782 -146.788886)
		(end 83.355942 -147.307046)
		(width 0.3556)
		(layer "B.Cu")
		(net "P3V3_STBY")
	)
	(segment
		(start 38.3667 -157.5308)
		(end 38.3667 -156.5021)
		(width 0.508)
		(layer "B.Cu")
		(net "P3V3_STBY")
	)
	(segment
		(start 46.8376 -155.8544)
		(end 47.0154 -156.0322)
		(width 0.508)
		(layer "B.Cu")
		(net "P3V3_STBY")
	)
	(segment
		(start 58.511948 -155.558998)
		(end 59.9694 -154.101546)
		(width 0.508)
		(layer "B.Cu")
		(net "P3V3_STBY")
	)
	(segment
		(start 52.7304 -125.89002)
		(end 53.83276 -125.89002)
		(width 0.3556)
		(layer "B.Cu")
		(net "P3V3_STBY")
	)
	(segment
		(start 85.40242 -95.9612)
		(end 86.9061 -95.9612)
		(width 0.508)
		(layer "B.Cu")
		(net "P3V3_STBY")
	)
	(segment
		(start 59.9567 -148.0693)
		(end 59.6138 -147.7264)
		(width 0.508)
		(layer "B.Cu")
		(net "P3V3_STBY")
	)
	(segment
		(start 52.7304 -125.05436)
		(end 52.7304 -125.89002)
		(width 0.3556)
		(layer "B.Cu")
		(net "P3V3_STBY")
	)
	(segment
		(start 93.37548 -151.524716)
		(end 93.251782 -151.401018)
		(width 0.508)
		(layer "B.Cu")
		(net "P3V3_STBY")
	)
	(segment
		(start 90.96248 -137.956798)
		(end 90.96248 -138.215116)
		(width 0.508)
		(layer "B.Cu")
		(net "P3V3_STBY")
	)
	(segment
		(start 71.914258 -149.17547)
		(end 71.535544 -149.554184)
		(width 0.508)
		(layer "B.Cu")
		(net "P3V3_STBY")
	)
	(segment
		(start 90.337386 -135.87984)
		(end 91.11742 -135.87984)
		(width 0.3556)
		(layer "B.Cu")
		(net "P3V3_STBY")
	)
	(segment
		(start 83.194652 -152.469596)
		(end 82.743548 -152.018492)
		(width 0.508)
		(layer "B.Cu")
		(net "P3V3_STBY")
	)
	(segment
		(start 60.4774 -148.0693)
		(end 59.9567 -148.0693)
		(width 0.508)
		(layer "B.Cu")
		(net "P3V3_STBY")
	)
	(segment
		(start 93.84792 -159.013144)
		(end 93.84792 -159.394144)
		(width 0.508)
		(layer "B.Cu")
		(net "P3V3_STBY")
	)
	(segment
		(start 80.3529 -130.92684)
		(end 79.3496 -130.92684)
		(width 0.3048)
		(layer "B.Cu")
		(net "P3V3_STBY")
	)
	(segment
		(start 47.68342 -132.96138)
		(end 47.68342 -132.09143)
		(width 0.508)
		(layer "B.Cu")
		(net "P3V3_STBY")
	)
	(segment
		(start 206.040736 -100.529136)
		(end 206.040736 -97.463864)
		(width 0.635)
		(layer "B.Cu")
		(net "P3V3_STBY")
	)
	(segment
		(start 94.8436 -159.0167)
		(end 94.8436 -159.262064)
		(width 0.508)
		(layer "B.Cu")
		(net "P3V3_STBY")
	)
	(segment
		(start 89.2048 -153.2509)
		(end 89.2048 -155.6004)
		(width 0.508)
		(layer "B.Cu")
		(net "P3V3_STBY")
	)
	(segment
		(start 58.837068 -158.191708)
		(end 58.837068 -157.542484)
		(width 0.508)
		(layer "B.Cu")
		(net "P3V3_STBY")
	)
	(segment
		(start 47.625 -133.0198)
		(end 47.5996 -133.0452)
		(width 0.4572)
		(layer "B.Cu")
		(net "P3V3_STBY")
	)
	(segment
		(start 73.819258 -152.59304)
		(end 73.224644 -151.998426)
		(width 0.381)
		(layer "B.Cu")
		(net "P3V3_STBY")
	)
	(segment
		(start 89.831926 -152.623774)
		(end 89.2048 -153.2509)
		(width 0.508)
		(layer "B.Cu")
		(net "P3V3_STBY")
	)
	(segment
		(start 66.7893 -135.001)
		(end 65.6971 -136.0932)
		(width 0.508)
		(layer "B.Cu")
		(net "P3V3_STBY")
	)
	(segment
		(start 28.631388 -125.468634)
		(end 28.631388 -126.31547)
		(width 0.508)
		(layer "B.Cu")
		(net "P3V3_STBY")
	)
	(segment
		(start 44.4246 -127.7747)
		(end 44.4246 -126.9492)
		(width 0.508)
		(layer "B.Cu")
		(net "P3V3_STBY")
	)
	(segment
		(start 64.1223 -138.0744)
		(end 64.1223 -137.0711)
		(width 0.508)
		(layer "B.Cu")
		(net "P3V3_STBY")
	)
	(segment
		(start 41.3258 -125.0315)
		(end 41.3258 -124.552964)
		(width 0.508)
		(layer "B.Cu")
		(net "P3V3_STBY")
	)
	(segment
		(start 206.103474 -102.391718)
		(end 206.103474 -100.591874)
		(width 0.508)
		(layer "B.Cu")
		(net "P3V3_STBY")
	)
	(segment
		(start 179.8066 -111.252)
		(end 177.43932 -111.252)
		(width 0.635)
		(layer "B.Cu")
		(net "P3V3_STBY")
	)
	(segment
		(start 82.051906 -171.970446)
		(end 82.988404 -171.970446)
		(width 0.3556)
		(layer "B.Cu")
		(net "P3V3_STBY")
	)
	(segment
		(start 84.074508 -151.58974)
		(end 83.194652 -152.469596)
		(width 0.381)
		(layer "B.Cu")
		(net "P3V3_STBY")
	)
	(segment
		(start 73.224644 -149.17547)
		(end 73.697846 -149.17547)
		(width 0.508)
		(layer "B.Cu")
		(net "P3V3_STBY")
	)
	(segment
		(start 91.8845 -132.75564)
		(end 91.8845 -132.9055)
		(width 0.4064)
		(layer "B.Cu")
		(net "P3V3_STBY")
	)
	(segment
		(start 90.805 -144.6276)
		(end 90.805 -144.0053)
		(width 0.508)
		(layer "B.Cu")
		(net "P3V3_STBY")
	)
	(segment
		(start 49.0601 -134.366)
		(end 49.1871 -134.239)
		(width 0.4572)
		(layer "B.Cu")
		(net "P3V3_STBY")
	)
	(segment
		(start 89.641934 -136.276334)
		(end 89.940892 -136.276334)
		(width 0.3556)
		(layer "B.Cu")
		(net "P3V3_STBY")
	)
	(segment
		(start 92.282518 -133.650482)
		(end 90.567256 -133.650482)
		(width 0.508)
		(layer "B.Cu")
		(net "P3V3_STBY")
	)
	(segment
		(start 80.6196 -173.0756)
		(end 80.6323 -173.0883)
		(width 0.508)
		(layer "B.Cu")
		(net "P3V3_STBY")
	)
	(segment
		(start 79.3496 -130.92684)
		(end 79.2226 -130.79984)
		(width 0.3048)
		(layer "B.Cu")
		(net "P3V3_STBY")
	)
	(segment
		(start 173.3804 -5.1816)
		(end 172.540422 -5.1816)
		(width 0.508)
		(layer "B.Cu")
		(net "P3V3_STBY")
	)
	(segment
		(start 55.499 -123.7615)
		(end 55.499 -122.853958)
		(width 0.508)
		(layer "B.Cu")
		(net "P3V3_STBY")
	)
	(segment
		(start 79.9592 -173.0883)
		(end 79.9719 -173.0756)
		(width 0.508)
		(layer "B.Cu")
		(net "P3V3_STBY")
	)
	(segment
		(start 57.5183 -151.6888)
		(end 57.5945 -151.765)
		(width 0.508)
		(layer "B.Cu")
		(net "P3V3_STBY")
	)
	(segment
		(start 174.220378 -7.777988)
		(end 174.220378 -15.390622)
		(width 0.508)
		(layer "B.Cu")
		(net "P3V3_STBY")
	)
	(segment
		(start 57.86755 -146.511264)
		(end 57.871614 -146.5072)
		(width 0.508)
		(layer "B.Cu")
		(net "P3V3_STBY")
	)
	(segment
		(start 38.3667 -156.5021)
		(end 38.5572 -156.3116)
		(width 0.508)
		(layer "B.Cu")
		(net "P3V3_STBY")
	)
	(segment
		(start 73.224644 -145.761456)
		(end 73.42378 -145.56232)
		(width 0.508)
		(layer "B.Cu")
		(net "P3V3_STBY")
	)
	(segment
		(start 73.697846 -149.17547)
		(end 74.27214 -149.749764)
		(width 0.508)
		(layer "B.Cu")
		(net "P3V3_STBY")
	)
	(segment
		(start 55.499 -123.7615)
		(end 54.8513 -123.7615)
		(width 0.508)
		(layer "B.Cu")
		(net "P3V3_STBY")
	)
	(segment
		(start 57.871614 -146.5072)
		(end 58.7248 -146.5072)
		(width 0.508)
		(layer "B.Cu")
		(net "P3V3_STBY")
	)
	(segment
		(start 91.297506 -137.207752)
		(end 91.297506 -137.621772)
		(width 0.508)
		(layer "B.Cu")
		(net "P3V3_STBY")
	)
	(segment
		(start 47.861474 -155.800552)
		(end 47.629826 -156.0322)
		(width 0.508)
		(layer "B.Cu")
		(net "P3V3_STBY")
	)
	(segment
		(start 95.106744 -152.289256)
		(end 93.37548 -152.289256)
		(width 0.508)
		(layer "B.Cu")
		(net "P3V3_STBY")
	)
	(segment
		(start 174.220378 -7.777988)
		(end 174.220378 -6.021578)
		(width 0.508)
		(layer "B.Cu")
		(net "P3V3_STBY")
	)
	(segment
		(start 85.034628 -33.701228)
		(end 85.034628 -46.971712)
		(width 0.508)
		(layer "B.Cu")
		(net "P3V3_STBY")
	)
	(segment
		(start 176.1109 -115.57)
		(end 176.1109 -112.0521)
		(width 0.508)
		(layer "B.Cu")
		(net "P3V3_STBY")
	)
	(segment
		(start 91.11742 -137.027666)
		(end 91.11742 -135.87984)
		(width 0.3556)
		(layer "B.Cu")
		(net "P3V3_STBY")
	)
	(segment
		(start 69.56933 -145.199354)
		(end 70.199504 -145.829528)
		(width 0.508)
		(layer "B.Cu")
		(net "P3V3_STBY")
	)
	(segment
		(start 82.936588 -147.7264)
		(end 82.5246 -147.7264)
		(width 0.508)
		(layer "B.Cu")
		(net "P3V3_STBY")
	)
	(segment
		(start 45.588936 -156.341064)
		(end 45.6438 -156.2862)
		(width 0.508)
		(layer "B.Cu")
		(net "P3V3_STBY")
	)
	(segment
		(start 207.014064 -88.535256)
		(end 206.468218 -88.535256)
		(width 0.508)
		(layer "B.Cu")
		(net "P3V3_STBY")
	)
	(segment
		(start 176.83353 -111.32947)
		(end 177.36185 -111.32947)
		(width 0.508)
		(layer "B.Cu")
		(net "P3V3_STBY")
	)
	(segment
		(start 208.3181 -110.2106)
		(end 206.4893 -112.0394)
		(width 0.635)
		(layer "B.Cu")
		(net "P3V3_STBY")
	)
	(segment
		(start 92.0115 -145.00225)
		(end 91.17965 -145.00225)
		(width 0.508)
		(layer "B.Cu")
		(net "P3V3_STBY")
	)
	(segment
		(start 46.100238 -149.800056)
		(end 46.186344 -149.800056)
		(width 0.508)
		(layer "B.Cu")
		(net "P3V3_STBY")
	)
	(segment
		(start 64.5541 -147.5105)
		(end 64.8716 -147.193)
		(width 0.508)
		(layer "B.Cu")
		(net "P3V3_STBY")
	)
	(segment
		(start 54.864762 -134.134352)
		(end 54.155848 -134.134352)
		(width 0.508)
		(layer "B.Cu")
		(net "P3V3_STBY")
	)
	(segment
		(start 48.1076 -134.366)
		(end 49.0601 -134.366)
		(width 0.4572)
		(layer "B.Cu")
		(net "P3V3_STBY")
	)
	(segment
		(start 177.43932 -111.252)
		(end 177.36185 -111.32947)
		(width 0.635)
		(layer "B.Cu")
		(net "P3V3_STBY")
	)
	(segment
		(start 91.8845 -132.9055)
		(end 92.456 -133.477)
		(width 0.4064)
		(layer "B.Cu")
		(net "P3V3_STBY")
	)
	(segment
		(start 64.2493 -144.0434)
		(end 64.2493 -145.0594)
		(width 0.508)
		(layer "B.Cu")
		(net "P3V3_STBY")
	)
	(segment
		(start 82.743548 -152.018492)
		(end 82.743548 -151.6126)
		(width 0.508)
		(layer "B.Cu")
		(net "P3V3_STBY")
	)
	(segment
		(start 206.4893 -112.0394)
		(end 205.2574 -112.0394)
		(width 0.635)
		(layer "B.Cu")
		(net "P3V3_STBY")
	)
	(segment
		(start 75.6539 -134.0866)
		(end 75.6539 -133.223)
		(width 0.508)
		(layer "B.Cu")
		(net "P3V3_STBY")
	)
	(segment
		(start 50.5841 -162.5981)
		(end 50.4698 -162.4838)
		(width 0.508)
		(layer "B.Cu")
		(net "P3V3_STBY")
	)
	(segment
		(start 86.678516 -146.0246)
		(end 87.4141 -146.0246)
		(width 0.508)
		(layer "B.Cu")
		(net "P3V3_STBY")
	)
	(segment
		(start 54.688232 -135.166354)
		(end 53.9242 -134.402322)
		(width 0.508)
		(layer "B.Cu")
		(net "P3V3_STBY")
	)
	(segment
		(start 190.888366 -136.466834)
		(end 191.4652 -135.89)
		(width 0.508)
		(layer "B.Cu")
		(net "P3V3_STBY")
	)
	(segment
		(start 69.56933 -145.136108)
		(end 69.56933 -145.199354)
		(width 0.508)
		(layer "B.Cu")
		(net "P3V3_STBY")
	)
	(segment
		(start 206.468218 -88.535256)
		(end 206.11846 -88.885014)
		(width 0.508)
		(layer "B.Cu")
		(net "P3V3_STBY")
	)
	(segment
		(start 60.2742 -138.0871)
		(end 61.2902 -138.0871)
		(width 0.508)
		(layer "B.Cu")
		(net "P3V3_STBY")
	)
	(segment
		(start 79.0956 -130.9243)
		(end 78.4098 -130.9243)
		(width 0.508)
		(layer "B.Cu")
		(net "P3V3_STBY")
	)
	(segment
		(start 82.69859 -173.0883)
		(end 83.402424 -172.384466)
		(width 0.508)
		(layer "B.Cu")
		(net "P3V3_STBY")
	)
	(segment
		(start 64.0842 -147.5105)
		(end 64.5541 -147.5105)
		(width 0.508)
		(layer "B.Cu")
		(net "P3V3_STBY")
	)
	(segment
		(start 190.888366 -136.834372)
		(end 190.888366 -136.466834)
		(width 0.508)
		(layer "B.Cu")
		(net "P3V3_STBY")
	)
	(segment
		(start 206.040736 -97.463864)
		(end 210.954874 -92.549726)
		(width 0.635)
		(layer "B.Cu")
		(net "P3V3_STBY")
	)
	(segment
		(start 47.5996 -133.858)
		(end 48.1076 -134.366)
		(width 0.4572)
		(layer "B.Cu")
		(net "P3V3_STBY")
	)
	(segment
		(start 174.220378 -6.021578)
		(end 173.3804 -5.1816)
		(width 0.508)
		(layer "B.Cu")
		(net "P3V3_STBY")
	)
	(segment
		(start 63.841884 -140.7414)
		(end 63.841884 -141.2494)
		(width 0.508)
		(layer "B.Cu")
		(net "P3V3_STBY")
	)
	(segment
		(start 77.3049 -167.9702)
		(end 76.5556 -167.9702)
		(width 0.508)
		(layer "B.Cu")
		(net "P3V3_STBY")
	)
	(segment
		(start 65.041272 -143.251428)
		(end 65.231264 -143.251428)
		(width 0.508)
		(layer "B.Cu")
		(net "P3V3_STBY")
	)
	(segment
		(start 84.995004 -98.494596)
		(end 85.344 -98.1456)
		(width 0.508)
		(layer "B.Cu")
		(net "P3V3_STBY")
	)
	(segment
		(start 59.9694 -154.101546)
		(end 59.9694 -151.765)
		(width 0.508)
		(layer "B.Cu")
		(net "P3V3_STBY")
	)
	(segment
		(start 61.2902 -138.0871)
		(end 61.3029 -138.0998)
		(width 0.508)
		(layer "B.Cu")
		(net "P3V3_STBY")
	)
	(segment
		(start 91.8464 -152.4254)
		(end 91.8972 -152.3746)
		(width 0.508)
		(layer "B.Cu")
		(net "P3V3_STBY")
	)
	(segment
		(start 85.344 -98.1456)
		(end 85.344 -97.6376)
		(width 0.508)
		(layer "B.Cu")
		(net "P3V3_STBY")
	)
	(segment
		(start 82.988404 -171.970446)
		(end 83.402424 -172.384466)
		(width 0.3556)
		(layer "B.Cu")
		(net "P3V3_STBY")
	)
	(segment
		(start 47.629826 -156.0322)
		(end 47.0154 -156.0322)
		(width 0.508)
		(layer "B.Cu")
		(net "P3V3_STBY")
	)
	(segment
		(start 176.1109 -112.0521)
		(end 176.83353 -111.32947)
		(width 0.508)
		(layer "B.Cu")
		(net "P3V3_STBY")
	)
	(segment
		(start 57.5945 -151.765)
		(end 59.8043 -151.765)
		(width 0.508)
		(layer "B.Cu")
		(net "P3V3_STBY")
	)
	(segment
		(start 80.6323 -173.0883)
		(end 82.69859 -173.0883)
		(width 0.508)
		(layer "B.Cu")
		(net "P3V3_STBY")
	)
	(segment
		(start 46.8376 -155.2829)
		(end 46.8376 -155.8544)
		(width 0.508)
		(layer "B.Cu")
		(net "P3V3_STBY")
	)
	(segment
		(start 79.2226 -130.79984)
		(end 79.2226 -130.7973)
		(width 0.3048)
		(layer "B.Cu")
		(net "P3V3_STBY")
	)
	(segment
		(start 54.650132 -123.560332)
		(end 53.88991 -123.560332)
		(width 0.508)
		(layer "B.Cu")
		(net "P3V3_STBY")
	)
	(segment
		(start 75.3745 -152.59304)
		(end 73.819258 -152.59304)
		(width 0.381)
		(layer "B.Cu")
		(net "P3V3_STBY")
	)
	(segment
		(start 91.297506 -137.621772)
		(end 90.96248 -137.956798)
		(width 0.508)
		(layer "B.Cu")
		(net "P3V3_STBY")
	)
	(segment
		(start 79.2226 -130.7973)
		(end 79.0956 -130.9243)
		(width 0.508)
		(layer "B.Cu")
		(net "P3V3_STBY")
	)
	(segment
		(start 48.58893 -163.240974)
		(end 48.58893 -163.01847)
		(width 0.508)
		(layer "B.Cu")
		(net "P3V3_STBY")
	)
	(segment
		(start 206.11846 -88.885014)
		(end 206.11846 -90.266266)
		(width 0.635)
		(layer "B.Cu")
		(net "P3V3_STBY")
	)
	(segment
		(start 41.85031 -124.028454)
		(end 42.626534 -124.028454)
		(width 0.508)
		(layer "B.Cu")
		(net "P3V3_STBY")
	)
	(segment
		(start 46.7487 -149.2377)
		(end 46.9138 -149.2377)
		(width 0.508)
		(layer "B.Cu")
		(net "P3V3_STBY")
	)
	(segment
		(start 84.074508 -151.057102)
		(end 84.074508 -151.58974)
		(width 0.381)
		(layer "B.Cu")
		(net "P3V3_STBY")
	)
	(segment
		(start 69.6214 -150.114)
		(end 69.3166 -149.8092)
		(width 0.508)
		(layer "B.Cu")
		(net "P3V3_STBY")
	)
	(segment
		(start 94.669356 -129.35585)
		(end 94.56166 -129.463546)
		(width 0.508)
		(layer "B.Cu")
		(net "P3V3_STBY")
	)
	(segment
		(start 78.763368 -146.788886)
		(end 82.837782 -146.788886)
		(width 0.3556)
		(layer "B.Cu")
		(net "P3V3_STBY")
	)
	(segment
		(start 61.3029 -138.0998)
		(end 61.3029 -139.0015)
		(width 0.508)
		(layer "B.Cu")
		(net "P3V3_STBY")
	)
	(segment
		(start 48.58893 -163.01847)
		(end 49.1236 -162.4838)
		(width 0.508)
		(layer "B.Cu")
		(net "P3V3_STBY")
	)
	(segment
		(start 52.92598 -124.85878)
		(end 52.7304 -125.05436)
		(width 0.3556)
		(layer "B.Cu")
		(net "P3V3_STBY")
	)
	(segment
		(start 65.864994 -139.270232)
		(end 66.686938 -139.270232)
		(width 0.508)
		(layer "B.Cu")
		(net "P3V3_STBY")
	)
	(segment
		(start 92.0115 -146.0246)
		(end 92.0115 -145.00225)
		(width 0.508)
		(layer "B.Cu")
		(net "P3V3_STBY")
	)
	(segment
		(start 58.436002 -157.141418)
		(end 58.511948 -157.065472)
		(width 0.508)
		(layer "B.Cu")
		(net "P3V3_STBY")
	)
	(segment
		(start 210.954874 -92.549726)
		(end 210.954874 -91.843606)
		(width 0.635)
		(layer "B.Cu")
		(net "P3V3_STBY")
	)
	(segment
		(start 54.723792 -135.166354)
		(end 54.688232 -135.166354)
		(width 0.508)
		(layer "B.Cu")
		(net "P3V3_STBY")
	)
	(segment
		(start 84.2137 -98.494596)
		(end 84.995004 -98.494596)
		(width 0.508)
		(layer "B.Cu")
		(net "P3V3_STBY")
	)
	(segment
		(start 63.227712 -141.863572)
		(end 62.73292 -141.863572)
		(width 0.508)
		(layer "B.Cu")
		(net "P3V3_STBY")
	)
	(segment
		(start 75.512168 -146.788886)
		(end 74.199242 -146.788886)
		(width 0.3556)
		(layer "B.Cu")
		(net "P3V3_STBY")
	)
	(segment
		(start 36.4998 -119.9007)
		(end 36.4998 -119.126)
		(width 0.508)
		(layer "B.Cu")
		(net "P3V3_STBY")
	)
	(segment
		(start 58.7883 -144.018)
		(end 58.7883 -143.002)
		(width 0.508)
		(layer "B.Cu")
		(net "P3V3_STBY")
	)
	(segment
		(start 45.588936 -157.25648)
		(end 45.588936 -156.341064)
		(width 0.508)
		(layer "B.Cu")
		(net "P3V3_STBY")
	)
	(segment
		(start 90.6526 -2.4892)
		(end 83.0834 -10.0584)
		(width 0.508)
		(layer "B.Cu")
		(net "P3V3_STBY")
	)
	(segment
		(start 69.3166 -149.8092)
		(end 69.3166 -149.2885)
		(width 0.508)
		(layer "B.Cu")
		(net "P3V3_STBY")
	)
	(segment
		(start 86.59368 -146.109436)
		(end 86.678516 -146.0246)
		(width 0.508)
		(layer "B.Cu")
		(net "P3V3_STBY")
	)
	(segment
		(start 95.4024 -151.9936)
		(end 95.106744 -152.289256)
		(width 0.508)
		(layer "B.Cu")
		(net "P3V3_STBY")
	)
	(segment
		(start 74.27214 -149.749764)
		(end 74.599038 -149.749764)
		(width 0.508)
		(layer "B.Cu")
		(net "P3V3_STBY")
	)
	(segment
		(start 79.2226 -130.7846)
		(end 79.2226 -130.7973)
		(width 0.508)
		(layer "B.Cu")
		(net "P3V3_STBY")
	)
	(segment
		(start 47.5996 -133.0452)
		(end 47.5996 -133.858)
		(width 0.4572)
		(layer "B.Cu")
		(net "P3V3_STBY")
	)
	(segment
		(start 206.0702 -100.5586)
		(end 206.040736 -100.529136)
		(width 0.635)
		(layer "B.Cu")
		(net "P3V3_STBY")
	)
	(segment
		(start 76.8858 -140.0302)
		(end 76.633324 -140.0302)
		(width 0.508)
		(layer "B.Cu")
		(net "P3V3_STBY")
	)
	(segment
		(start 64.2493 -144.0434)
		(end 65.041272 -143.251428)
		(width 0.508)
		(layer "B.Cu")
		(net "P3V3_STBY")
	)
	(segment
		(start 76.248768 -140.414756)
		(end 75.35672 -140.414756)
		(width 0.508)
		(layer "B.Cu")
		(net "P3V3_STBY")
	)
	(segment
		(start 94.56166 -129.463546)
		(end 93.817186 -129.463546)
		(width 0.508)
		(layer "B.Cu")
		(net "P3V3_STBY")
	)
	(segment
		(start 76.633324 -140.0302)
		(end 76.248768 -140.414756)
		(width 0.508)
		(layer "B.Cu")
		(net "P3V3_STBY")
	)
	(segment
		(start 83.0834 -10.0584)
		(end 83.0834 -31.75)
		(width 0.508)
		(layer "B.Cu")
		(net "P3V3_STBY")
	)
	(segment
		(start 92.456 -133.477)
		(end 92.282518 -133.650482)
		(width 0.508)
		(layer "B.Cu")
		(net "P3V3_STBY")
	)
	(segment
		(start 59.9694 -151.765)
		(end 59.8043 -151.765)
		(width 0.508)
		(layer "B.Cu")
		(net "P3V3_STBY")
	)
	(segment
		(start 174.220378 -15.390622)
		(end 164.99586 -24.61514)
		(width 0.508)
		(layer "B.Cu")
		(net "P3V3_STBY")
	)
	(segment
		(start 83.355942 -147.307046)
		(end 82.936588 -147.7264)
		(width 0.508)
		(layer "B.Cu")
		(net "P3V3_STBY")
	)
	(segment
		(start 50.5841 -163.2712)
		(end 50.5841 -162.5981)
		(width 0.508)
		(layer "B.Cu")
		(net "P3V3_STBY")
	)
	(segment
		(start 83.0834 -31.75)
		(end 85.034628 -33.701228)
		(width 0.508)
		(layer "B.Cu")
		(net "P3V3_STBY")
	)
	(segment
		(start 90.567256 -133.650482)
		(end 90.084148 -133.167374)
		(width 0.508)
		(layer "B.Cu")
		(net "P3V3_STBY")
	)
	(segment
		(start 54.155848 -134.134352)
		(end 53.9242 -134.366)
		(width 0.508)
		(layer "B.Cu")
		(net "P3V3_STBY")
	)
	(segment
		(start 53.83276 -125.89002)
		(end 54.36616 -126.42342)
		(width 0.3556)
		(layer "B.Cu")
		(net "P3V3_STBY")
	)
	(segment
		(start 90.084148 -133.167374)
		(end 90.084148 -132.840984)
		(width 0.508)
		(layer "B.Cu")
		(net "P3V3_STBY")
	)
	(segment
		(start 53.88991 -123.560332)
		(end 53.88991 -124.21743)
		(width 0.508)
		(layer "B.Cu")
		(net "P3V3_STBY")
	)
	(segment
		(start 69.547486 -142.331694)
		(end 69.547486 -141.931136)
		(width 0.508)
		(layer "B.Cu")
		(net "P3V3_STBY")
	)
	(segment
		(start 91.297506 -137.207752)
		(end 91.11742 -137.027666)
		(width 0.3556)
		(layer "B.Cu")
		(net "P3V3_STBY")
	)
	(segment
		(start 53.88991 -124.21743)
		(end 53.676296 -124.431044)
		(width 0.508)
		(layer "B.Cu")
		(net "P3V3_STBY")
	)
	(segment
		(start 69.547486 -141.931136)
		(end 69.01561 -141.39926)
		(width 0.508)
		(layer "B.Cu")
		(net "P3V3_STBY")
	)
	(segment
		(start 76.5556 -167.9702)
		(end 75.6666 -168.8592)
		(width 0.508)
		(layer "B.Cu")
		(net "P3V3_STBY")
	)
	(segment
		(start 91.17965 -145.00225)
		(end 90.805 -144.6276)
		(width 0.508)
		(layer "B.Cu")
		(net "P3V3_STBY")
	)
	(segment
		(start 66.686938 -139.270232)
		(end 66.800984 -139.384278)
		(width 0.508)
		(layer "B.Cu")
		(net "P3V3_STBY")
	)
	(segment
		(start 207.6958 -91.843606)
		(end 210.954874 -91.843606)
		(width 0.635)
		(layer "B.Cu")
		(net "P3V3_STBY")
	)
	(segment
		(start 55.499 -122.853958)
		(end 55.348632 -122.70359)
		(width 0.508)
		(layer "B.Cu")
		(net "P3V3_STBY")
	)
	(segment
		(start 94.8436 -159.262064)
		(end 94.27972 -159.825944)
		(width 0.508)
		(layer "B.Cu")
		(net "P3V3_STBY")
	)
	(segment
		(start 93.84792 -159.394144)
		(end 94.27972 -159.825944)
		(width 0.508)
		(layer "B.Cu")
		(net "P3V3_STBY")
	)
	(segment
		(start 73.224644 -151.998426)
		(end 73.224644 -149.17547)
		(width 0.508)
		(layer "B.Cu")
		(net "P3V3_STBY")
	)
	(segment
		(start 73.224644 -146.37258)
		(end 73.224644 -145.761456)
		(width 0.508)
		(layer "B.Cu")
		(net "P3V3_STBY")
	)
	(segment
		(start 58.511948 -157.065472)
		(end 58.511948 -155.558998)
		(width 0.508)
		(layer "B.Cu")
		(net "P3V3_STBY")
	)
	(segment
		(start 61.3029 -139.0015)
		(end 61.6458 -139.3444)
		(width 0.508)
		(layer "B.Cu")
		(net "P3V3_STBY")
	)
	(segment
		(start 47.625 -133.0198)
		(end 47.68342 -132.96138)
		(width 0.508)
		(layer "B.Cu")
		(net "P3V3_STBY")
	)
	(segment
		(start 66.9036 -135.001)
		(end 66.7893 -135.001)
		(width 0.508)
		(layer "B.Cu")
		(net "P3V3_STBY")
	)
	(segment
		(start 41.3258 -124.552964)
		(end 41.85031 -124.028454)
		(width 0.508)
		(layer "B.Cu")
		(net "P3V3_STBY")
	)
	(segment
		(start 172.540422 -5.1816)
		(end 169.848022 -2.4892)
		(width 0.508)
		(layer "B.Cu")
		(net "P3V3_STBY")
	)
	(segment
		(start 58.5216 -148.8186)
		(end 59.6138 -147.7264)
		(width 0.508)
		(layer "B.Cu")
		(net "P3V3_STBY")
	)
	(segment
		(start 90.0303 -152.4254)
		(end 91.8464 -152.4254)
		(width 0.508)
		(layer "B.Cu")
		(net "P3V3_STBY")
	)
	(segment
		(start 79.9719 -173.0756)
		(end 80.6196 -173.0756)
		(width 0.508)
		(layer "B.Cu")
		(net "P3V3_STBY")
	)
	(segment
		(start 180.848 -112.2934)
		(end 179.8066 -111.252)
		(width 0.635)
		(layer "B.Cu")
		(net "P3V3_STBY")
	)
	(segment
		(start 89.940892 -136.276334)
		(end 90.337386 -135.87984)
		(width 0.3556)
		(layer "B.Cu")
		(net "P3V3_STBY")
	)
	(segment
		(start 74.199242 -146.788886)
		(end 74.127106 -146.861022)
		(width 0.3556)
		(layer "B.Cu")
		(net "P3V3_STBY")
	)
	(segment
		(start 58.837068 -157.542484)
		(end 58.436002 -157.141418)
		(width 0.508)
		(layer "B.Cu")
		(net "P3V3_STBY")
	)
	(segment
		(start 89.831926 -152.623774)
		(end 90.0303 -152.4254)
		(width 0.508)
		(layer "B.Cu")
		(net "P3V3_STBY")
	)
	(segment
		(start 64.1223 -137.0711)
		(end 64.1096 -137.0584)
		(width 0.508)
		(layer "B.Cu")
		(net "P3V3_STBY")
	)
	(segment
		(start 46.186344 -149.800056)
		(end 46.7487 -149.2377)
		(width 0.508)
		(layer "B.Cu")
		(net "P3V3_STBY")
	)
	(segment
		(start 73.224644 -149.17547)
		(end 71.914258 -149.17547)
		(width 0.508)
		(layer "B.Cu")
		(net "P3V3_STBY")
	)
	(segment
		(start 206.11846 -90.266266)
		(end 207.6958 -91.843606)
		(width 0.635)
		(layer "B.Cu")
		(net "P3V3_STBY")
	)
	(segment
		(start 53.9242 -134.402322)
		(end 53.9242 -134.366)
		(width 0.508)
		(layer "B.Cu")
		(net "P3V3_STBY")
	)
	(segment
		(start 63.841884 -141.2494)
		(end 63.227712 -141.863572)
		(width 0.508)
		(layer "B.Cu")
		(net "P3V3_STBY")
	)
	(segment
		(start 54.8513 -123.7615)
		(end 54.650132 -123.560332)
		(width 0.508)
		(layer "B.Cu")
		(net "P3V3_STBY")
	)
	(segment
		(start 93.37548 -152.289256)
		(end 93.37548 -151.524716)
		(width 0.508)
		(layer "B.Cu")
		(net "P3V3_STBY")
	)
	(segment
		(start 169.848022 -2.4892)
		(end 90.6526 -2.4892)
		(width 0.508)
		(layer "B.Cu")
		(net "P3V3_STBY")
	)
	(segment
		(start 25.7937 -47.18304)
		(end 15.739872 -57.236868)
		(width 0.508)
		(layer "In2.Cu")
		(net "P3V3_STBY")
	)
	(segment
		(start 23.973282 -16.95577)
		(end 25.7937 -18.776188)
		(width 0.508)
		(layer "In2.Cu")
		(net "P3V3_STBY")
	)
	(segment
		(start 188.087 -109.474)
		(end 186.7662 -109.474)
		(width 0.635)
		(layer "In2.Cu")
		(net "P3V3_STBY")
	)
	(segment
		(start 166.023036 -122.43943)
		(end 166.023036 -130.494278)
		(width 0.508)
		(layer "In2.Cu")
		(net "P3V3_STBY")
	)
	(segment
		(start 15.739872 -57.236868)
		(end 15.739872 -63.137288)
		(width 0.508)
		(layer "In2.Cu")
		(net "P3V3_STBY")
	)
	(segment
		(start 184.2008 -112.2934)
		(end 183.4642 -113.03)
		(width 0.635)
		(layer "In2.Cu")
		(net "P3V3_STBY")
	)
	(segment
		(start 183.4642 -113.03)
		(end 181.5846 -113.03)
		(width 0.635)
		(layer "In2.Cu")
		(net "P3V3_STBY")
	)
	(segment
		(start 201.9046 -112.0394)
		(end 201.9046 -107.569)
		(width 0.635)
		(layer "In2.Cu")
		(net "P3V3_STBY")
	)
	(segment
		(start 15.739872 -63.137288)
		(end 25.5651 -72.962516)
		(width 0.508)
		(layer "In2.Cu")
		(net "P3V3_STBY")
	)
	(segment
		(start 25.5651 -119.6213)
		(end 24.9936 -120.1928)
		(width 0.508)
		(layer "In2.Cu")
		(net "P3V3_STBY")
	)
	(segment
		(start 82.166968 -54.415436)
		(end 81.095088 -53.343556)
		(width 0.635)
		(layer "In2.Cu")
		(net "P3V3_STBY")
	)
	(segment
		(start 191.2366 -135.89)
		(end 191.4652 -135.89)
		(width 0.508)
		(layer "In2.Cu")
		(net "P3V3_STBY")
	)
	(segment
		(start 177.36185 -111.32947)
		(end 176.421796 -112.04067)
		(width 0.508)
		(layer "In2.Cu")
		(net "P3V3_STBY")
	)
	(segment
		(start 184.422542 -131.123944)
		(end 187.710826 -134.412228)
		(width 0.508)
		(layer "In2.Cu")
		(net "P3V3_STBY")
	)
	(segment
		(start 25.7937 -18.776188)
		(end 25.7937 -47.18304)
		(width 0.508)
		(layer "In2.Cu")
		(net "P3V3_STBY")
	)
	(segment
		(start 17.275302 -14.351)
		(end 9.779 -14.351)
		(width 0.508)
		(layer "In2.Cu")
		(net "P3V3_STBY")
	)
	(segment
		(start 19.880072 -16.95577)
		(end 17.275302 -14.351)
		(width 0.508)
		(layer "In2.Cu")
		(net "P3V3_STBY")
	)
	(segment
		(start 187.710826 -134.412228)
		(end 189.758828 -134.412228)
		(width 0.508)
		(layer "In2.Cu")
		(net "P3V3_STBY")
	)
	(segment
		(start 175.20539 -8.763)
		(end 174.220378 -7.777988)
		(width 0.508)
		(layer "In2.Cu")
		(net "P3V3_STBY")
	)
	(segment
		(start 204.518768 -112.778032)
		(end 205.2574 -112.0394)
		(width 0.635)
		(layer "In2.Cu")
		(net "P3V3_STBY")
	)
	(segment
		(start 164.99586 -97.973896)
		(end 177.36185 -110.339886)
		(width 0.508)
		(layer "In2.Cu")
		(net "P3V3_STBY")
	)
	(segment
		(start 25.5651 -72.962516)
		(end 25.5651 -119.6213)
		(width 0.508)
		(layer "In2.Cu")
		(net "P3V3_STBY")
	)
	(segment
		(start 166.023036 -130.494278)
		(end 166.652702 -131.123944)
		(width 0.508)
		(layer "In2.Cu")
		(net "P3V3_STBY")
	)
	(segment
		(start 203.831444 -105.286556)
		(end 203.831444 -102.797356)
		(width 0.635)
		(layer "In2.Cu")
		(net "P3V3_STBY")
	)
	(segment
		(start 180.6702 -107.6452)
		(end 180.848 -107.823)
		(width 0.635)
		(layer "In2.Cu")
		(net "P3V3_STBY")
	)
	(segment
		(start 164.99586 -28.965144)
		(end 164.99586 -97.973896)
		(width 0.508)
		(layer "In2.Cu")
		(net "P3V3_STBY")
	)
	(segment
		(start 201.7268 -107.3912)
		(end 203.831444 -105.286556)
		(width 0.635)
		(layer "In2.Cu")
		(net "P3V3_STBY")
	)
	(segment
		(start 176.421796 -112.04067)
		(end 166.023036 -122.43943)
		(width 0.508)
		(layer "In2.Cu")
		(net "P3V3_STBY")
	)
	(segment
		(start 180.848 -107.823)
		(end 180.848 -112.2934)
		(width 0.635)
		(layer "In2.Cu")
		(net "P3V3_STBY")
	)
	(segment
		(start 177.36185 -110.339886)
		(end 177.36185 -111.32947)
		(width 0.508)
		(layer "In2.Cu")
		(net "P3V3_STBY")
	)
	(segment
		(start 201.9046 -112.0394)
		(end 202.643232 -112.778032)
		(width 0.635)
		(layer "In2.Cu")
		(net "P3V3_STBY")
	)
	(segment
		(start 202.643232 -112.778032)
		(end 204.518768 -112.778032)
		(width 0.635)
		(layer "In2.Cu")
		(net "P3V3_STBY")
	)
	(segment
		(start 16.659606 -171.704)
		(end 14.2494 -171.704)
		(width 0.508)
		(layer "In2.Cu")
		(net "P3V3_STBY")
	)
	(segment
		(start 201.9046 -107.569)
		(end 201.7268 -107.3912)
		(width 0.635)
		(layer "In2.Cu")
		(net "P3V3_STBY")
	)
	(segment
		(start 166.652702 -131.123944)
		(end 184.422542 -131.123944)
		(width 0.508)
		(layer "In2.Cu")
		(net "P3V3_STBY")
	)
	(segment
		(start 19.880072 -16.95577)
		(end 23.973282 -16.95577)
		(width 0.508)
		(layer "In2.Cu")
		(net "P3V3_STBY")
	)
	(segment
		(start 181.5846 -113.03)
		(end 180.848 -112.2934)
		(width 0.635)
		(layer "In2.Cu")
		(net "P3V3_STBY")
	)
	(segment
		(start 81.095088 -53.343556)
		(end 77.688948 -53.343556)
		(width 0.635)
		(layer "In2.Cu")
		(net "P3V3_STBY")
	)
	(segment
		(start 21.851112 -176.895506)
		(end 16.659606 -171.704)
		(width 0.508)
		(layer "In2.Cu")
		(net "P3V3_STBY")
	)
	(segment
		(start 197.485 -8.763)
		(end 175.20539 -8.763)
		(width 0.508)
		(layer "In2.Cu")
		(net "P3V3_STBY")
	)
	(segment
		(start 189.758828 -134.412228)
		(end 191.2366 -135.89)
		(width 0.508)
		(layer "In2.Cu")
		(net "P3V3_STBY")
	)
	(segment
		(start 186.7662 -109.474)
		(end 184.2008 -112.2934)
		(width 0.635)
		(layer "In2.Cu")
		(net "P3V3_STBY")
	)
	(segment
		(start 203.831444 -102.797356)
		(end 206.0702 -100.5586)
		(width 0.635)
		(layer "In2.Cu")
		(net "P3V3_STBY")
	)
	(segment
		(start 188.087 -109.474)
		(end 198.042022 -109.474)
		(width 0.635)
		(layer "In5.Cu")
		(net "P3V3_STBY")
	)
	(segment
		(start 80.38211 -181.880002)
		(end 80.702912 -181.5592)
		(width 0.508)
		(layer "In5.Cu")
		(net "P3V3_STBY")
	)
	(segment
		(start 83.058 -181.5592)
		(end 83.8962 -180.721)
		(width 0.508)
		(layer "In5.Cu")
		(net "P3V3_STBY")
	)
	(segment
		(start 198.042022 -109.474)
		(end 200.124822 -107.3912)
		(width 0.635)
		(layer "In5.Cu")
		(net "P3V3_STBY")
	)
	(segment
		(start 94.4626 -180.721)
		(end 94.5134 -180.7718)
		(width 0.508)
		(layer "In5.Cu")
		(net "P3V3_STBY")
	)
	(segment
		(start 97.4344 -180.7972)
		(end 97.409 -180.7718)
		(width 0.508)
		(layer "In5.Cu")
		(net "P3V3_STBY")
	)
	(segment
		(start 83.8962 -180.721)
		(end 94.4626 -180.721)
		(width 0.508)
		(layer "In5.Cu")
		(net "P3V3_STBY")
	)
	(segment
		(start 97.409 -180.7718)
		(end 94.5134 -180.7718)
		(width 0.508)
		(layer "In5.Cu")
		(net "P3V3_STBY")
	)
	(segment
		(start 200.124822 -107.3912)
		(end 201.7268 -107.3912)
		(width 0.635)
		(layer "In5.Cu")
		(net "P3V3_STBY")
	)
	(segment
		(start 80.702912 -181.5592)
		(end 83.058 -181.5592)
		(width 0.508)
		(layer "In5.Cu")
		(net "P3V3_STBY")
	)
	(segment
		(start 161.708338 -15.330678)
		(end 162.178238 -15.330678)
		(width 0.254)
		(layer "F.Cu")
		(net "P1V8_STBY_VFB_R")
	)
	(segment
		(start 161.708338 -16.3322)
		(end 161.708338 -15.330678)
		(width 0.254)
		(layer "F.Cu")
		(net "P1V8_STBY_VFB_R")
	)
	(segment
		(start 162.178238 -15.330678)
		(end 162.902138 -16.054578)
		(width 0.254)
		(layer "F.Cu")
		(net "P1V8_STBY_VFB_R")
	)
	(via
		(at 161.708338 -16.3322)
		(size 0.508)
		(drill 0.254)
		(layers "F.Cu" "B.Cu")
		(net "P1V8_STBY_VFB_R")
	)
	(via
		(at 153.377138 -15.432278)
		(size 0.6096)
		(drill 0.3048)
		(layers "F.Cu" "B.Cu")
		(net "P1V8_STBY_VFB_R")
	)
	(segment
		(start 151.55164 -16.105378)
		(end 149.630638 -16.105378)
		(width 0.254)
		(layer "B.Cu")
		(net "P1V8_STBY_VFB_R")
	)
	(segment
		(start 160.808416 -15.432278)
		(end 161.708338 -16.3322)
		(width 0.254)
		(layer "B.Cu")
		(net "P1V8_STBY_VFB_R")
	)
	(segment
		(start 153.377138 -15.432278)
		(end 152.22474 -15.432278)
		(width 0.254)
		(layer "B.Cu")
		(net "P1V8_STBY_VFB_R")
	)
	(segment
		(start 153.377138 -15.432278)
		(end 160.808416 -15.432278)
		(width 0.254)
		(layer "B.Cu")
		(net "P1V8_STBY_VFB_R")
	)
	(segment
		(start 149.630638 -16.105378)
		(end 148.957538 -15.432278)
		(width 0.254)
		(layer "B.Cu")
		(net "P1V8_STBY_VFB_R")
	)
	(segment
		(start 152.22474 -15.432278)
		(end 151.55164 -16.105378)
		(width 0.254)
		(layer "B.Cu")
		(net "P1V8_STBY_VFB_R")
	)
	(segment
		(start 151.294338 -12.828778)
		(end 151.951436 -12.17168)
		(width 0.254)
		(layer "F.Cu")
		(net "P1V8_STBY_VFB")
	)
	(segment
		(start 149.948138 -14.543278)
		(end 149.008338 -14.543278)
		(width 0.254)
		(layer "F.Cu")
		(net "P1V8_STBY_VFB")
	)
	(segment
		(start 149.743668 -12.828778)
		(end 151.294338 -12.828778)
		(width 0.254)
		(layer "F.Cu")
		(net "P1V8_STBY_VFB")
	)
	(segment
		(start 151.951436 -12.17168)
		(end 152.374092 -12.17168)
		(width 0.254)
		(layer "F.Cu")
		(net "P1V8_STBY_VFB")
	)
	(segment
		(start 149.72538 -12.949936)
		(end 149.035516 -13.6398)
		(width 0.254)
		(layer "F.Cu")
		(net "P1V8_STBY_VFB")
	)
	(segment
		(start 149.035516 -13.6398)
		(end 149.035516 -13.707618)
		(width 0.254)
		(layer "F.Cu")
		(net "P1V8_STBY_VFB")
	)
	(segment
		(start 149.72538 -12.81049)
		(end 149.743668 -12.828778)
		(width 0.254)
		(layer "F.Cu")
		(net "P1V8_STBY_VFB")
	)
	(segment
		(start 149.008338 -14.543278)
		(end 149.008338 -13.734796)
		(width 0.254)
		(layer "F.Cu")
		(net "P1V8_STBY_VFB")
	)
	(segment
		(start 149.72538 -12.81049)
		(end 149.72538 -12.949936)
		(width 0.254)
		(layer "F.Cu")
		(net "P1V8_STBY_VFB")
	)
	(segment
		(start 149.008338 -13.734796)
		(end 149.035516 -13.707618)
		(width 0.254)
		(layer "F.Cu")
		(net "P1V8_STBY_VFB")
	)
	(via
		(at 150.202138 -13.692378)
		(size 0.6096)
		(drill 0.3048)
		(layers "F.Cu" "B.Cu")
		(net "P1V8_STBY_VFB")
	)
	(via
		(at 149.035516 -13.707618)
		(size 0.508)
		(drill 0.254)
		(layers "F.Cu" "B.Cu")
		(net "P1V8_STBY_VFB")
	)
	(segment
		(start 148.957538 -14.543278)
		(end 149.757638 -14.543278)
		(width 0.254)
		(layer "B.Cu")
		(net "P1V8_STBY_VFB")
	)
	(segment
		(start 149.757638 -14.543278)
		(end 150.202138 -14.098778)
		(width 0.254)
		(layer "B.Cu")
		(net "P1V8_STBY_VFB")
	)
	(segment
		(start 150.202138 -14.098778)
		(end 150.202138 -13.692378)
		(width 0.254)
		(layer "B.Cu")
		(net "P1V8_STBY_VFB")
	)
	(segment
		(start 150.202138 -13.692378)
		(end 149.050756 -13.692378)
		(width 0.254)
		(layer "B.Cu")
		(net "P1V8_STBY_VFB")
	)
	(segment
		(start 149.050756 -13.692378)
		(end 149.035516 -13.707618)
		(width 0.254)
		(layer "B.Cu")
		(net "P1V8_STBY_VFB")
	)
	(segment
		(start 156.43606 -12.17168)
		(end 157.110684 -12.846304)
		(width 0.3048)
		(layer "F.Cu")
		(net "P1V8_STBY_VBST")
	)
	(segment
		(start 157.110684 -12.846304)
		(end 157.110684 -14.005052)
		(width 0.508)
		(layer "F.Cu")
		(net "P1V8_STBY_VBST")
	)
	(segment
		(start 155.47594 -12.17168)
		(end 156.43606 -12.17168)
		(width 0.3048)
		(layer "F.Cu")
		(net "P1V8_STBY_VBST")
	)
	(via
		(at 157.110684 -12.846304)
		(size 0.6604)
		(drill 0.3302)
		(layers "F.Cu" "B.Cu")
		(net "P1V8_STBY_VBST")
	)
	(segment
		(start 158.124398 -6.393688)
		(end 158.124398 -7.867904)
		(width 0.508)
		(layer "F.Cu")
		(net "P1V8_STBY_SNB")
	)
	(segment
		(start 157.819344 -6.088634)
		(end 156.681678 -6.088634)
		(width 0.508)
		(layer "F.Cu")
		(net "P1V8_STBY_SNB")
	)
	(segment
		(start 158.080456 -6.349746)
		(end 158.124398 -6.393688)
		(width 0.508)
		(layer "F.Cu")
		(net "P1V8_STBY_SNB")
	)
	(segment
		(start 158.080456 -6.349746)
		(end 157.819344 -6.088634)
		(width 0.508)
		(layer "F.Cu")
		(net "P1V8_STBY_SNB")
	)
	(via
		(at 158.080456 -6.349746)
		(size 0.6604)
		(drill 0.3302)
		(layers "F.Cu" "B.Cu")
		(net "P1V8_STBY_SNB")
	)
	(segment
		(start 50.099722 -140.20038)
		(end 49.70018 -140.599922)
		(width 0.3048)
		(layer "F.Cu")
		(net "P1V8_STBY")
	)
	(segment
		(start 162.927538 -10.847578)
		(end 164.089334 -10.847578)
		(width 0.254)
		(layer "F.Cu")
		(net "P1V8_STBY")
	)
	(segment
		(start 162.495738 -11.279378)
		(end 162.927538 -10.847578)
		(width 0.254)
		(layer "F.Cu")
		(net "P1V8_STBY")
	)
	(segment
		(start 164.134546 -10.847578)
		(end 164.089334 -10.847578)
		(width 0.254)
		(layer "F.Cu")
		(net "P1V8_STBY")
	)
	(segment
		(start 171.106338 -9.183878)
		(end 171.106338 -9.511538)
		(width 0.1016)
		(layer "F.Cu")
		(net "P1V8_STBY")
	)
	(segment
		(start 206.019146 -120.327166)
		(end 206.019146 -119.481854)
		(width 0.508)
		(layer "F.Cu")
		(net "P1V8_STBY")
	)
	(segment
		(start 56.7436 -163.90239)
		(end 56.645302 -164.000688)
		(width 0.508)
		(layer "F.Cu")
		(net "P1V8_STBY")
	)
	(segment
		(start 162.902138 -14.530578)
		(end 162.902138 -14.286738)
		(width 0.254)
		(layer "F.Cu")
		(net "P1V8_STBY")
	)
	(segment
		(start 49.299622 -140.20038)
		(end 48.90008 -140.599922)
		(width 0.3048)
		(layer "F.Cu")
		(net "P1V8_STBY")
	)
	(segment
		(start 181.064154 -119.43207)
		(end 181.069996 -119.426228)
		(width 0.508)
		(layer "F.Cu")
		(net "P1V8_STBY")
	)
	(segment
		(start 48.90008 -140.599922)
		(end 48.899826 -140.599922)
		(width 0.3048)
		(layer "F.Cu")
		(net "P1V8_STBY")
	)
	(segment
		(start 49.70018 -140.599922)
		(end 49.699926 -140.599922)
		(width 0.3048)
		(layer "F.Cu")
		(net "P1V8_STBY")
	)
	(segment
		(start 56.7436 -162.9283)
		(end 56.7436 -163.90239)
		(width 0.508)
		(layer "F.Cu")
		(net "P1V8_STBY")
	)
	(segment
		(start 162.902138 -14.286738)
		(end 162.495738 -13.880338)
		(width 0.254)
		(layer "F.Cu")
		(net "P1V8_STBY")
	)
	(segment
		(start 181.064154 -120.607328)
		(end 181.064154 -119.43207)
		(width 0.508)
		(layer "F.Cu")
		(net "P1V8_STBY")
	)
	(segment
		(start 206.019146 -119.481854)
		(end 206.030068 -119.470932)
		(width 0.508)
		(layer "F.Cu")
		(net "P1V8_STBY")
	)
	(segment
		(start 162.495738 -13.880338)
		(end 162.495738 -11.279378)
		(width 0.254)
		(layer "F.Cu")
		(net "P1V8_STBY")
	)
	(via
		(at 175.22825 -118.004844)
		(size 0.7112)
		(drill 0.4064)
		(layers "F.Cu" "B.Cu")
		(net "P1V8_STBY")
	)
	(via
		(at 164.82314 -10.18286)
		(size 0.6096)
		(drill 0.3048)
		(layers "F.Cu" "B.Cu")
		(net "P1V8_STBY")
	)
	(via
		(at 211.2391 -107.343448)
		(size 0.508)
		(drill 0.254)
		(layers "F.Cu" "B.Cu")
		(net "P1V8_STBY")
	)
	(via
		(at 167.284654 -11.877294)
		(size 0.7112)
		(drill 0.4064)
		(layers "F.Cu" "B.Cu")
		(net "P1V8_STBY")
	)
	(via
		(at 81.788 -165.882574)
		(size 0.7112)
		(drill 0.4064)
		(layers "F.Cu" "B.Cu")
		(net "P1V8_STBY")
	)
	(via
		(at 80.5688 -165.882574)
		(size 0.7112)
		(drill 0.4064)
		(layers "F.Cu" "B.Cu")
		(net "P1V8_STBY")
	)
	(via
		(at 170.05427 -10.478516)
		(size 0.6096)
		(drill 0.3048)
		(layers "F.Cu" "B.Cu")
		(net "P1V8_STBY")
	)
	(via
		(at 19.443446 -172.858938)
		(size 0.7112)
		(drill 0.4064)
		(layers "F.Cu" "B.Cu")
		(net "P1V8_STBY")
	)
	(via
		(at 26.40076 -161.40684)
		(size 0.7112)
		(drill 0.4064)
		(layers "F.Cu" "B.Cu")
		(net "P1V8_STBY")
	)
	(via
		(at 179.677314 -122.988832)
		(size 0.508)
		(drill 0.254)
		(layers "F.Cu" "B.Cu")
		(net "P1V8_STBY")
	)
	(via
		(at 64.680592 -189.347602)
		(size 0.508)
		(drill 0.254)
		(layers "F.Cu" "B.Cu")
		(net "P1V8_STBY")
	)
	(via
		(at 50.099722 -140.20038)
		(size 0.4572)
		(drill 0.2032)
		(layers "F.Cu" "B.Cu")
		(net "P1V8_STBY")
	)
	(via
		(at 181.069996 -119.426228)
		(size 0.508)
		(drill 0.254)
		(layers "F.Cu" "B.Cu")
		(net "P1V8_STBY")
	)
	(via
		(at 166.014654 -13.147294)
		(size 0.7112)
		(drill 0.4064)
		(layers "F.Cu" "B.Cu")
		(net "P1V8_STBY")
	)
	(via
		(at 19.443446 -171.588938)
		(size 0.7112)
		(drill 0.4064)
		(layers "F.Cu" "B.Cu")
		(net "P1V8_STBY")
	)
	(via
		(at 205.486 -109.0676)
		(size 0.7112)
		(drill 0.4064)
		(layers "F.Cu" "B.Cu")
		(net "P1V8_STBY")
	)
	(via
		(at 170.97756 -10.5664)
		(size 0.6604)
		(drill 0.3302)
		(layers "F.Cu" "B.Cu")
		(net "P1V8_STBY")
	)
	(via
		(at 20.713446 -172.858938)
		(size 0.7112)
		(drill 0.4064)
		(layers "F.Cu" "B.Cu")
		(net "P1V8_STBY")
	)
	(via
		(at 176.80178 -122.805444)
		(size 0.508)
		(drill 0.254)
		(layers "F.Cu" "B.Cu")
		(net "P1V8_STBY")
	)
	(via
		(at 49.299622 -140.20038)
		(size 0.4572)
		(drill 0.2032)
		(layers "F.Cu" "B.Cu")
		(net "P1V8_STBY")
	)
	(via
		(at 169.824654 -11.877294)
		(size 0.7112)
		(drill 0.4064)
		(layers "F.Cu" "B.Cu")
		(net "P1V8_STBY")
	)
	(via
		(at 56.645302 -164.000688)
		(size 0.508)
		(drill 0.254)
		(layers "F.Cu" "B.Cu")
		(net "P1V8_STBY")
	)
	(via
		(at 168.554654 -11.877294)
		(size 0.7112)
		(drill 0.4064)
		(layers "F.Cu" "B.Cu")
		(net "P1V8_STBY")
	)
	(via
		(at 169.824654 -13.147294)
		(size 0.7112)
		(drill 0.4064)
		(layers "F.Cu" "B.Cu")
		(net "P1V8_STBY")
	)
	(via
		(at 168.554654 -13.147294)
		(size 0.7112)
		(drill 0.4064)
		(layers "F.Cu" "B.Cu")
		(net "P1V8_STBY")
	)
	(via
		(at 166.014654 -11.877294)
		(size 0.7112)
		(drill 0.4064)
		(layers "F.Cu" "B.Cu")
		(net "P1V8_STBY")
	)
	(via
		(at 167.284654 -13.147294)
		(size 0.7112)
		(drill 0.4064)
		(layers "F.Cu" "B.Cu")
		(net "P1V8_STBY")
	)
	(via
		(at 206.030068 -119.470932)
		(size 0.508)
		(drill 0.254)
		(layers "F.Cu" "B.Cu")
		(net "P1V8_STBY")
	)
	(via
		(at 206.163672 -110.160562)
		(size 0.508)
		(drill 0.254)
		(layers "F.Cu" "B.Cu")
		(net "P1V8_STBY")
	)
	(via
		(at 78.1304 -165.882574)
		(size 0.7112)
		(drill 0.4064)
		(layers "F.Cu" "B.Cu")
		(net "P1V8_STBY")
	)
	(via
		(at 20.713446 -171.588938)
		(size 0.7112)
		(drill 0.4064)
		(layers "F.Cu" "B.Cu")
		(net "P1V8_STBY")
	)
	(via
		(at 79.3496 -165.882574)
		(size 0.7112)
		(drill 0.4064)
		(layers "F.Cu" "B.Cu")
		(net "P1V8_STBY")
	)
	(segment
		(start 210.4517 -107.343448)
		(end 211.2391 -107.343448)
		(width 0.508)
		(layer "B.Cu")
		(net "P1V8_STBY")
	)
	(segment
		(start 179.677314 -122.988832)
		(end 178.902614 -122.988832)
		(width 0.508)
		(layer "B.Cu")
		(net "P1V8_STBY")
	)
	(segment
		(start 175.22825 -119.097044)
		(end 175.22825 -118.004844)
		(width 0.508)
		(layer "B.Cu")
		(net "P1V8_STBY")
	)
	(segment
		(start 20.713446 -171.588938)
		(end 23.406862 -171.588938)
		(width 0.508)
		(layer "In2.Cu")
		(net "P1V8_STBY")
	)
	(segment
		(start 176.80178 -119.578374)
		(end 176.80178 -122.805444)
		(width 0.635)
		(layer "In2.Cu")
		(net "P1V8_STBY")
	)
	(segment
		(start 56.645302 -164.000688)
		(end 56.3626 -164.28339)
		(width 0.508)
		(layer "In2.Cu")
		(net "P1V8_STBY")
	)
	(segment
		(start 58.87593 -175.3108)
		(end 62.611 -179.04587)
		(width 0.508)
		(layer "In2.Cu")
		(net "P1V8_STBY")
	)
	(segment
		(start 175.22825 -118.004844)
		(end 176.80178 -119.578374)
		(width 0.635)
		(layer "In2.Cu")
		(net "P1V8_STBY")
	)
	(segment
		(start 58.87593 -172.667676)
		(end 58.87593 -175.3108)
		(width 0.508)
		(layer "In2.Cu")
		(net "P1V8_STBY")
	)
	(segment
		(start 26.86304 -161.40684)
		(end 26.40076 -161.40684)
		(width 0.508)
		(layer "In2.Cu")
		(net "P1V8_STBY")
	)
	(segment
		(start 64.680592 -182.39867)
		(end 64.680592 -189.347602)
		(width 0.508)
		(layer "In2.Cu")
		(net "P1V8_STBY")
	)
	(segment
		(start 27.432 -167.5638)
		(end 27.432 -161.9758)
		(width 0.508)
		(layer "In2.Cu")
		(net "P1V8_STBY")
	)
	(segment
		(start 179.0446 -120.9548)
		(end 179.0446 -122.356118)
		(width 0.508)
		(layer "In2.Cu")
		(net "P1V8_STBY")
	)
	(segment
		(start 176.985168 -122.988832)
		(end 176.80178 -122.805444)
		(width 0.508)
		(layer "In2.Cu")
		(net "P1V8_STBY")
	)
	(segment
		(start 180.573172 -119.426228)
		(end 179.0446 -120.9548)
		(width 0.508)
		(layer "In2.Cu")
		(net "P1V8_STBY")
	)
	(segment
		(start 181.069996 -119.426228)
		(end 180.573172 -119.426228)
		(width 0.508)
		(layer "In2.Cu")
		(net "P1V8_STBY")
	)
	(segment
		(start 62.611 -180.329078)
		(end 64.680592 -182.39867)
		(width 0.508)
		(layer "In2.Cu")
		(net "P1V8_STBY")
	)
	(segment
		(start 27.432 -161.9758)
		(end 26.86304 -161.40684)
		(width 0.508)
		(layer "In2.Cu")
		(net "P1V8_STBY")
	)
	(segment
		(start 23.406862 -171.588938)
		(end 27.432 -167.5638)
		(width 0.508)
		(layer "In2.Cu")
		(net "P1V8_STBY")
	)
	(segment
		(start 179.0446 -122.356118)
		(end 179.677314 -122.988832)
		(width 0.508)
		(layer "In2.Cu")
		(net "P1V8_STBY")
	)
	(segment
		(start 56.3626 -170.154346)
		(end 58.87593 -172.667676)
		(width 0.508)
		(layer "In2.Cu")
		(net "P1V8_STBY")
	)
	(segment
		(start 62.611 -179.04587)
		(end 62.611 -180.329078)
		(width 0.508)
		(layer "In2.Cu")
		(net "P1V8_STBY")
	)
	(segment
		(start 56.3626 -164.28339)
		(end 56.3626 -170.154346)
		(width 0.508)
		(layer "In2.Cu")
		(net "P1V8_STBY")
	)
	(segment
		(start 179.677314 -122.988832)
		(end 176.985168 -122.988832)
		(width 0.508)
		(layer "In2.Cu")
		(net "P1V8_STBY")
	)
	(segment
		(start 203.475336 -120.273064)
		(end 204.277468 -119.470932)
		(width 0.635)
		(layer "In5.Cu")
		(net "P1V8_STBY")
	)
	(segment
		(start 47.8536 -141.7828)
		(end 48.514 -141.1224)
		(width 0.508)
		(layer "In5.Cu")
		(net "P1V8_STBY")
	)
	(segment
		(start 37.601144 -153.7335)
		(end 38.198044 -153.1366)
		(width 0.508)
		(layer "In5.Cu")
		(net "P1V8_STBY")
	)
	(segment
		(start 46.075346 -153.1366)
		(end 46.8376 -152.374346)
		(width 0.508)
		(layer "In5.Cu")
		(net "P1V8_STBY")
	)
	(segment
		(start 183.734202 -119.426228)
		(end 184.581038 -120.273064)
		(width 0.635)
		(layer "In5.Cu")
		(net "P1V8_STBY")
	)
	(segment
		(start 26.40076 -161.40684)
		(end 29.16936 -161.40684)
		(width 0.508)
		(layer "In5.Cu")
		(net "P1V8_STBY")
	)
	(segment
		(start 48.514 -140.708634)
		(end 49.022254 -140.20038)
		(width 0.508)
		(layer "In5.Cu")
		(net "P1V8_STBY")
	)
	(segment
		(start 175.3108 -112.304322)
		(end 177.0126 -114.006122)
		(width 0.635)
		(layer "In5.Cu")
		(net "P1V8_STBY")
	)
	(segment
		(start 181.069996 -119.426228)
		(end 183.734202 -119.426228)
		(width 0.635)
		(layer "In5.Cu")
		(net "P1V8_STBY")
	)
	(segment
		(start 30.0355 -153.7335)
		(end 37.601144 -153.7335)
		(width 0.508)
		(layer "In5.Cu")
		(net "P1V8_STBY")
	)
	(segment
		(start 30.4038 -158.8262)
		(end 29.5402 -157.9626)
		(width 0.508)
		(layer "In5.Cu")
		(net "P1V8_STBY")
	)
	(segment
		(start 46.8376 -152.374346)
		(end 46.8376 -148.2852)
		(width 0.508)
		(layer "In5.Cu")
		(net "P1V8_STBY")
	)
	(segment
		(start 49.022254 -140.20038)
		(end 49.299622 -140.20038)
		(width 0.508)
		(layer "In5.Cu")
		(net "P1V8_STBY")
	)
	(segment
		(start 206.163672 -110.160562)
		(end 206.163672 -119.337328)
		(width 0.635)
		(layer "In5.Cu")
		(net "P1V8_STBY")
	)
	(segment
		(start 175.3108 -94.27972)
		(end 175.3108 -112.304322)
		(width 0.635)
		(layer "In5.Cu")
		(net "P1V8_STBY")
	)
	(segment
		(start 206.163672 -110.160562)
		(end 206.163672 -109.978952)
		(width 0.635)
		(layer "In5.Cu")
		(net "P1V8_STBY")
	)
	(segment
		(start 38.198044 -153.1366)
		(end 46.075346 -153.1366)
		(width 0.508)
		(layer "In5.Cu")
		(net "P1V8_STBY")
	)
	(segment
		(start 205.486 -109.30128)
		(end 205.486 -109.0676)
		(width 0.635)
		(layer "In5.Cu")
		(net "P1V8_STBY")
	)
	(segment
		(start 206.972916 -107.343448)
		(end 211.2391 -107.343448)
		(width 0.635)
		(layer "In5.Cu")
		(net "P1V8_STBY")
	)
	(segment
		(start 175.049688 -94.018608)
		(end 175.3108 -94.27972)
		(width 0.635)
		(layer "In5.Cu")
		(net "P1V8_STBY")
	)
	(segment
		(start 29.5402 -157.9626)
		(end 29.5402 -154.2288)
		(width 0.508)
		(layer "In5.Cu")
		(net "P1V8_STBY")
	)
	(segment
		(start 48.514 -141.1224)
		(end 48.514 -140.708634)
		(width 0.508)
		(layer "In5.Cu")
		(net "P1V8_STBY")
	)
	(segment
		(start 168.554654 -32.611822)
		(end 175.049688 -39.106856)
		(width 0.635)
		(layer "In5.Cu")
		(net "P1V8_STBY")
	)
	(segment
		(start 184.581038 -120.273064)
		(end 203.475336 -120.273064)
		(width 0.635)
		(layer "In5.Cu")
		(net "P1V8_STBY")
	)
	(segment
		(start 29.5402 -154.2288)
		(end 30.0355 -153.7335)
		(width 0.508)
		(layer "In5.Cu")
		(net "P1V8_STBY")
	)
	(segment
		(start 46.8376 -148.2852)
		(end 46.2026 -147.6502)
		(width 0.508)
		(layer "In5.Cu")
		(net "P1V8_STBY")
	)
	(segment
		(start 29.16936 -161.40684)
		(end 30.4038 -160.1724)
		(width 0.508)
		(layer "In5.Cu")
		(net "P1V8_STBY")
	)
	(segment
		(start 175.049688 -39.106856)
		(end 175.049688 -94.018608)
		(width 0.635)
		(layer "In5.Cu")
		(net "P1V8_STBY")
	)
	(segment
		(start 206.163672 -119.337328)
		(end 206.030068 -119.470932)
		(width 0.635)
		(layer "In5.Cu")
		(net "P1V8_STBY")
	)
	(segment
		(start 205.486 -108.830364)
		(end 206.972916 -107.343448)
		(width 0.635)
		(layer "In5.Cu")
		(net "P1V8_STBY")
	)
	(segment
		(start 177.0126 -114.006122)
		(end 177.0126 -116.220494)
		(width 0.635)
		(layer "In5.Cu")
		(net "P1V8_STBY")
	)
	(segment
		(start 204.277468 -119.470932)
		(end 206.030068 -119.470932)
		(width 0.635)
		(layer "In5.Cu")
		(net "P1V8_STBY")
	)
	(segment
		(start 205.486 -109.0676)
		(end 205.486 -108.830364)
		(width 0.635)
		(layer "In5.Cu")
		(net "P1V8_STBY")
	)
	(segment
		(start 177.0126 -116.220494)
		(end 175.22825 -118.004844)
		(width 0.635)
		(layer "In5.Cu")
		(net "P1V8_STBY")
	)
	(segment
		(start 49.299622 -140.20038)
		(end 50.099722 -140.20038)
		(width 0.508)
		(layer "In5.Cu")
		(net "P1V8_STBY")
	)
	(segment
		(start 168.554654 -13.147294)
		(end 168.554654 -32.611822)
		(width 0.635)
		(layer "In5.Cu")
		(net "P1V8_STBY")
	)
	(segment
		(start 46.2026 -142.367)
		(end 46.7868 -141.7828)
		(width 0.508)
		(layer "In5.Cu")
		(net "P1V8_STBY")
	)
	(segment
		(start 46.7868 -141.7828)
		(end 47.8536 -141.7828)
		(width 0.508)
		(layer "In5.Cu")
		(net "P1V8_STBY")
	)
	(segment
		(start 206.163672 -109.978952)
		(end 205.486 -109.30128)
		(width 0.635)
		(layer "In5.Cu")
		(net "P1V8_STBY")
	)
	(segment
		(start 30.4038 -160.1724)
		(end 30.4038 -158.8262)
		(width 0.508)
		(layer "In5.Cu")
		(net "P1V8_STBY")
	)
	(segment
		(start 46.2026 -147.6502)
		(end 46.2026 -142.367)
		(width 0.508)
		(layer "In5.Cu")
		(net "P1V8_STBY")
	)
	(segment
		(start 41.300146 -140.20038)
		(end 40.900604 -140.599922)
		(width 0.3048)
		(layer "F.Cu")
		(net "MPLLAV33")
	)
	(segment
		(start 44.099988 -145.400014)
		(end 44.099734 -145.400014)
		(width 0.3556)
		(layer "F.Cu")
		(net "MPLLAV33")
	)
	(segment
		(start 41.699942 -140.599922)
		(end 41.699688 -140.599922)
		(width 0.3048)
		(layer "F.Cu")
		(net "MPLLAV33")
	)
	(segment
		(start 41.699688 -140.599922)
		(end 41.300146 -140.20038)
		(width 0.3048)
		(layer "F.Cu")
		(net "MPLLAV33")
	)
	(segment
		(start 40.900604 -140.599922)
		(end 40.899842 -140.599922)
		(width 0.3048)
		(layer "F.Cu")
		(net "MPLLAV33")
	)
	(segment
		(start 44.099734 -145.400014)
		(end 43.699938 -145.000218)
		(width 0.3556)
		(layer "F.Cu")
		(net "MPLLAV33")
	)
	(via
		(at 43.699938 -145.000218)
		(size 0.4572)
		(drill 0.2032)
		(layers "F.Cu" "B.Cu")
		(net "MPLLAV33")
	)
	(via
		(at 41.300146 -140.20038)
		(size 0.4572)
		(drill 0.2032)
		(layers "F.Cu" "B.Cu")
		(net "MPLLAV33")
	)
	(via
		(at 34.8234 -149.714458)
		(size 0.6096)
		(drill 0.3048)
		(layers "F.Cu" "B.Cu")
		(net "MPLLAV33")
	)
	(segment
		(start 43.293538 -144.593818)
		(end 43.699938 -145.000218)
		(width 0.127)
		(layer "B.Cu")
		(net "MPLLAV33")
	)
	(segment
		(start 33.9344 -151.6507)
		(end 32.9819 -151.6507)
		(width 0.508)
		(layer "B.Cu")
		(net "MPLLAV33")
	)
	(segment
		(start 37.98316 -147.7772)
		(end 35.7759 -147.7772)
		(width 0.508)
		(layer "B.Cu")
		(net "MPLLAV33")
	)
	(segment
		(start 41.075864 -144.606264)
		(end 41.463214 -144.606264)
		(width 0.127)
		(layer "B.Cu")
		(net "MPLLAV33")
	)
	(segment
		(start 42.493692 -144.836642)
		(end 42.493692 -145.475452)
		(width 0.127)
		(layer "B.Cu")
		(net "MPLLAV33")
	)
	(segment
		(start 41.660572 -140.593572)
		(end 42.263314 -140.593572)
		(width 0.127)
		(layer "B.Cu")
		(net "MPLLAV33")
	)
	(segment
		(start 38.369494 -147.390866)
		(end 37.98316 -147.7772)
		(width 0.508)
		(layer "B.Cu")
		(net "MPLLAV33")
	)
	(segment
		(start 39.2811 -145.52676)
		(end 38.912292 -145.52676)
		(width 0.508)
		(layer "B.Cu")
		(net "MPLLAV33")
	)
	(segment
		(start 38.912292 -145.52676)
		(end 38.369494 -146.069558)
		(width 0.508)
		(layer "B.Cu")
		(net "MPLLAV33")
	)
	(segment
		(start 42.50563 -144.362678)
		(end 42.73677 -144.593818)
		(width 0.127)
		(layer "B.Cu")
		(net "MPLLAV33")
	)
	(segment
		(start 43.644058 -145.000218)
		(end 43.117516 -145.52676)
		(width 0.381)
		(layer "B.Cu")
		(net "MPLLAV33")
	)
	(segment
		(start 40.893746 -141.351254)
		(end 40.893746 -144.424146)
		(width 0.127)
		(layer "B.Cu")
		(net "MPLLAV33")
	)
	(segment
		(start 42.73677 -144.593818)
		(end 43.293538 -144.593818)
		(width 0.127)
		(layer "B.Cu")
		(net "MPLLAV33")
	)
	(segment
		(start 31.5214 -151.4602)
		(end 31.1404 -151.0792)
		(width 0.508)
		(layer "B.Cu")
		(net "MPLLAV33")
	)
	(segment
		(start 34.8234 -151.6507)
		(end 33.9344 -151.6507)
		(width 0.508)
		(layer "B.Cu")
		(net "MPLLAV33")
	)
	(segment
		(start 32.9819 -151.6507)
		(end 32.7914 -151.4602)
		(width 0.508)
		(layer "B.Cu")
		(net "MPLLAV33")
	)
	(segment
		(start 42.263314 -140.593572)
		(end 42.50563 -140.835888)
		(width 0.127)
		(layer "B.Cu")
		(net "MPLLAV33")
	)
	(segment
		(start 41.693592 -144.36344)
		(end 41.936416 -144.606264)
		(width 0.127)
		(layer "B.Cu")
		(net "MPLLAV33")
	)
	(segment
		(start 41.936416 -144.606264)
		(end 42.263314 -144.606264)
		(width 0.127)
		(layer "B.Cu")
		(net "MPLLAV33")
	)
	(segment
		(start 42.50563 -140.835888)
		(end 42.50563 -144.362678)
		(width 0.127)
		(layer "B.Cu")
		(net "MPLLAV33")
	)
	(segment
		(start 32.7914 -151.4602)
		(end 31.5214 -151.4602)
		(width 0.508)
		(layer "B.Cu")
		(net "MPLLAV33")
	)
	(segment
		(start 43.117516 -145.52676)
		(end 42.545 -145.52676)
		(width 0.381)
		(layer "B.Cu")
		(net "MPLLAV33")
	)
	(segment
		(start 34.8234 -149.714458)
		(end 34.8234 -151.6507)
		(width 0.508)
		(layer "B.Cu")
		(net "MPLLAV33")
	)
	(segment
		(start 35.7759 -147.7772)
		(end 34.8234 -148.7297)
		(width 0.508)
		(layer "B.Cu")
		(net "MPLLAV33")
	)
	(segment
		(start 34.8234 -148.7297)
		(end 34.8234 -149.714458)
		(width 0.508)
		(layer "B.Cu")
		(net "MPLLAV33")
	)
	(segment
		(start 41.701466 -145.52676)
		(end 39.2811 -145.52676)
		(width 0.381)
		(layer "B.Cu")
		(net "MPLLAV33")
	)
	(segment
		(start 42.545 -145.52676)
		(end 41.701466 -145.52676)
		(width 0.381)
		(layer "B.Cu")
		(net "MPLLAV33")
	)
	(segment
		(start 40.893746 -144.424146)
		(end 41.075864 -144.606264)
		(width 0.127)
		(layer "B.Cu")
		(net "MPLLAV33")
	)
	(segment
		(start 41.706292 -145.521934)
		(end 41.701466 -145.52676)
		(width 0.127)
		(layer "B.Cu")
		(net "MPLLAV33")
	)
	(segment
		(start 38.369494 -146.069558)
		(end 38.369494 -147.390866)
		(width 0.508)
		(layer "B.Cu")
		(net "MPLLAV33")
	)
	(segment
		(start 41.706292 -144.849342)
		(end 41.706292 -145.521934)
		(width 0.127)
		(layer "B.Cu")
		(net "MPLLAV33")
	)
	(segment
		(start 41.463214 -144.606264)
		(end 41.706292 -144.849342)
		(width 0.127)
		(layer "B.Cu")
		(net "MPLLAV33")
	)
	(segment
		(start 42.263314 -144.606264)
		(end 42.493692 -144.836642)
		(width 0.127)
		(layer "B.Cu")
		(net "MPLLAV33")
	)
	(segment
		(start 42.493692 -145.475452)
		(end 42.545 -145.52676)
		(width 0.127)
		(layer "B.Cu")
		(net "MPLLAV33")
	)
	(segment
		(start 43.699938 -145.000218)
		(end 43.644058 -145.000218)
		(width 0.381)
		(layer "B.Cu")
		(net "MPLLAV33")
	)
	(segment
		(start 41.693592 -141.261592)
		(end 41.693592 -144.36344)
		(width 0.127)
		(layer "B.Cu")
		(net "MPLLAV33")
	)
	(segment
		(start 15.944088 -140.561314)
		(end 14.769338 -141.736064)
		(width 0.127)
		(layer "F.Cu")
		(net "MEMWEN")
	)
	(segment
		(start 12.47267 -142.347696)
		(end 12.34567 -142.220696)
		(width 0.127)
		(layer "F.Cu")
		(net "MEMWEN")
	)
	(segment
		(start 9.331198 -141.008862)
		(end 10.347198 -141.008862)
		(width 0.127)
		(layer "F.Cu")
		(net "MEMWEN")
	)
	(segment
		(start 12.21867 -141.736064)
		(end 11.96467 -141.736064)
		(width 0.127)
		(layer "F.Cu")
		(net "MEMWEN")
	)
	(segment
		(start 17.634458 -140.561822)
		(end 17.634458 -140.561568)
		(width 0.127)
		(layer "F.Cu")
		(net "MEMWEN")
	)
	(segment
		(start 11.83767 -141.863064)
		(end 11.83767 -142.220696)
		(width 0.127)
		(layer "F.Cu")
		(net "MEMWEN")
	)
	(segment
		(start 11.32967 -142.220696)
		(end 11.32967 -141.863064)
		(width 0.127)
		(layer "F.Cu")
		(net "MEMWEN")
	)
	(segment
		(start 11.20267 -141.736064)
		(end 11.0744 -141.736064)
		(width 0.127)
		(layer "F.Cu")
		(net "MEMWEN")
	)
	(segment
		(start 11.32967 -141.863064)
		(end 11.20267 -141.736064)
		(width 0.127)
		(layer "F.Cu")
		(net "MEMWEN")
	)
	(segment
		(start 40.900096 -144.599914)
		(end 40.899842 -144.599914)
		(width 0.127)
		(layer "F.Cu")
		(net "MEMWEN")
	)
	(segment
		(start 12.34567 -141.863064)
		(end 12.21867 -141.736064)
		(width 0.127)
		(layer "F.Cu")
		(net "MEMWEN")
	)
	(segment
		(start 15.953486 -140.561314)
		(end 15.944088 -140.561314)
		(width 0.127)
		(layer "F.Cu")
		(net "MEMWEN")
	)
	(segment
		(start 12.85367 -141.863064)
		(end 12.85367 -142.220696)
		(width 0.127)
		(layer "F.Cu")
		(net "MEMWEN")
	)
	(segment
		(start 41.299892 -144.200118)
		(end 40.900096 -144.599914)
		(width 0.127)
		(layer "F.Cu")
		(net "MEMWEN")
	)
	(segment
		(start 11.96467 -141.736064)
		(end 11.83767 -141.863064)
		(width 0.127)
		(layer "F.Cu")
		(net "MEMWEN")
	)
	(segment
		(start 16.296132 -140.218668)
		(end 15.953486 -140.561314)
		(width 0.127)
		(layer "F.Cu")
		(net "MEMWEN")
	)
	(segment
		(start 14.769338 -141.736064)
		(end 12.98067 -141.736064)
		(width 0.127)
		(layer "F.Cu")
		(net "MEMWEN")
	)
	(segment
		(start 17.291558 -140.218668)
		(end 16.296132 -140.218668)
		(width 0.127)
		(layer "F.Cu")
		(net "MEMWEN")
	)
	(segment
		(start 17.234662 -140.961618)
		(end 17.634458 -140.561822)
		(width 0.127)
		(layer "F.Cu")
		(net "MEMWEN")
	)
	(segment
		(start 11.0744 -141.736064)
		(end 10.347198 -141.008862)
		(width 0.127)
		(layer "F.Cu")
		(net "MEMWEN")
	)
	(segment
		(start 12.98067 -141.736064)
		(end 12.85367 -141.863064)
		(width 0.127)
		(layer "F.Cu")
		(net "MEMWEN")
	)
	(segment
		(start 12.34567 -142.220696)
		(end 12.34567 -141.863064)
		(width 0.127)
		(layer "F.Cu")
		(net "MEMWEN")
	)
	(segment
		(start 11.83767 -142.220696)
		(end 11.71067 -142.347696)
		(width 0.127)
		(layer "F.Cu")
		(net "MEMWEN")
	)
	(segment
		(start 11.45667 -142.347696)
		(end 11.32967 -142.220696)
		(width 0.127)
		(layer "F.Cu")
		(net "MEMWEN")
	)
	(segment
		(start 11.71067 -142.347696)
		(end 11.45667 -142.347696)
		(width 0.127)
		(layer "F.Cu")
		(net "MEMWEN")
	)
	(segment
		(start 17.634458 -140.561568)
		(end 17.291558 -140.218668)
		(width 0.127)
		(layer "F.Cu")
		(net "MEMWEN")
	)
	(segment
		(start 12.72667 -142.347696)
		(end 12.47267 -142.347696)
		(width 0.127)
		(layer "F.Cu")
		(net "MEMWEN")
	)
	(segment
		(start 12.85367 -142.220696)
		(end 12.72667 -142.347696)
		(width 0.127)
		(layer "F.Cu")
		(net "MEMWEN")
	)
	(via
		(at 17.234662 -140.961618)
		(size 0.508)
		(drill 0.254)
		(layers "F.Cu" "B.Cu")
		(net "MEMWEN")
	)
	(via
		(at 41.299892 -144.200118)
		(size 0.4572)
		(drill 0.2032)
		(layers "F.Cu" "B.Cu")
		(net "MEMWEN")
	)
	(segment
		(start 21.144738 -140.840968)
		(end 21.144738 -141.00556)
		(width 0.0889)
		(layer "In5.Cu")
		(net "MEMWEN")
	)
	(segment
		(start 27.400758 -141.93393)
		(end 27.400758 -141.754098)
		(width 0.127)
		(layer "In5.Cu")
		(net "MEMWEN")
	)
	(segment
		(start 20.433538 -141.00556)
		(end 20.344638 -141.09446)
		(width 0.0889)
		(layer "In5.Cu")
		(net "MEMWEN")
	)
	(segment
		(start 29.555948 -143.08582)
		(end 28.980638 -142.51051)
		(width 0.127)
		(layer "In5.Cu")
		(net "MEMWEN")
	)
	(segment
		(start 27.760168 -142.113508)
		(end 27.580336 -142.113508)
		(width 0.127)
		(layer "In5.Cu")
		(net "MEMWEN")
	)
	(segment
		(start 21.67001 -140.752068)
		(end 21.233638 -140.752068)
		(width 0.0889)
		(layer "In5.Cu")
		(net "MEMWEN")
	)
	(segment
		(start 40.81653 -143.933164)
		(end 40.79748 -143.91386)
		(width 0.127)
		(layer "In5.Cu")
		(net "MEMWEN")
	)
	(segment
		(start 22.362414 -140.56106)
		(end 21.861018 -140.56106)
		(width 0.0889)
		(layer "In5.Cu")
		(net "MEMWEN")
	)
	(segment
		(start 26.403808 -140.716762)
		(end 22.518116 -140.716762)
		(width 0.127)
		(layer "In5.Cu")
		(net "MEMWEN")
	)
	(segment
		(start 20.789138 -141.00556)
		(end 20.789138 -140.840968)
		(width 0.0889)
		(layer "In5.Cu")
		(net "MEMWEN")
	)
	(segment
		(start 22.518116 -140.716762)
		(end 22.362414 -140.56106)
		(width 0.127)
		(layer "In5.Cu")
		(net "MEMWEN")
	)
	(segment
		(start 20.700238 -140.752068)
		(end 20.522438 -140.752068)
		(width 0.0889)
		(layer "In5.Cu")
		(net "MEMWEN")
	)
	(segment
		(start 17.634712 -140.561568)
		(end 17.234662 -140.961618)
		(width 0.0889)
		(layer "In5.Cu")
		(net "MEMWEN")
	)
	(segment
		(start 27.400758 -141.754098)
		(end 27.722576 -141.43228)
		(width 0.127)
		(layer "In5.Cu")
		(net "MEMWEN")
	)
	(segment
		(start 21.055838 -141.09446)
		(end 20.878038 -141.09446)
		(width 0.0889)
		(layer "In5.Cu")
		(net "MEMWEN")
	)
	(segment
		(start 32.35452 -142.885414)
		(end 32.154114 -143.08582)
		(width 0.127)
		(layer "In5.Cu")
		(net "MEMWEN")
	)
	(segment
		(start 20.878038 -141.09446)
		(end 20.789138 -141.00556)
		(width 0.0889)
		(layer "In5.Cu")
		(net "MEMWEN")
	)
	(segment
		(start 20.077938 -140.840968)
		(end 19.989038 -140.752068)
		(width 0.0889)
		(layer "In5.Cu")
		(net "MEMWEN")
	)
	(segment
		(start 21.861018 -140.56106)
		(end 21.67001 -140.752068)
		(width 0.0889)
		(layer "In5.Cu")
		(net "MEMWEN")
	)
	(segment
		(start 26.51633 -140.60424)
		(end 26.403808 -140.716762)
		(width 0.127)
		(layer "In5.Cu")
		(net "MEMWEN")
	)
	(segment
		(start 28.261818 -141.79169)
		(end 28.081986 -141.79169)
		(width 0.127)
		(layer "In5.Cu")
		(net "MEMWEN")
	)
	(segment
		(start 28.441396 -142.1511)
		(end 28.441396 -141.971268)
		(width 0.127)
		(layer "In5.Cu")
		(net "MEMWEN")
	)
	(segment
		(start 28.478988 -142.832328)
		(end 28.299156 -142.832328)
		(width 0.127)
		(layer "In5.Cu")
		(net "MEMWEN")
	)
	(segment
		(start 20.166838 -141.09446)
		(end 20.077938 -141.00556)
		(width 0.0889)
		(layer "In5.Cu")
		(net "MEMWEN")
	)
	(segment
		(start 38.50513 -143.552164)
		(end 37.838634 -142.885668)
		(width 0.127)
		(layer "In5.Cu")
		(net "MEMWEN")
	)
	(segment
		(start 28.441396 -141.971268)
		(end 28.261818 -141.79169)
		(width 0.127)
		(layer "In5.Cu")
		(net "MEMWEN")
	)
	(segment
		(start 28.980638 -142.51051)
		(end 28.800806 -142.51051)
		(width 0.127)
		(layer "In5.Cu")
		(net "MEMWEN")
	)
	(segment
		(start 20.344638 -141.09446)
		(end 20.166838 -141.09446)
		(width 0.0889)
		(layer "In5.Cu")
		(net "MEMWEN")
	)
	(segment
		(start 37.838634 -142.885668)
		(end 33.02635 -142.885668)
		(width 0.127)
		(layer "In5.Cu")
		(net "MEMWEN")
	)
	(segment
		(start 20.522438 -140.752068)
		(end 20.433538 -140.840968)
		(width 0.0889)
		(layer "In5.Cu")
		(net "MEMWEN")
	)
	(segment
		(start 20.789138 -140.840968)
		(end 20.700238 -140.752068)
		(width 0.0889)
		(layer "In5.Cu")
		(net "MEMWEN")
	)
	(segment
		(start 18.647664 -140.752068)
		(end 18.457164 -140.561568)
		(width 0.0889)
		(layer "In5.Cu")
		(net "MEMWEN")
	)
	(segment
		(start 19.989038 -140.752068)
		(end 18.647664 -140.752068)
		(width 0.0889)
		(layer "In5.Cu")
		(net "MEMWEN")
	)
	(segment
		(start 18.457164 -140.561568)
		(end 17.634712 -140.561568)
		(width 0.0889)
		(layer "In5.Cu")
		(net "MEMWEN")
	)
	(segment
		(start 32.154114 -143.08582)
		(end 29.555948 -143.08582)
		(width 0.127)
		(layer "In5.Cu")
		(net "MEMWEN")
	)
	(segment
		(start 27.074368 -140.60424)
		(end 26.51633 -140.60424)
		(width 0.127)
		(layer "In5.Cu")
		(net "MEMWEN")
	)
	(segment
		(start 40.96893 -144.085564)
		(end 40.81653 -143.933164)
		(width 0.127)
		(layer "In5.Cu")
		(net "MEMWEN")
	)
	(segment
		(start 20.077938 -141.00556)
		(end 20.077938 -140.840968)
		(width 0.0889)
		(layer "In5.Cu")
		(net "MEMWEN")
	)
	(segment
		(start 27.580336 -142.113508)
		(end 27.400758 -141.93393)
		(width 0.127)
		(layer "In5.Cu")
		(net "MEMWEN")
	)
	(segment
		(start 27.722576 -141.252448)
		(end 27.074368 -140.60424)
		(width 0.127)
		(layer "In5.Cu")
		(net "MEMWEN")
	)
	(segment
		(start 28.081986 -141.79169)
		(end 27.760168 -142.113508)
		(width 0.127)
		(layer "In5.Cu")
		(net "MEMWEN")
	)
	(segment
		(start 28.119578 -142.65275)
		(end 28.119578 -142.472918)
		(width 0.127)
		(layer "In5.Cu")
		(net "MEMWEN")
	)
	(segment
		(start 21.233638 -140.752068)
		(end 21.144738 -140.840968)
		(width 0.0889)
		(layer "In5.Cu")
		(net "MEMWEN")
	)
	(segment
		(start 33.02635 -142.885668)
		(end 33.02635 -142.885414)
		(width 0.127)
		(layer "In5.Cu")
		(net "MEMWEN")
	)
	(segment
		(start 21.144738 -141.00556)
		(end 21.055838 -141.09446)
		(width 0.0889)
		(layer "In5.Cu")
		(net "MEMWEN")
	)
	(segment
		(start 28.119578 -142.472918)
		(end 28.441396 -142.1511)
		(width 0.127)
		(layer "In5.Cu")
		(net "MEMWEN")
	)
	(segment
		(start 20.433538 -140.840968)
		(end 20.433538 -141.00556)
		(width 0.0889)
		(layer "In5.Cu")
		(net "MEMWEN")
	)
	(segment
		(start 28.299156 -142.832328)
		(end 28.119578 -142.65275)
		(width 0.127)
		(layer "In5.Cu")
		(net "MEMWEN")
	)
	(segment
		(start 27.722576 -141.43228)
		(end 27.722576 -141.252448)
		(width 0.127)
		(layer "In5.Cu")
		(net "MEMWEN")
	)
	(segment
		(start 28.800806 -142.51051)
		(end 28.478988 -142.832328)
		(width 0.127)
		(layer "In5.Cu")
		(net "MEMWEN")
	)
	(segment
		(start 41.299892 -144.200118)
		(end 41.245536 -144.200118)
		(width 0.127)
		(layer "In5.Cu")
		(net "MEMWEN")
	)
	(segment
		(start 33.02635 -142.885414)
		(end 32.35452 -142.885414)
		(width 0.127)
		(layer "In5.Cu")
		(net "MEMWEN")
	)
	(segment
		(start 40.53713 -143.806164)
		(end 39.118286 -143.806164)
		(width 0.127)
		(layer "In5.Cu")
		(net "MEMWEN")
	)
	(arc
		(start 40.79748 -143.91386)
		(mid 40.678002 -143.834154)
		(end 40.53713 -143.806164)
		(width 0.127)
		(layer "In5.Cu")
		(net "MEMWEN")
	)
	(arc
		(start 41.245536 -144.200118)
		(mid 41.095846 -144.170343)
		(end 40.96893 -144.085564)
		(width 0.127)
		(layer "In5.Cu")
		(net "MEMWEN")
	)
	(arc
		(start 39.118286 -143.806164)
		(mid 38.78644 -143.740156)
		(end 38.50513 -143.552164)
		(width 0.127)
		(layer "In5.Cu")
		(net "MEMWEN")
	)
	(segment
		(start 42.099992 -144.200118)
		(end 41.700196 -144.599914)
		(width 0.127)
		(layer "F.Cu")
		(net "MEMRASN")
	)
	(segment
		(start 22.43455 -140.561568)
		(end 22.343872 -140.47089)
		(width 0.127)
		(layer "F.Cu")
		(net "MEMRASN")
	)
	(segment
		(start 22.343872 -140.47089)
		(end 22.343872 -140.470382)
		(width 0.127)
		(layer "F.Cu")
		(net "MEMRASN")
	)
	(segment
		(start 22.343872 -140.470382)
		(end 22.0345 -140.16101)
		(width 0.127)
		(layer "F.Cu")
		(net "MEMRASN")
	)
	(segment
		(start 41.700196 -144.599914)
		(end 41.699942 -144.599914)
		(width 0.127)
		(layer "F.Cu")
		(net "MEMRASN")
	)
	(via
		(at 42.099992 -144.200118)
		(size 0.4572)
		(drill 0.2032)
		(layers "F.Cu" "B.Cu")
		(net "MEMRASN")
	)
	(via
		(at 22.0345 -140.16101)
		(size 0.508)
		(drill 0.254)
		(layers "F.Cu" "B.Cu")
		(net "MEMRASN")
	)
	(segment
		(start 25.3619 -139.62126)
		(end 22.57425 -139.62126)
		(width 0.127)
		(layer "B.Cu")
		(net "MEMRASN")
	)
	(segment
		(start 25.3619 -140.12926)
		(end 25.4889 -140.00226)
		(width 0.127)
		(layer "B.Cu")
		(net "MEMRASN")
	)
	(segment
		(start 25.4889 -139.74826)
		(end 25.3619 -139.62126)
		(width 0.127)
		(layer "B.Cu")
		(net "MEMRASN")
	)
	(segment
		(start 25.4889 -140.00226)
		(end 25.4889 -139.74826)
		(width 0.127)
		(layer "B.Cu")
		(net "MEMRASN")
	)
	(segment
		(start 25.779476 -141.14018)
		(end 24.898604 -142.021052)
		(width 0.127)
		(layer "B.Cu")
		(net "MEMRASN")
	)
	(segment
		(start 22.57425 -139.62126)
		(end 22.0345 -140.16101)
		(width 0.127)
		(layer "B.Cu")
		(net "MEMRASN")
	)
	(segment
		(start 23.154132 -140.312394)
		(end 23.337266 -140.12926)
		(width 0.127)
		(layer "B.Cu")
		(net "MEMRASN")
	)
	(segment
		(start 23.337266 -140.12926)
		(end 25.3619 -140.12926)
		(width 0.127)
		(layer "B.Cu")
		(net "MEMRASN")
	)
	(segment
		(start 24.898604 -142.021052)
		(end 24.898604 -142.282164)
		(width 0.127)
		(layer "B.Cu")
		(net "MEMRASN")
	)
	(segment
		(start 24.898604 -142.282164)
		(end 24.155654 -142.282164)
		(width 0.127)
		(layer "B.Cu")
		(net "MEMRASN")
	)
	(segment
		(start 25.779476 -141.03096)
		(end 25.779476 -141.14018)
		(width 0.127)
		(layer "B.Cu")
		(net "MEMRASN")
	)
	(segment
		(start 23.154132 -141.280642)
		(end 23.154132 -140.312394)
		(width 0.127)
		(layer "B.Cu")
		(net "MEMRASN")
	)
	(segment
		(start 24.155654 -142.282164)
		(end 23.154132 -141.280642)
		(width 0.127)
		(layer "B.Cu")
		(net "MEMRASN")
	)
	(segment
		(start 27.10688 -141.715998)
		(end 26.960322 -141.862556)
		(width 0.127)
		(layer "In2.Cu")
		(net "MEMRASN")
	)
	(segment
		(start 23.848822 -140.716762)
		(end 23.29307 -140.16101)
		(width 0.127)
		(layer "In2.Cu")
		(net "MEMRASN")
	)
	(segment
		(start 36.21532 -143.77162)
		(end 36.34232 -143.64462)
		(width 0.127)
		(layer "In2.Cu")
		(net "MEMRASN")
	)
	(segment
		(start 25.59431 -140.676376)
		(end 24.426164 -140.676376)
		(width 0.127)
		(layer "In2.Cu")
		(net "MEMRASN")
	)
	(segment
		(start 39.51732 -144.15262)
		(end 36.34232 -144.15262)
		(width 0.127)
		(layer "In2.Cu")
		(net "MEMRASN")
	)
	(segment
		(start 27.46629 -142.075408)
		(end 27.46629 -141.895576)
		(width 0.127)
		(layer "In2.Cu")
		(net "MEMRASN")
	)
	(segment
		(start 42.099992 -144.200118)
		(end 41.706292 -143.806418)
		(width 0.127)
		(layer "In2.Cu")
		(net "MEMRASN")
	)
	(segment
		(start 27.756612 -142.838678)
		(end 27.319732 -142.401798)
		(width 0.127)
		(layer "In2.Cu")
		(net "MEMRASN")
	)
	(segment
		(start 29.47797 -142.838678)
		(end 27.756612 -142.838678)
		(width 0.127)
		(layer "In2.Cu")
		(net "MEMRASN")
	)
	(segment
		(start 23.29307 -140.16101)
		(end 22.0345 -140.16101)
		(width 0.127)
		(layer "In2.Cu")
		(net "MEMRASN")
	)
	(segment
		(start 36.34232 -143.64462)
		(end 39.10076 -143.64462)
		(width 0.127)
		(layer "In2.Cu")
		(net "MEMRASN")
	)
	(segment
		(start 24.385778 -140.716762)
		(end 23.848822 -140.716762)
		(width 0.127)
		(layer "In2.Cu")
		(net "MEMRASN")
	)
	(segment
		(start 36.21532 -144.02562)
		(end 36.21532 -143.77162)
		(width 0.127)
		(layer "In2.Cu")
		(net "MEMRASN")
	)
	(segment
		(start 26.960322 -141.862556)
		(end 26.78049 -141.862556)
		(width 0.127)
		(layer "In2.Cu")
		(net "MEMRASN")
	)
	(segment
		(start 41.706292 -143.806418)
		(end 39.863522 -143.806418)
		(width 0.127)
		(layer "In2.Cu")
		(net "MEMRASN")
	)
	(segment
		(start 27.319732 -142.221966)
		(end 27.46629 -142.075408)
		(width 0.127)
		(layer "In2.Cu")
		(net "MEMRASN")
	)
	(segment
		(start 29.775912 -143.13662)
		(end 29.47797 -142.838678)
		(width 0.127)
		(layer "In2.Cu")
		(net "MEMRASN")
	)
	(segment
		(start 24.426164 -140.676376)
		(end 24.385778 -140.716762)
		(width 0.127)
		(layer "In2.Cu")
		(net "MEMRASN")
	)
	(segment
		(start 36.34232 -144.15262)
		(end 36.21532 -144.02562)
		(width 0.127)
		(layer "In2.Cu")
		(net "MEMRASN")
	)
	(segment
		(start 39.22776 -143.26362)
		(end 39.10076 -143.13662)
		(width 0.127)
		(layer "In2.Cu")
		(net "MEMRASN")
	)
	(segment
		(start 39.10076 -143.64462)
		(end 39.22776 -143.51762)
		(width 0.127)
		(layer "In2.Cu")
		(net "MEMRASN")
	)
	(segment
		(start 27.319732 -142.401798)
		(end 27.319732 -142.221966)
		(width 0.127)
		(layer "In2.Cu")
		(net "MEMRASN")
	)
	(segment
		(start 39.863522 -143.806418)
		(end 39.51732 -144.15262)
		(width 0.127)
		(layer "In2.Cu")
		(net "MEMRASN")
	)
	(segment
		(start 39.10076 -143.13662)
		(end 29.775912 -143.13662)
		(width 0.127)
		(layer "In2.Cu")
		(net "MEMRASN")
	)
	(segment
		(start 27.286712 -141.715998)
		(end 27.10688 -141.715998)
		(width 0.127)
		(layer "In2.Cu")
		(net "MEMRASN")
	)
	(segment
		(start 27.46629 -141.895576)
		(end 27.286712 -141.715998)
		(width 0.127)
		(layer "In2.Cu")
		(net "MEMRASN")
	)
	(segment
		(start 39.22776 -143.51762)
		(end 39.22776 -143.26362)
		(width 0.127)
		(layer "In2.Cu")
		(net "MEMRASN")
	)
	(segment
		(start 26.78049 -141.862556)
		(end 25.59431 -140.676376)
		(width 0.127)
		(layer "In2.Cu")
		(net "MEMRASN")
	)
	(segment
		(start 42.500042 -145.400014)
		(end 42.099992 -144.999964)
		(width 0.127)
		(layer "F.Cu")
		(net "MEMODT")
	)
	(segment
		(start 18.434558 -141.361668)
		(end 18.034508 -140.961618)
		(width 0.127)
		(layer "F.Cu")
		(net "MEMODT")
	)
	(via
		(at 42.099992 -144.999964)
		(size 0.4572)
		(drill 0.2032)
		(layers "F.Cu" "B.Cu")
		(net "MEMODT")
	)
	(via
		(at 18.034508 -140.961618)
		(size 0.508)
		(drill 0.254)
		(layers "F.Cu" "B.Cu")
		(net "MEMODT")
	)
	(segment
		(start 17.615408 -140.542518)
		(end 18.034508 -140.961618)
		(width 0.127)
		(layer "B.Cu")
		(net "MEMODT")
	)
	(segment
		(start 15.62989 -142.392146)
		(end 15.62989 -142.061184)
		(width 0.127)
		(layer "B.Cu")
		(net "MEMODT")
	)
	(segment
		(start 14.935708 -143.086328)
		(end 15.11554 -143.086328)
		(width 0.127)
		(layer "B.Cu")
		(net "MEMODT")
	)
	(segment
		(start 15.11554 -143.086328)
		(end 15.583154 -143.553942)
		(width 0.127)
		(layer "B.Cu")
		(net "MEMODT")
	)
	(segment
		(start 10.6299 -142.4686)
		(end 11.662156 -142.4686)
		(width 0.127)
		(layer "B.Cu")
		(net "MEMODT")
	)
	(segment
		(start 15.62989 -142.061184)
		(end 16.536924 -141.15415)
		(width 0.127)
		(layer "B.Cu")
		(net "MEMODT")
	)
	(segment
		(start 17.060926 -140.542518)
		(end 17.615408 -140.542518)
		(width 0.127)
		(layer "B.Cu")
		(net "MEMODT")
	)
	(segment
		(start 15.942564 -143.374364)
		(end 15.942564 -143.194532)
		(width 0.127)
		(layer "B.Cu")
		(net "MEMODT")
	)
	(segment
		(start 11.90244 -143.161766)
		(end 14.86027 -143.161766)
		(width 0.127)
		(layer "B.Cu")
		(net "MEMODT")
	)
	(segment
		(start 11.66749 -142.926816)
		(end 11.90244 -143.161766)
		(width 0.127)
		(layer "B.Cu")
		(net "MEMODT")
	)
	(segment
		(start 15.762986 -143.553942)
		(end 15.942564 -143.374364)
		(width 0.127)
		(layer "B.Cu")
		(net "MEMODT")
	)
	(segment
		(start 16.536924 -141.06652)
		(end 17.060926 -140.542518)
		(width 0.127)
		(layer "B.Cu")
		(net "MEMODT")
	)
	(segment
		(start 14.86027 -143.161766)
		(end 14.935708 -143.086328)
		(width 0.127)
		(layer "B.Cu")
		(net "MEMODT")
	)
	(segment
		(start 16.536924 -141.15415)
		(end 16.536924 -141.06652)
		(width 0.127)
		(layer "B.Cu")
		(net "MEMODT")
	)
	(segment
		(start 15.583154 -143.553942)
		(end 15.762986 -143.553942)
		(width 0.127)
		(layer "B.Cu")
		(net "MEMODT")
	)
	(segment
		(start 15.47495 -142.726918)
		(end 15.47495 -142.547086)
		(width 0.127)
		(layer "B.Cu")
		(net "MEMODT")
	)
	(segment
		(start 11.66749 -142.463266)
		(end 11.66749 -142.926816)
		(width 0.127)
		(layer "B.Cu")
		(net "MEMODT")
	)
	(segment
		(start 15.942564 -143.194532)
		(end 15.47495 -142.726918)
		(width 0.127)
		(layer "B.Cu")
		(net "MEMODT")
	)
	(segment
		(start 11.662156 -142.4686)
		(end 11.66749 -142.463266)
		(width 0.127)
		(layer "B.Cu")
		(net "MEMODT")
	)
	(segment
		(start 15.47495 -142.547086)
		(end 15.62989 -142.392146)
		(width 0.127)
		(layer "B.Cu")
		(net "MEMODT")
	)
	(segment
		(start 32.439102 -143.610076)
		(end 32.65551 -143.393668)
		(width 0.127)
		(layer "In5.Cu")
		(net "MEMODT")
	)
	(segment
		(start 18.974054 -140.95984)
		(end 19.062954 -141.04874)
		(width 0.0889)
		(layer "In5.Cu")
		(net "MEMODT")
	)
	(segment
		(start 19.062954 -141.71168)
		(end 19.167094 -141.81582)
		(width 0.0889)
		(layer "In5.Cu")
		(net "MEMODT")
	)
	(segment
		(start 19.418554 -141.04874)
		(end 19.507454 -140.95984)
		(width 0.0889)
		(layer "In5.Cu")
		(net "MEMODT")
	)
	(segment
		(start 19.062954 -141.04874)
		(end 19.062954 -141.71168)
		(width 0.0889)
		(layer "In5.Cu")
		(net "MEMODT")
	)
	(segment
		(start 42.09923 -144.999964)
		(end 42.099992 -144.999964)
		(width 0.127)
		(layer "In5.Cu")
		(net "MEMODT")
	)
	(segment
		(start 39.632128 -144.606264)
		(end 41.3131 -144.606264)
		(width 0.127)
		(layer "In5.Cu")
		(net "MEMODT")
	)
	(segment
		(start 29.128212 -143.610076)
		(end 32.439102 -143.610076)
		(width 0.127)
		(layer "In5.Cu")
		(net "MEMODT")
	)
	(segment
		(start 19.507454 -140.95984)
		(end 19.685254 -140.95984)
		(width 0.0889)
		(layer "In5.Cu")
		(net "MEMODT")
	)
	(segment
		(start 18.707354 -141.27226)
		(end 18.707354 -141.04874)
		(width 0.0889)
		(layer "In5.Cu")
		(net "MEMODT")
	)
	(segment
		(start 20.287996 -141.96568)
		(end 20.392136 -141.86154)
		(width 0.0889)
		(layer "In5.Cu")
		(net "MEMODT")
	)
	(segment
		(start 39.619428 -144.593564)
		(end 39.632128 -144.606264)
		(width 0.127)
		(layer "In5.Cu")
		(net "MEMODT")
	)
	(segment
		(start 19.685254 -140.95984)
		(end 19.774154 -141.04874)
		(width 0.0889)
		(layer "In5.Cu")
		(net "MEMODT")
	)
	(segment
		(start 20.140676 -141.96568)
		(end 20.287996 -141.96568)
		(width 0.0889)
		(layer "In5.Cu")
		(net "MEMODT")
	)
	(segment
		(start 20.392136 -141.45006)
		(end 20.481036 -141.36116)
		(width 0.0889)
		(layer "In5.Cu")
		(net "MEMODT")
	)
	(segment
		(start 20.392136 -141.86154)
		(end 20.392136 -141.45006)
		(width 0.0889)
		(layer "In5.Cu")
		(net "MEMODT")
	)
	(segment
		(start 28.908756 -143.39062)
		(end 29.128212 -143.610076)
		(width 0.127)
		(layer "In5.Cu")
		(net "MEMODT")
	)
	(segment
		(start 19.314414 -141.81582)
		(end 19.418554 -141.71168)
		(width 0.0889)
		(layer "In5.Cu")
		(net "MEMODT")
	)
	(segment
		(start 18.707354 -141.04874)
		(end 18.796254 -140.95984)
		(width 0.0889)
		(layer "In5.Cu")
		(net "MEMODT")
	)
	(segment
		(start 20.036536 -141.534642)
		(end 20.036536 -141.86154)
		(width 0.0889)
		(layer "In5.Cu")
		(net "MEMODT")
	)
	(segment
		(start 18.17878 -141.36116)
		(end 18.618454 -141.36116)
		(width 0.0889)
		(layer "In5.Cu")
		(net "MEMODT")
	)
	(segment
		(start 26.109676 -141.450822)
		(end 28.049474 -143.39062)
		(width 0.127)
		(layer "In5.Cu")
		(net "MEMODT")
	)
	(segment
		(start 19.774154 -141.27226)
		(end 20.036536 -141.534642)
		(width 0.0889)
		(layer "In5.Cu")
		(net "MEMODT")
	)
	(segment
		(start 24.584406 -141.450822)
		(end 26.109676 -141.450822)
		(width 0.127)
		(layer "In5.Cu")
		(net "MEMODT")
	)
	(segment
		(start 22.490938 -141.36116)
		(end 22.753066 -141.099032)
		(width 0.127)
		(layer "In5.Cu")
		(net "MEMODT")
	)
	(segment
		(start 41.54043 -144.682464)
		(end 41.687242 -144.829276)
		(width 0.127)
		(layer "In5.Cu")
		(net "MEMODT")
	)
	(segment
		(start 18.796254 -140.95984)
		(end 18.974054 -140.95984)
		(width 0.0889)
		(layer "In5.Cu")
		(net "MEMODT")
	)
	(segment
		(start 32.65551 -143.393668)
		(end 37.737034 -143.393668)
		(width 0.127)
		(layer "In5.Cu")
		(net "MEMODT")
	)
	(segment
		(start 28.049474 -143.39062)
		(end 28.908756 -143.39062)
		(width 0.127)
		(layer "In5.Cu")
		(net "MEMODT")
	)
	(segment
		(start 18.618454 -141.36116)
		(end 18.707354 -141.27226)
		(width 0.0889)
		(layer "In5.Cu")
		(net "MEMODT")
	)
	(segment
		(start 18.034508 -141.216888)
		(end 18.17878 -141.36116)
		(width 0.0889)
		(layer "In5.Cu")
		(net "MEMODT")
	)
	(segment
		(start 20.481036 -141.36116)
		(end 22.490938 -141.36116)
		(width 0.0889)
		(layer "In5.Cu")
		(net "MEMODT")
	)
	(segment
		(start 24.232616 -141.099032)
		(end 24.584406 -141.450822)
		(width 0.127)
		(layer "In5.Cu")
		(net "MEMODT")
	)
	(segment
		(start 18.034508 -140.961618)
		(end 18.034508 -141.216888)
		(width 0.0889)
		(layer "In5.Cu")
		(net "MEMODT")
	)
	(segment
		(start 19.418554 -141.71168)
		(end 19.418554 -141.04874)
		(width 0.0889)
		(layer "In5.Cu")
		(net "MEMODT")
	)
	(segment
		(start 37.737034 -143.393668)
		(end 38.45433 -144.110964)
		(width 0.127)
		(layer "In5.Cu")
		(net "MEMODT")
	)
	(segment
		(start 22.753066 -141.099032)
		(end 24.232616 -141.099032)
		(width 0.127)
		(layer "In5.Cu")
		(net "MEMODT")
	)
	(segment
		(start 19.167094 -141.81582)
		(end 19.314414 -141.81582)
		(width 0.0889)
		(layer "In5.Cu")
		(net "MEMODT")
	)
	(segment
		(start 19.774154 -141.04874)
		(end 19.774154 -141.27226)
		(width 0.0889)
		(layer "In5.Cu")
		(net "MEMODT")
	)
	(segment
		(start 20.036536 -141.86154)
		(end 20.140676 -141.96568)
		(width 0.0889)
		(layer "In5.Cu")
		(net "MEMODT")
	)
	(arc
		(start 41.687242 -144.829276)
		(mid 41.876264 -144.955576)
		(end 42.09923 -144.999964)
		(width 0.127)
		(layer "In5.Cu")
		(net "MEMODT")
	)
	(arc
		(start 38.45433 -144.110964)
		(mid 38.988882 -144.46814)
		(end 39.619428 -144.593564)
		(width 0.127)
		(layer "In5.Cu")
		(net "MEMODT")
	)
	(arc
		(start 41.3131 -144.606264)
		(mid 41.43298 -144.625821)
		(end 41.54043 -144.682464)
		(width 0.127)
		(layer "In5.Cu")
		(net "MEMODT")
	)
	(segment
		(start 23.934166 -148.104352)
		(end 24.279098 -147.75942)
		(width 0.127)
		(layer "F.Cu")
		(net "MEMDQ_9")
	)
	(segment
		(start 40.900096 -147.80006)
		(end 40.899842 -147.80006)
		(width 0.127)
		(layer "F.Cu")
		(net "MEMDQ_9")
	)
	(segment
		(start 41.299892 -148.199856)
		(end 40.900096 -147.80006)
		(width 0.127)
		(layer "F.Cu")
		(net "MEMDQ_9")
	)
	(segment
		(start 22.43455 -147.761452)
		(end 22.77745 -148.104352)
		(width 0.127)
		(layer "F.Cu")
		(net "MEMDQ_9")
	)
	(segment
		(start 24.279098 -147.75942)
		(end 24.52878 -147.75942)
		(width 0.127)
		(layer "F.Cu")
		(net "MEMDQ_9")
	)
	(segment
		(start 22.77745 -148.104352)
		(end 23.934166 -148.104352)
		(width 0.127)
		(layer "F.Cu")
		(net "MEMDQ_9")
	)
	(via
		(at 24.52878 -147.75942)
		(size 0.508)
		(drill 0.254)
		(layers "F.Cu" "B.Cu")
		(net "MEMDQ_9")
	)
	(via
		(at 41.299892 -148.199856)
		(size 0.4572)
		(drill 0.2032)
		(layers "F.Cu" "B.Cu")
		(net "MEMDQ_9")
	)
	(segment
		(start 32.42564 -149.9616)
		(end 32.29864 -150.0886)
		(width 0.127)
		(layer "In2.Cu")
		(net "MEMDQ_9")
	)
	(segment
		(start 36.425378 -148.327872)
		(end 37.365432 -148.327872)
		(width 0.127)
		(layer "In2.Cu")
		(net "MEMDQ_9")
	)
	(segment
		(start 32.29864 -150.0886)
		(end 31.23438 -150.0886)
		(width 0.127)
		(layer "In2.Cu")
		(net "MEMDQ_9")
	)
	(segment
		(start 35.716464 -148.550122)
		(end 36.203128 -148.550122)
		(width 0.127)
		(layer "In2.Cu")
		(net "MEMDQ_9")
	)
	(segment
		(start 31.23438 -150.8506)
		(end 34.32556 -150.8506)
		(width 0.127)
		(layer "In2.Cu")
		(net "MEMDQ_9")
	)
	(segment
		(start 38.243764 -148.423376)
		(end 38.593776 -148.073364)
		(width 0.127)
		(layer "In2.Cu")
		(net "MEMDQ_9")
	)
	(segment
		(start 37.608764 -150.77948)
		(end 38.116764 -150.77948)
		(width 0.127)
		(layer "In2.Cu")
		(net "MEMDQ_9")
	)
	(segment
		(start 32.29864 -149.3266)
		(end 32.42564 -149.4536)
		(width 0.127)
		(layer "In2.Cu")
		(net "MEMDQ_9")
	)
	(segment
		(start 38.593776 -148.073364)
		(end 41.1734 -148.073364)
		(width 0.127)
		(layer "In2.Cu")
		(net "MEMDQ_9")
	)
	(segment
		(start 36.203128 -148.550122)
		(end 36.425378 -148.327872)
		(width 0.127)
		(layer "In2.Cu")
		(net "MEMDQ_9")
	)
	(segment
		(start 26.09596 -149.3266)
		(end 32.29864 -149.3266)
		(width 0.127)
		(layer "In2.Cu")
		(net "MEMDQ_9")
	)
	(segment
		(start 41.1734 -148.073364)
		(end 41.299892 -148.199856)
		(width 0.127)
		(layer "In2.Cu")
		(net "MEMDQ_9")
	)
	(segment
		(start 31.23438 -150.0886)
		(end 31.10738 -150.2156)
		(width 0.127)
		(layer "In2.Cu")
		(net "MEMDQ_9")
	)
	(segment
		(start 38.116764 -150.77948)
		(end 38.243764 -150.65248)
		(width 0.127)
		(layer "In2.Cu")
		(net "MEMDQ_9")
	)
	(segment
		(start 34.32556 -150.8506)
		(end 34.7472 -150.42896)
		(width 0.127)
		(layer "In2.Cu")
		(net "MEMDQ_9")
	)
	(segment
		(start 38.243764 -150.65248)
		(end 38.243764 -148.423376)
		(width 0.127)
		(layer "In2.Cu")
		(net "MEMDQ_9")
	)
	(segment
		(start 31.10738 -150.7236)
		(end 31.23438 -150.8506)
		(width 0.127)
		(layer "In2.Cu")
		(net "MEMDQ_9")
	)
	(segment
		(start 34.7472 -149.519386)
		(end 35.716464 -148.550122)
		(width 0.127)
		(layer "In2.Cu")
		(net "MEMDQ_9")
	)
	(segment
		(start 37.481764 -150.65248)
		(end 37.608764 -150.77948)
		(width 0.127)
		(layer "In2.Cu")
		(net "MEMDQ_9")
	)
	(segment
		(start 34.7472 -150.42896)
		(end 34.7472 -149.519386)
		(width 0.127)
		(layer "In2.Cu")
		(net "MEMDQ_9")
	)
	(segment
		(start 37.365432 -148.327872)
		(end 37.481764 -148.444204)
		(width 0.127)
		(layer "In2.Cu")
		(net "MEMDQ_9")
	)
	(segment
		(start 31.10738 -150.2156)
		(end 31.10738 -150.7236)
		(width 0.127)
		(layer "In2.Cu")
		(net "MEMDQ_9")
	)
	(segment
		(start 32.42564 -149.4536)
		(end 32.42564 -149.9616)
		(width 0.127)
		(layer "In2.Cu")
		(net "MEMDQ_9")
	)
	(segment
		(start 37.481764 -148.444204)
		(end 37.481764 -150.65248)
		(width 0.127)
		(layer "In2.Cu")
		(net "MEMDQ_9")
	)
	(segment
		(start 24.52878 -147.75942)
		(end 26.09596 -149.3266)
		(width 0.127)
		(layer "In2.Cu")
		(net "MEMDQ_9")
	)
	(segment
		(start 24.612854 -150.22068)
		(end 24.937466 -150.22068)
		(width 0.127)
		(layer "F.Cu")
		(net "MEMDQ_8")
	)
	(segment
		(start 20.66798 -151.12746)
		(end 20.54098 -151.25446)
		(width 0.127)
		(layer "F.Cu")
		(net "MEMDQ_8")
	)
	(segment
		(start 22.71522 -151.00046)
		(end 22.58822 -151.12746)
		(width 0.127)
		(layer "F.Cu")
		(net "MEMDQ_8")
	)
	(segment
		(start 20.66798 -151.88946)
		(end 22.944074 -151.88946)
		(width 0.127)
		(layer "F.Cu")
		(net "MEMDQ_8")
	)
	(segment
		(start 36.2839 -148.713444)
		(end 36.2839 -148.695664)
		(width 0.127)
		(layer "F.Cu")
		(net "MEMDQ_8")
	)
	(segment
		(start 20.54098 -151.25446)
		(end 20.54098 -151.76246)
		(width 0.127)
		(layer "F.Cu")
		(net "MEMDQ_8")
	)
	(segment
		(start 25.064466 -150.09368)
		(end 27.83459 -150.09368)
		(width 0.127)
		(layer "F.Cu")
		(net "MEMDQ_8")
	)
	(segment
		(start 27.83459 -150.09368)
		(end 28.470098 -149.458172)
		(width 0.127)
		(layer "F.Cu")
		(net "MEMDQ_8")
	)
	(segment
		(start 20.00504 -148.717)
		(end 20.00504 -150.132034)
		(width 0.127)
		(layer "F.Cu")
		(net "MEMDQ_8")
	)
	(segment
		(start 22.58822 -151.12746)
		(end 20.66798 -151.12746)
		(width 0.127)
		(layer "F.Cu")
		(net "MEMDQ_8")
	)
	(segment
		(start 22.944074 -151.88946)
		(end 24.612854 -150.22068)
		(width 0.127)
		(layer "F.Cu")
		(net "MEMDQ_8")
	)
	(segment
		(start 36.2839 -148.695664)
		(end 36.529264 -148.4503)
		(width 0.127)
		(layer "F.Cu")
		(net "MEMDQ_8")
	)
	(segment
		(start 24.937466 -150.22068)
		(end 25.064466 -150.09368)
		(width 0.127)
		(layer "F.Cu")
		(net "MEMDQ_8")
	)
	(segment
		(start 20.54098 -151.76246)
		(end 20.66798 -151.88946)
		(width 0.127)
		(layer "F.Cu")
		(net "MEMDQ_8")
	)
	(segment
		(start 20.00504 -150.132034)
		(end 20.238466 -150.36546)
		(width 0.127)
		(layer "F.Cu")
		(net "MEMDQ_8")
	)
	(segment
		(start 22.71522 -150.49246)
		(end 22.71522 -151.00046)
		(width 0.127)
		(layer "F.Cu")
		(net "MEMDQ_8")
	)
	(segment
		(start 20.238466 -150.36546)
		(end 22.58822 -150.36546)
		(width 0.127)
		(layer "F.Cu")
		(net "MEMDQ_8")
	)
	(segment
		(start 36.766246 -148.231098)
		(end 39.287196 -148.231098)
		(width 0.127)
		(layer "F.Cu")
		(net "MEMDQ_8")
	)
	(segment
		(start 39.287196 -148.231098)
		(end 39.31793 -148.200364)
		(width 0.127)
		(layer "F.Cu")
		(net "MEMDQ_8")
	)
	(segment
		(start 28.470098 -149.458172)
		(end 35.539172 -149.458172)
		(width 0.127)
		(layer "F.Cu")
		(net "MEMDQ_8")
	)
	(segment
		(start 22.58822 -150.36546)
		(end 22.71522 -150.49246)
		(width 0.127)
		(layer "F.Cu")
		(net "MEMDQ_8")
	)
	(segment
		(start 39.969694 -147.930362)
		(end 40.099996 -147.80006)
		(width 0.127)
		(layer "F.Cu")
		(net "MEMDQ_8")
	)
	(segment
		(start 36.547044 -148.4503)
		(end 36.766246 -148.231098)
		(width 0.127)
		(layer "F.Cu")
		(net "MEMDQ_8")
	)
	(segment
		(start 18.463006 -148.59)
		(end 19.87804 -148.59)
		(width 0.127)
		(layer "F.Cu")
		(net "MEMDQ_8")
	)
	(segment
		(start 18.434558 -148.561552)
		(end 18.463006 -148.59)
		(width 0.127)
		(layer "F.Cu")
		(net "MEMDQ_8")
	)
	(segment
		(start 19.87804 -148.59)
		(end 20.00504 -148.717)
		(width 0.127)
		(layer "F.Cu")
		(net "MEMDQ_8")
	)
	(segment
		(start 35.539172 -149.458172)
		(end 36.2839 -148.713444)
		(width 0.127)
		(layer "F.Cu")
		(net "MEMDQ_8")
	)
	(segment
		(start 36.529264 -148.4503)
		(end 36.547044 -148.4503)
		(width 0.127)
		(layer "F.Cu")
		(net "MEMDQ_8")
	)
	(arc
		(start 39.31793 -148.200364)
		(mid 39.670675 -148.130199)
		(end 39.969694 -147.930362)
		(width 0.127)
		(layer "F.Cu")
		(net "MEMDQ_8")
	)
	(segment
		(start 21.63445 -142.161514)
		(end 21.234654 -142.56131)
		(width 0.127)
		(layer "F.Cu")
		(net "MEMDQ_7")
	)
	(segment
		(start 42.500042 -146.99996)
		(end 42.099992 -147.40001)
		(width 0.127)
		(layer "F.Cu")
		(net "MEMDQ_7")
	)
	(segment
		(start 21.234654 -142.56131)
		(end 21.2344 -142.56131)
		(width 0.127)
		(layer "F.Cu")
		(net "MEMDQ_7")
	)
	(via
		(at 21.2344 -142.56131)
		(size 0.508)
		(drill 0.254)
		(layers "F.Cu" "B.Cu")
		(net "MEMDQ_7")
	)
	(via
		(at 42.099992 -147.40001)
		(size 0.4572)
		(drill 0.2032)
		(layers "F.Cu" "B.Cu")
		(net "MEMDQ_7")
	)
	(segment
		(start 43.942 -145.39468)
		(end 41.20134 -145.39468)
		(width 0.127)
		(layer "In5.Cu")
		(net "MEMDQ_7")
	)
	(segment
		(start 36.129468 -144.907)
		(end 35.031426 -144.907)
		(width 0.127)
		(layer "In5.Cu")
		(net "MEMDQ_7")
	)
	(segment
		(start 23.404322 -142.721076)
		(end 23.164038 -142.96136)
		(width 0.127)
		(layer "In5.Cu")
		(net "MEMDQ_7")
	)
	(segment
		(start 35.015424 -144.923002)
		(end 34.958528 -144.923002)
		(width 0.127)
		(layer "In5.Cu")
		(net "MEMDQ_7")
	)
	(segment
		(start 34.958528 -144.923002)
		(end 33.903666 -145.977864)
		(width 0.127)
		(layer "In5.Cu")
		(net "MEMDQ_7")
	)
	(segment
		(start 25.583642 -142.721076)
		(end 23.404322 -142.721076)
		(width 0.127)
		(layer "In5.Cu")
		(net "MEMDQ_7")
	)
	(segment
		(start 36.3728 -144.663668)
		(end 36.129468 -144.907)
		(width 0.127)
		(layer "In5.Cu")
		(net "MEMDQ_7")
	)
	(segment
		(start 28.360624 -144.919446)
		(end 27.782012 -144.919446)
		(width 0.127)
		(layer "In5.Cu")
		(net "MEMDQ_7")
	)
	(segment
		(start 29.784294 -145.977864)
		(end 29.530294 -145.723864)
		(width 0.127)
		(layer "In5.Cu")
		(net "MEMDQ_7")
	)
	(segment
		(start 42.099992 -147.40001)
		(end 42.099992 -147.260818)
		(width 0.127)
		(layer "In5.Cu")
		(net "MEMDQ_7")
	)
	(segment
		(start 40.915082 -145.680938)
		(end 39.17315 -145.680938)
		(width 0.127)
		(layer "In5.Cu")
		(net "MEMDQ_7")
	)
	(segment
		(start 21.63445 -142.96136)
		(end 21.2344 -142.56131)
		(width 0.0889)
		(layer "In5.Cu")
		(net "MEMDQ_7")
	)
	(segment
		(start 44.09313 -145.54581)
		(end 43.942 -145.39468)
		(width 0.127)
		(layer "In5.Cu")
		(net "MEMDQ_7")
	)
	(segment
		(start 41.20134 -145.39468)
		(end 40.915082 -145.680938)
		(width 0.127)
		(layer "In5.Cu")
		(net "MEMDQ_7")
	)
	(segment
		(start 23.164038 -142.96136)
		(end 21.63445 -142.96136)
		(width 0.0889)
		(layer "In5.Cu")
		(net "MEMDQ_7")
	)
	(segment
		(start 43.909996 -146.996912)
		(end 44.09313 -146.813778)
		(width 0.127)
		(layer "In5.Cu")
		(net "MEMDQ_7")
	)
	(segment
		(start 38.15588 -144.663668)
		(end 36.3728 -144.663668)
		(width 0.127)
		(layer "In5.Cu")
		(net "MEMDQ_7")
	)
	(segment
		(start 29.53004 -145.723864)
		(end 29.348176 -145.542)
		(width 0.127)
		(layer "In5.Cu")
		(net "MEMDQ_7")
	)
	(segment
		(start 29.348176 -145.542)
		(end 28.983178 -145.542)
		(width 0.127)
		(layer "In5.Cu")
		(net "MEMDQ_7")
	)
	(segment
		(start 42.099992 -147.260818)
		(end 42.363898 -146.996912)
		(width 0.127)
		(layer "In5.Cu")
		(net "MEMDQ_7")
	)
	(segment
		(start 39.17315 -145.680938)
		(end 38.15588 -144.663668)
		(width 0.127)
		(layer "In5.Cu")
		(net "MEMDQ_7")
	)
	(segment
		(start 42.363898 -146.996912)
		(end 43.909996 -146.996912)
		(width 0.127)
		(layer "In5.Cu")
		(net "MEMDQ_7")
	)
	(segment
		(start 33.903666 -145.977864)
		(end 29.784294 -145.977864)
		(width 0.127)
		(layer "In5.Cu")
		(net "MEMDQ_7")
	)
	(segment
		(start 27.782012 -144.919446)
		(end 25.583642 -142.721076)
		(width 0.127)
		(layer "In5.Cu")
		(net "MEMDQ_7")
	)
	(segment
		(start 35.031426 -144.907)
		(end 35.015424 -144.923002)
		(width 0.127)
		(layer "In5.Cu")
		(net "MEMDQ_7")
	)
	(segment
		(start 29.530294 -145.723864)
		(end 29.53004 -145.723864)
		(width 0.127)
		(layer "In5.Cu")
		(net "MEMDQ_7")
	)
	(segment
		(start 44.09313 -146.813778)
		(end 44.09313 -145.54581)
		(width 0.127)
		(layer "In5.Cu")
		(net "MEMDQ_7")
	)
	(segment
		(start 28.983178 -145.542)
		(end 28.360624 -144.919446)
		(width 0.127)
		(layer "In5.Cu")
		(net "MEMDQ_7")
	)
	(segment
		(start 18.434558 -142.161514)
		(end 18.434558 -142.429484)
		(width 0.127)
		(layer "F.Cu")
		(net "MEMDQ_6")
	)
	(segment
		(start 41.699942 -146.99996)
		(end 41.299892 -146.59991)
		(width 0.127)
		(layer "F.Cu")
		(net "MEMDQ_6")
	)
	(segment
		(start 18.434558 -142.429484)
		(end 19.066764 -143.06169)
		(width 0.127)
		(layer "F.Cu")
		(net "MEMDQ_6")
	)
	(via
		(at 19.066764 -143.06169)
		(size 0.508)
		(drill 0.254)
		(layers "F.Cu" "B.Cu")
		(net "MEMDQ_6")
	)
	(via
		(at 41.299892 -146.59991)
		(size 0.4572)
		(drill 0.2032)
		(layers "F.Cu" "B.Cu")
		(net "MEMDQ_6")
	)
	(segment
		(start 20.027138 -142.479776)
		(end 20.138644 -142.591282)
		(width 0.0889)
		(layer "In5.Cu")
		(net "MEMDQ_6")
	)
	(segment
		(start 41.05148 -145.934938)
		(end 41.252648 -145.73377)
		(width 0.127)
		(layer "In5.Cu")
		(net "MEMDQ_6")
	)
	(segment
		(start 19.17319 -142.479776)
		(end 20.027138 -142.479776)
		(width 0.0889)
		(layer "In5.Cu")
		(net "MEMDQ_6")
	)
	(segment
		(start 24.9301 -143.483076)
		(end 27.12847 -145.681446)
		(width 0.127)
		(layer "In5.Cu")
		(net "MEMDQ_6")
	)
	(segment
		(start 23.516844 -143.483076)
		(end 24.9301 -143.483076)
		(width 0.127)
		(layer "In5.Cu")
		(net "MEMDQ_6")
	)
	(segment
		(start 19.066764 -143.06169)
		(end 19.066764 -142.586202)
		(width 0.0889)
		(layer "In5.Cu")
		(net "MEMDQ_6")
	)
	(segment
		(start 28.044902 -145.681446)
		(end 28.667456 -146.304)
		(width 0.127)
		(layer "In5.Cu")
		(net "MEMDQ_6")
	)
	(segment
		(start 20.494244 -143.85036)
		(end 20.583144 -143.76146)
		(width 0.0889)
		(layer "In5.Cu")
		(net "MEMDQ_6")
	)
	(segment
		(start 29.032454 -146.304)
		(end 29.111448 -146.38274)
		(width 0.127)
		(layer "In5.Cu")
		(net "MEMDQ_6")
	)
	(segment
		(start 27.12847 -145.681446)
		(end 28.044902 -145.681446)
		(width 0.127)
		(layer "In5.Cu")
		(net "MEMDQ_6")
	)
	(segment
		(start 41.57091 -146.59991)
		(end 41.299892 -146.59991)
		(width 0.127)
		(layer "In5.Cu")
		(net "MEMDQ_6")
	)
	(segment
		(start 29.468572 -146.739864)
		(end 34.276284 -146.739864)
		(width 0.127)
		(layer "In5.Cu")
		(net "MEMDQ_6")
	)
	(segment
		(start 36.26358 -145.669)
		(end 36.768278 -145.164302)
		(width 0.127)
		(layer "In5.Cu")
		(net "MEMDQ_6")
	)
	(segment
		(start 39.069264 -145.934938)
		(end 41.05148 -145.934938)
		(width 0.127)
		(layer "In5.Cu")
		(net "MEMDQ_6")
	)
	(segment
		(start 36.768278 -145.164302)
		(end 38.298628 -145.164302)
		(width 0.127)
		(layer "In5.Cu")
		(net "MEMDQ_6")
	)
	(segment
		(start 29.111448 -146.38274)
		(end 29.468572 -146.739864)
		(width 0.127)
		(layer "In5.Cu")
		(net "MEMDQ_6")
	)
	(segment
		(start 20.138644 -142.591282)
		(end 20.138644 -144.23009)
		(width 0.0889)
		(layer "In5.Cu")
		(net "MEMDQ_6")
	)
	(segment
		(start 20.494244 -144.23009)
		(end 20.494244 -143.85036)
		(width 0.0889)
		(layer "In5.Cu")
		(net "MEMDQ_6")
	)
	(segment
		(start 35.347148 -145.669)
		(end 36.26358 -145.669)
		(width 0.127)
		(layer "In5.Cu")
		(net "MEMDQ_6")
	)
	(segment
		(start 41.72204 -145.979388)
		(end 41.72204 -146.44878)
		(width 0.127)
		(layer "In5.Cu")
		(net "MEMDQ_6")
	)
	(segment
		(start 41.252648 -145.73377)
		(end 41.476422 -145.73377)
		(width 0.127)
		(layer "In5.Cu")
		(net "MEMDQ_6")
	)
	(segment
		(start 19.066764 -142.586202)
		(end 19.17319 -142.479776)
		(width 0.0889)
		(layer "In5.Cu")
		(net "MEMDQ_6")
	)
	(segment
		(start 41.72204 -146.44878)
		(end 41.57091 -146.59991)
		(width 0.127)
		(layer "In5.Cu")
		(net "MEMDQ_6")
	)
	(segment
		(start 28.667456 -146.304)
		(end 29.032454 -146.304)
		(width 0.127)
		(layer "In5.Cu")
		(net "MEMDQ_6")
	)
	(segment
		(start 34.276284 -146.739864)
		(end 35.347148 -145.669)
		(width 0.127)
		(layer "In5.Cu")
		(net "MEMDQ_6")
	)
	(segment
		(start 20.242784 -144.33423)
		(end 20.390104 -144.33423)
		(width 0.0889)
		(layer "In5.Cu")
		(net "MEMDQ_6")
	)
	(segment
		(start 41.476422 -145.73377)
		(end 41.72204 -145.979388)
		(width 0.127)
		(layer "In5.Cu")
		(net "MEMDQ_6")
	)
	(segment
		(start 23.23846 -143.76146)
		(end 23.516844 -143.483076)
		(width 0.127)
		(layer "In5.Cu")
		(net "MEMDQ_6")
	)
	(segment
		(start 20.138644 -144.23009)
		(end 20.242784 -144.33423)
		(width 0.0889)
		(layer "In5.Cu")
		(net "MEMDQ_6")
	)
	(segment
		(start 20.390104 -144.33423)
		(end 20.494244 -144.23009)
		(width 0.0889)
		(layer "In5.Cu")
		(net "MEMDQ_6")
	)
	(segment
		(start 38.298628 -145.164302)
		(end 39.069264 -145.934938)
		(width 0.127)
		(layer "In5.Cu")
		(net "MEMDQ_6")
	)
	(segment
		(start 20.583144 -143.76146)
		(end 23.23846 -143.76146)
		(width 0.0889)
		(layer "In5.Cu")
		(net "MEMDQ_6")
	)
	(segment
		(start 22.43455 -142.961614)
		(end 22.434296 -142.961614)
		(width 0.127)
		(layer "F.Cu")
		(net "MEMDQ_5")
	)
	(segment
		(start 22.434296 -142.961614)
		(end 22.0345 -143.36141)
		(width 0.127)
		(layer "F.Cu")
		(net "MEMDQ_5")
	)
	(segment
		(start 40.500046 -147.40001)
		(end 40.899842 -147.000214)
		(width 0.127)
		(layer "F.Cu")
		(net "MEMDQ_5")
	)
	(segment
		(start 40.899842 -147.000214)
		(end 40.899842 -146.99996)
		(width 0.127)
		(layer "F.Cu")
		(net "MEMDQ_5")
	)
	(via
		(at 40.500046 -147.40001)
		(size 0.4572)
		(drill 0.2032)
		(layers "F.Cu" "B.Cu")
		(net "MEMDQ_5")
	)
	(via
		(at 22.0345 -143.36141)
		(size 0.508)
		(drill 0.254)
		(layers "F.Cu" "B.Cu")
		(net "MEMDQ_5")
	)
	(segment
		(start 38.46576 -146.28876)
		(end 38.59276 -146.16176)
		(width 0.127)
		(layer "In2.Cu")
		(net "MEMDQ_5")
	)
	(segment
		(start 22.43455 -143.76146)
		(end 22.0345 -143.36141)
		(width 0.0889)
		(layer "In2.Cu")
		(net "MEMDQ_5")
	)
	(segment
		(start 39.887144 -146.998944)
		(end 38.59276 -146.998944)
		(width 0.127)
		(layer "In2.Cu")
		(net "MEMDQ_5")
	)
	(segment
		(start 36.39566 -145.14576)
		(end 36.23564 -145.30578)
		(width 0.127)
		(layer "In2.Cu")
		(net "MEMDQ_5")
	)
	(segment
		(start 28.042362 -146.03857)
		(end 26.601674 -146.03857)
		(width 0.127)
		(layer "In2.Cu")
		(net "MEMDQ_5")
	)
	(segment
		(start 34.623756 -145.379948)
		(end 33.242504 -146.7612)
		(width 0.127)
		(layer "In2.Cu")
		(net "MEMDQ_5")
	)
	(segment
		(start 38.94582 -145.14576)
		(end 36.39566 -145.14576)
		(width 0.127)
		(layer "In2.Cu")
		(net "MEMDQ_5")
	)
	(segment
		(start 34.750756 -144.987518)
		(end 34.623756 -145.114518)
		(width 0.127)
		(layer "In2.Cu")
		(net "MEMDQ_5")
	)
	(segment
		(start 26.601674 -146.03857)
		(end 24.321262 -143.758158)
		(width 0.127)
		(layer "In2.Cu")
		(net "MEMDQ_5")
	)
	(segment
		(start 41.51884 -145.39976)
		(end 39.19982 -145.39976)
		(width 0.127)
		(layer "In2.Cu")
		(net "MEMDQ_5")
	)
	(segment
		(start 24.321262 -143.758158)
		(end 23.463758 -143.758158)
		(width 0.127)
		(layer "In2.Cu")
		(net "MEMDQ_5")
	)
	(segment
		(start 41.51884 -146.16176)
		(end 41.64584 -146.03476)
		(width 0.127)
		(layer "In2.Cu")
		(net "MEMDQ_5")
	)
	(segment
		(start 34.623756 -145.114518)
		(end 34.623756 -145.379948)
		(width 0.127)
		(layer "In2.Cu")
		(net "MEMDQ_5")
	)
	(segment
		(start 40.01643 -147.12823)
		(end 39.887144 -146.998944)
		(width 0.127)
		(layer "In2.Cu")
		(net "MEMDQ_5")
	)
	(segment
		(start 23.000208 -143.76146)
		(end 22.43455 -143.76146)
		(width 0.0889)
		(layer "In2.Cu")
		(net "MEMDQ_5")
	)
	(segment
		(start 35.258756 -144.987518)
		(end 34.750756 -144.987518)
		(width 0.127)
		(layer "In2.Cu")
		(net "MEMDQ_5")
	)
	(segment
		(start 28.764992 -146.7612)
		(end 28.042362 -146.03857)
		(width 0.127)
		(layer "In2.Cu")
		(net "MEMDQ_5")
	)
	(segment
		(start 35.385756 -145.114518)
		(end 35.258756 -144.987518)
		(width 0.127)
		(layer "In2.Cu")
		(net "MEMDQ_5")
	)
	(segment
		(start 35.588956 -145.794222)
		(end 35.385756 -145.591022)
		(width 0.127)
		(layer "In2.Cu")
		(net "MEMDQ_5")
	)
	(segment
		(start 23.463758 -143.758158)
		(end 23.00351 -143.758158)
		(width 0.0889)
		(layer "In2.Cu")
		(net "MEMDQ_5")
	)
	(segment
		(start 39.19982 -145.39976)
		(end 38.94582 -145.14576)
		(width 0.127)
		(layer "In2.Cu")
		(net "MEMDQ_5")
	)
	(segment
		(start 38.59276 -146.16176)
		(end 41.51884 -146.16176)
		(width 0.127)
		(layer "In2.Cu")
		(net "MEMDQ_5")
	)
	(segment
		(start 41.64584 -145.52676)
		(end 41.51884 -145.39976)
		(width 0.127)
		(layer "In2.Cu")
		(net "MEMDQ_5")
	)
	(segment
		(start 36.03244 -145.794222)
		(end 35.588956 -145.794222)
		(width 0.127)
		(layer "In2.Cu")
		(net "MEMDQ_5")
	)
	(segment
		(start 35.385756 -145.591022)
		(end 35.385756 -145.114518)
		(width 0.127)
		(layer "In2.Cu")
		(net "MEMDQ_5")
	)
	(segment
		(start 36.23564 -145.591022)
		(end 36.03244 -145.794222)
		(width 0.127)
		(layer "In2.Cu")
		(net "MEMDQ_5")
	)
	(segment
		(start 33.242504 -146.7612)
		(end 28.764992 -146.7612)
		(width 0.127)
		(layer "In2.Cu")
		(net "MEMDQ_5")
	)
	(segment
		(start 23.00351 -143.758158)
		(end 23.000208 -143.76146)
		(width 0.0889)
		(layer "In2.Cu")
		(net "MEMDQ_5")
	)
	(segment
		(start 41.64584 -146.03476)
		(end 41.64584 -145.52676)
		(width 0.127)
		(layer "In2.Cu")
		(net "MEMDQ_5")
	)
	(segment
		(start 38.46576 -146.871944)
		(end 38.46576 -146.28876)
		(width 0.127)
		(layer "In2.Cu")
		(net "MEMDQ_5")
	)
	(segment
		(start 36.23564 -145.30578)
		(end 36.23564 -145.591022)
		(width 0.127)
		(layer "In2.Cu")
		(net "MEMDQ_5")
	)
	(segment
		(start 40.138604 -147.25015)
		(end 40.01643 -147.12823)
		(width 0.127)
		(layer "In2.Cu")
		(net "MEMDQ_5")
	)
	(segment
		(start 38.59276 -146.998944)
		(end 38.46576 -146.871944)
		(width 0.127)
		(layer "In2.Cu")
		(net "MEMDQ_5")
	)
	(arc
		(start 40.500046 -147.40001)
		(mid 40.304433 -147.361007)
		(end 40.138604 -147.25015)
		(width 0.127)
		(layer "In2.Cu")
		(net "MEMDQ_5")
	)
	(segment
		(start 17.634458 -142.961868)
		(end 17.234662 -143.361664)
		(width 0.127)
		(layer "F.Cu")
		(net "MEMDQ_4")
	)
	(segment
		(start 17.634458 -142.961614)
		(end 17.634458 -142.961868)
		(width 0.127)
		(layer "F.Cu")
		(net "MEMDQ_4")
	)
	(segment
		(start 42.900092 -147.40001)
		(end 43.299888 -147.000214)
		(width 0.127)
		(layer "F.Cu")
		(net "MEMDQ_4")
	)
	(segment
		(start 43.299888 -147.000214)
		(end 43.299888 -146.99996)
		(width 0.127)
		(layer "F.Cu")
		(net "MEMDQ_4")
	)
	(via
		(at 17.234662 -143.361664)
		(size 0.508)
		(drill 0.254)
		(layers "F.Cu" "B.Cu")
		(net "MEMDQ_4")
	)
	(via
		(at 42.900092 -147.40001)
		(size 0.4572)
		(drill 0.2032)
		(layers "F.Cu" "B.Cu")
		(net "MEMDQ_4")
	)
	(segment
		(start 18.499582 -144.811242)
		(end 18.2499 -144.56156)
		(width 0.0889)
		(layer "In5.Cu")
		(net "MEMDQ_4")
	)
	(segment
		(start 17.234662 -143.927576)
		(end 17.234662 -143.361664)
		(width 0.0889)
		(layer "In5.Cu")
		(net "MEMDQ_4")
	)
	(segment
		(start 42.900092 -147.40001)
		(end 42.505884 -147.794218)
		(width 0.127)
		(layer "In5.Cu")
		(net "MEMDQ_4")
	)
	(segment
		(start 28.250642 -148.7551)
		(end 26.7335 -148.7551)
		(width 0.127)
		(layer "In5.Cu")
		(net "MEMDQ_4")
	)
	(segment
		(start 19.276568 -144.952974)
		(end 18.641314 -144.952974)
		(width 0.127)
		(layer "In5.Cu")
		(net "MEMDQ_4")
	)
	(segment
		(start 18.641314 -144.952974)
		(end 18.499582 -144.811242)
		(width 0.127)
		(layer "In5.Cu")
		(net "MEMDQ_4")
	)
	(segment
		(start 28.678124 -149.182582)
		(end 28.250642 -148.7551)
		(width 0.127)
		(layer "In5.Cu")
		(net "MEMDQ_4")
	)
	(segment
		(start 18.2499 -144.56156)
		(end 17.868646 -144.56156)
		(width 0.0889)
		(layer "In5.Cu")
		(net "MEMDQ_4")
	)
	(segment
		(start 39.098982 -147.794218)
		(end 38.707822 -148.185378)
		(width 0.127)
		(layer "In5.Cu")
		(net "MEMDQ_4")
	)
	(segment
		(start 17.868646 -144.56156)
		(end 17.234662 -143.927576)
		(width 0.0889)
		(layer "In5.Cu")
		(net "MEMDQ_4")
	)
	(segment
		(start 38.707822 -148.185378)
		(end 36.226242 -148.185378)
		(width 0.127)
		(layer "In5.Cu")
		(net "MEMDQ_4")
	)
	(segment
		(start 36.226242 -148.185378)
		(end 35.229038 -149.182582)
		(width 0.127)
		(layer "In5.Cu")
		(net "MEMDQ_4")
	)
	(segment
		(start 42.505884 -147.794218)
		(end 39.098982 -147.794218)
		(width 0.127)
		(layer "In5.Cu")
		(net "MEMDQ_4")
	)
	(segment
		(start 24.282146 -146.303746)
		(end 24.282146 -145.492978)
		(width 0.127)
		(layer "In5.Cu")
		(net "MEMDQ_4")
	)
	(segment
		(start 24.282146 -145.492978)
		(end 23.826978 -145.03781)
		(width 0.127)
		(layer "In5.Cu")
		(net "MEMDQ_4")
	)
	(segment
		(start 35.229038 -149.182582)
		(end 28.678124 -149.182582)
		(width 0.127)
		(layer "In5.Cu")
		(net "MEMDQ_4")
	)
	(segment
		(start 26.7335 -148.7551)
		(end 24.282146 -146.303746)
		(width 0.127)
		(layer "In5.Cu")
		(net "MEMDQ_4")
	)
	(segment
		(start 19.361404 -145.03781)
		(end 19.276568 -144.952974)
		(width 0.127)
		(layer "In5.Cu")
		(net "MEMDQ_4")
	)
	(segment
		(start 23.826978 -145.03781)
		(end 19.361404 -145.03781)
		(width 0.127)
		(layer "In5.Cu")
		(net "MEMDQ_4")
	)
	(segment
		(start 40.099996 -146.19986)
		(end 39.699946 -146.59991)
		(width 0.127)
		(layer "F.Cu")
		(net "MEMDQ_3")
	)
	(segment
		(start 21.63445 -142.961614)
		(end 21.634196 -142.961614)
		(width 0.127)
		(layer "F.Cu")
		(net "MEMDQ_3")
	)
	(segment
		(start 21.634196 -142.961614)
		(end 21.2344 -143.36141)
		(width 0.127)
		(layer "F.Cu")
		(net "MEMDQ_3")
	)
	(via
		(at 39.699946 -146.59991)
		(size 0.4572)
		(drill 0.2032)
		(layers "F.Cu" "B.Cu")
		(net "MEMDQ_3")
	)
	(via
		(at 21.2344 -143.36141)
		(size 0.508)
		(drill 0.254)
		(layers "F.Cu" "B.Cu")
		(net "MEMDQ_3")
	)
	(segment
		(start 24.61387 -142.96517)
		(end 26.92527 -145.27657)
		(width 0.127)
		(layer "In2.Cu")
		(net "MEMDQ_3")
	)
	(segment
		(start 23.186898 -142.96517)
		(end 24.61387 -142.96517)
		(width 0.127)
		(layer "In2.Cu")
		(net "MEMDQ_3")
	)
	(segment
		(start 35.54222 -144.179544)
		(end 36.142676 -144.78)
		(width 0.127)
		(layer "In2.Cu")
		(net "MEMDQ_3")
	)
	(segment
		(start 42.506392 -146.746468)
		(end 42.25544 -146.99742)
		(width 0.127)
		(layer "In2.Cu")
		(net "MEMDQ_3")
	)
	(segment
		(start 42.378884 -144.606264)
		(end 42.506392 -144.733772)
		(width 0.127)
		(layer "In2.Cu")
		(net "MEMDQ_3")
	)
	(segment
		(start 21.2344 -143.36141)
		(end 21.63445 -142.96136)
		(width 0.0889)
		(layer "In2.Cu")
		(net "MEMDQ_3")
	)
	(segment
		(start 39.705026 -146.59991)
		(end 39.699946 -146.59991)
		(width 0.127)
		(layer "In2.Cu")
		(net "MEMDQ_3")
	)
	(segment
		(start 33.90265 -144.117822)
		(end 34.104072 -143.9164)
		(width 0.127)
		(layer "In2.Cu")
		(net "MEMDQ_3")
	)
	(segment
		(start 32.73044 -145.9992)
		(end 33.90265 -144.82699)
		(width 0.127)
		(layer "In2.Cu")
		(net "MEMDQ_3")
	)
	(segment
		(start 23.183088 -142.96136)
		(end 23.186898 -142.96517)
		(width 0.0889)
		(layer "In2.Cu")
		(net "MEMDQ_3")
	)
	(segment
		(start 35.54222 -144.0434)
		(end 35.54222 -144.179544)
		(width 0.127)
		(layer "In2.Cu")
		(net "MEMDQ_3")
	)
	(segment
		(start 36.142676 -144.78)
		(end 38.52672 -144.78)
		(width 0.127)
		(layer "In2.Cu")
		(net "MEMDQ_3")
	)
	(segment
		(start 42.25544 -146.99742)
		(end 40.438324 -146.99742)
		(width 0.127)
		(layer "In2.Cu")
		(net "MEMDQ_3")
	)
	(segment
		(start 28.358084 -145.27657)
		(end 29.080714 -145.9992)
		(width 0.127)
		(layer "In2.Cu")
		(net "MEMDQ_3")
	)
	(segment
		(start 33.90265 -144.82699)
		(end 33.90265 -144.117822)
		(width 0.127)
		(layer "In2.Cu")
		(net "MEMDQ_3")
	)
	(segment
		(start 35.41522 -143.9164)
		(end 35.54222 -144.0434)
		(width 0.127)
		(layer "In2.Cu")
		(net "MEMDQ_3")
	)
	(segment
		(start 29.080714 -145.9992)
		(end 32.73044 -145.9992)
		(width 0.127)
		(layer "In2.Cu")
		(net "MEMDQ_3")
	)
	(segment
		(start 38.52672 -144.78)
		(end 38.700456 -144.606264)
		(width 0.127)
		(layer "In2.Cu")
		(net "MEMDQ_3")
	)
	(segment
		(start 42.506392 -144.733772)
		(end 42.506392 -146.746468)
		(width 0.127)
		(layer "In2.Cu")
		(net "MEMDQ_3")
	)
	(segment
		(start 34.104072 -143.9164)
		(end 35.41522 -143.9164)
		(width 0.127)
		(layer "In2.Cu")
		(net "MEMDQ_3")
	)
	(segment
		(start 26.92527 -145.27657)
		(end 28.358084 -145.27657)
		(width 0.127)
		(layer "In2.Cu")
		(net "MEMDQ_3")
	)
	(segment
		(start 40.14089 -146.87423)
		(end 39.98087 -146.71421)
		(width 0.127)
		(layer "In2.Cu")
		(net "MEMDQ_3")
	)
	(segment
		(start 21.63445 -142.96136)
		(end 23.183088 -142.96136)
		(width 0.0889)
		(layer "In2.Cu")
		(net "MEMDQ_3")
	)
	(segment
		(start 38.700456 -144.606264)
		(end 42.378884 -144.606264)
		(width 0.127)
		(layer "In2.Cu")
		(net "MEMDQ_3")
	)
	(arc
		(start 40.438324 -146.99742)
		(mid 40.277358 -146.965402)
		(end 40.14089 -146.87423)
		(width 0.127)
		(layer "In2.Cu")
		(net "MEMDQ_3")
	)
	(arc
		(start 39.98087 -146.71421)
		(mid 39.854312 -146.629646)
		(end 39.705026 -146.59991)
		(width 0.127)
		(layer "In2.Cu")
		(net "MEMDQ_3")
	)
	(segment
		(start 18.434558 -142.961614)
		(end 18.034508 -142.561564)
		(width 0.127)
		(layer "F.Cu")
		(net "MEMDQ_2")
	)
	(segment
		(start 40.899842 -146.200114)
		(end 40.899842 -146.19986)
		(width 0.127)
		(layer "F.Cu")
		(net "MEMDQ_2")
	)
	(segment
		(start 40.500046 -146.59991)
		(end 40.899842 -146.200114)
		(width 0.127)
		(layer "F.Cu")
		(net "MEMDQ_2")
	)
	(via
		(at 18.034508 -142.561564)
		(size 0.508)
		(drill 0.254)
		(layers "F.Cu" "B.Cu")
		(net "MEMDQ_2")
	)
	(via
		(at 40.500046 -146.59991)
		(size 0.4572)
		(drill 0.2032)
		(layers "F.Cu" "B.Cu")
		(net "MEMDQ_2")
	)
	(segment
		(start 23.56104 -143.98752)
		(end 23.6982 -143.85036)
		(width 0.127)
		(layer "In5.Cu")
		(net "MEMDQ_2")
	)
	(segment
		(start 19.550888 -144.58061)
		(end 23.3426 -144.58061)
		(width 0.127)
		(layer "In5.Cu")
		(net "MEMDQ_2")
	)
	(segment
		(start 18.7071 -142.68958)
		(end 18.542 -142.85468)
		(width 0.127)
		(layer "In5.Cu")
		(net "MEMDQ_2")
	)
	(segment
		(start 24.36114 -143.97736)
		(end 24.36114 -144.40916)
		(width 0.127)
		(layer "In5.Cu")
		(net "MEMDQ_2")
	)
	(segment
		(start 18.7071 -142.35176)
		(end 18.7071 -142.68958)
		(width 0.127)
		(layer "In5.Cu")
		(net "MEMDQ_2")
	)
	(segment
		(start 23.6982 -143.85036)
		(end 24.23414 -143.85036)
		(width 0.127)
		(layer "In5.Cu")
		(net "MEMDQ_2")
	)
	(segment
		(start 28.882086 -147.2311)
		(end 29.15285 -147.501864)
		(width 0.127)
		(layer "In5.Cu")
		(net "MEMDQ_2")
	)
	(segment
		(start 18.542 -143.50492)
		(end 18.66392 -143.62684)
		(width 0.127)
		(layer "In5.Cu")
		(net "MEMDQ_2")
	)
	(segment
		(start 19.440398 -144.042638)
		(end 19.440398 -144.47012)
		(width 0.127)
		(layer "In5.Cu")
		(net "MEMDQ_2")
	)
	(segment
		(start 40.364664 -146.193764)
		(end 40.500046 -146.329146)
		(width 0.127)
		(layer "In5.Cu")
		(net "MEMDQ_2")
	)
	(segment
		(start 18.542 -142.85468)
		(end 18.542 -143.50492)
		(width 0.127)
		(layer "In5.Cu")
		(net "MEMDQ_2")
	)
	(segment
		(start 26.037794 -145.668492)
		(end 26.037794 -145.90395)
		(width 0.127)
		(layer "In5.Cu")
		(net "MEMDQ_2")
	)
	(segment
		(start 19.440398 -144.47012)
		(end 19.550888 -144.58061)
		(width 0.127)
		(layer "In5.Cu")
		(net "MEMDQ_2")
	)
	(segment
		(start 18.034508 -142.561564)
		(end 18.034508 -142.330932)
		(width 0.127)
		(layer "In5.Cu")
		(net "MEMDQ_2")
	)
	(segment
		(start 37.9222 -145.43532)
		(end 38.20922 -145.72234)
		(width 0.127)
		(layer "In5.Cu")
		(net "MEMDQ_2")
	)
	(segment
		(start 24.36114 -144.40916)
		(end 24.534876 -144.582896)
		(width 0.127)
		(layer "In5.Cu")
		(net "MEMDQ_2")
	)
	(segment
		(start 18.57756 -142.22222)
		(end 18.7071 -142.35176)
		(width 0.127)
		(layer "In5.Cu")
		(net "MEMDQ_2")
	)
	(segment
		(start 26.037794 -145.90395)
		(end 27.364944 -147.2311)
		(width 0.127)
		(layer "In5.Cu")
		(net "MEMDQ_2")
	)
	(segment
		(start 18.66392 -143.62684)
		(end 19.0246 -143.62684)
		(width 0.127)
		(layer "In5.Cu")
		(net "MEMDQ_2")
	)
	(segment
		(start 24.534876 -144.582896)
		(end 24.952198 -144.582896)
		(width 0.127)
		(layer "In5.Cu")
		(net "MEMDQ_2")
	)
	(segment
		(start 29.15285 -147.501864)
		(end 34.676842 -147.501864)
		(width 0.127)
		(layer "In5.Cu")
		(net "MEMDQ_2")
	)
	(segment
		(start 19.0246 -143.62684)
		(end 19.440398 -144.042638)
		(width 0.127)
		(layer "In5.Cu")
		(net "MEMDQ_2")
	)
	(segment
		(start 18.034508 -142.330932)
		(end 18.14322 -142.22222)
		(width 0.127)
		(layer "In5.Cu")
		(net "MEMDQ_2")
	)
	(segment
		(start 38.20922 -145.72234)
		(end 38.20922 -146.066764)
		(width 0.127)
		(layer "In5.Cu")
		(net "MEMDQ_2")
	)
	(segment
		(start 40.500046 -146.329146)
		(end 40.500046 -146.59991)
		(width 0.127)
		(layer "In5.Cu")
		(net "MEMDQ_2")
	)
	(segment
		(start 27.364944 -147.2311)
		(end 28.882086 -147.2311)
		(width 0.127)
		(layer "In5.Cu")
		(net "MEMDQ_2")
	)
	(segment
		(start 38.20922 -146.066764)
		(end 38.33622 -146.193764)
		(width 0.127)
		(layer "In5.Cu")
		(net "MEMDQ_2")
	)
	(segment
		(start 23.56104 -144.36217)
		(end 23.56104 -143.98752)
		(width 0.127)
		(layer "In5.Cu")
		(net "MEMDQ_2")
	)
	(segment
		(start 36.95446 -146.35988)
		(end 36.95446 -145.5674)
		(width 0.127)
		(layer "In5.Cu")
		(net "MEMDQ_2")
	)
	(segment
		(start 37.08654 -145.43532)
		(end 37.9222 -145.43532)
		(width 0.127)
		(layer "In5.Cu")
		(net "MEMDQ_2")
	)
	(segment
		(start 38.33622 -146.193764)
		(end 40.364664 -146.193764)
		(width 0.127)
		(layer "In5.Cu")
		(net "MEMDQ_2")
	)
	(segment
		(start 36.83508 -146.47926)
		(end 36.95446 -146.35988)
		(width 0.127)
		(layer "In5.Cu")
		(net "MEMDQ_2")
	)
	(segment
		(start 23.3426 -144.58061)
		(end 23.56104 -144.36217)
		(width 0.127)
		(layer "In5.Cu")
		(net "MEMDQ_2")
	)
	(segment
		(start 24.952198 -144.582896)
		(end 26.037794 -145.668492)
		(width 0.127)
		(layer "In5.Cu")
		(net "MEMDQ_2")
	)
	(segment
		(start 18.14322 -142.22222)
		(end 18.57756 -142.22222)
		(width 0.127)
		(layer "In5.Cu")
		(net "MEMDQ_2")
	)
	(segment
		(start 24.23414 -143.85036)
		(end 24.36114 -143.97736)
		(width 0.127)
		(layer "In5.Cu")
		(net "MEMDQ_2")
	)
	(segment
		(start 34.676842 -147.501864)
		(end 35.699446 -146.47926)
		(width 0.127)
		(layer "In5.Cu")
		(net "MEMDQ_2")
	)
	(segment
		(start 36.95446 -145.5674)
		(end 37.08654 -145.43532)
		(width 0.127)
		(layer "In5.Cu")
		(net "MEMDQ_2")
	)
	(segment
		(start 35.699446 -146.47926)
		(end 36.83508 -146.47926)
		(width 0.127)
		(layer "In5.Cu")
		(net "MEMDQ_2")
	)
	(segment
		(start 42.900092 -148.999956)
		(end 43.299888 -148.60016)
		(width 0.127)
		(layer "F.Cu")
		(net "MEMDQ_15")
	)
	(segment
		(start 43.299888 -148.60016)
		(end 43.299888 -148.599906)
		(width 0.127)
		(layer "F.Cu")
		(net "MEMDQ_15")
	)
	(segment
		(start 21.63445 -146.161506)
		(end 22.0345 -146.561556)
		(width 0.127)
		(layer "F.Cu")
		(net "MEMDQ_15")
	)
	(via
		(at 22.0345 -146.561556)
		(size 0.508)
		(drill 0.254)
		(layers "F.Cu" "B.Cu")
		(net "MEMDQ_15")
	)
	(via
		(at 42.900092 -148.999956)
		(size 0.4572)
		(drill 0.2032)
		(layers "F.Cu" "B.Cu")
		(net "MEMDQ_15")
	)
	(segment
		(start 37.191188 -152.273)
		(end 40.064436 -149.399752)
		(width 0.127)
		(layer "In5.Cu")
		(net "MEMDQ_15")
	)
	(segment
		(start 23.30704 -149.72792)
		(end 23.48992 -149.9108)
		(width 0.127)
		(layer "In5.Cu")
		(net "MEMDQ_15")
	)
	(segment
		(start 21.15058 -149.44598)
		(end 21.43252 -149.72792)
		(width 0.127)
		(layer "In5.Cu")
		(net "MEMDQ_15")
	)
	(segment
		(start 21.87956 -146.95932)
		(end 21.87956 -147.53336)
		(width 0.127)
		(layer "In5.Cu")
		(net "MEMDQ_15")
	)
	(segment
		(start 21.87956 -147.53336)
		(end 21.15058 -148.26234)
		(width 0.127)
		(layer "In5.Cu")
		(net "MEMDQ_15")
	)
	(segment
		(start 22.0345 -146.80438)
		(end 21.87956 -146.95932)
		(width 0.127)
		(layer "In5.Cu")
		(net "MEMDQ_15")
	)
	(segment
		(start 40.064436 -149.399752)
		(end 42.500296 -149.399752)
		(width 0.127)
		(layer "In5.Cu")
		(net "MEMDQ_15")
	)
	(segment
		(start 21.15058 -148.26234)
		(end 21.15058 -149.44598)
		(width 0.127)
		(layer "In5.Cu")
		(net "MEMDQ_15")
	)
	(segment
		(start 22.45868 -150.5458)
		(end 22.58568 -150.4188)
		(width 0.127)
		(layer "In5.Cu")
		(net "MEMDQ_15")
	)
	(segment
		(start 21.95068 -150.5458)
		(end 22.45868 -150.5458)
		(width 0.127)
		(layer "In5.Cu")
		(net "MEMDQ_15")
	)
	(segment
		(start 21.43252 -149.72792)
		(end 21.69668 -149.72792)
		(width 0.127)
		(layer "In5.Cu")
		(net "MEMDQ_15")
	)
	(segment
		(start 21.69668 -149.72792)
		(end 21.82368 -149.85492)
		(width 0.127)
		(layer "In5.Cu")
		(net "MEMDQ_15")
	)
	(segment
		(start 27.303476 -151.0411)
		(end 28.535376 -152.273)
		(width 0.127)
		(layer "In5.Cu")
		(net "MEMDQ_15")
	)
	(segment
		(start 23.48992 -149.9108)
		(end 23.48992 -150.87346)
		(width 0.127)
		(layer "In5.Cu")
		(net "MEMDQ_15")
	)
	(segment
		(start 28.535376 -152.273)
		(end 37.191188 -152.273)
		(width 0.127)
		(layer "In5.Cu")
		(net "MEMDQ_15")
	)
	(segment
		(start 22.58568 -150.4188)
		(end 22.58568 -149.85492)
		(width 0.127)
		(layer "In5.Cu")
		(net "MEMDQ_15")
	)
	(segment
		(start 22.71268 -149.72792)
		(end 23.30704 -149.72792)
		(width 0.127)
		(layer "In5.Cu")
		(net "MEMDQ_15")
	)
	(segment
		(start 21.82368 -150.4188)
		(end 21.95068 -150.5458)
		(width 0.127)
		(layer "In5.Cu")
		(net "MEMDQ_15")
	)
	(segment
		(start 22.58568 -149.85492)
		(end 22.71268 -149.72792)
		(width 0.127)
		(layer "In5.Cu")
		(net "MEMDQ_15")
	)
	(segment
		(start 23.65756 -151.0411)
		(end 27.303476 -151.0411)
		(width 0.127)
		(layer "In5.Cu")
		(net "MEMDQ_15")
	)
	(segment
		(start 22.0345 -146.561556)
		(end 22.0345 -146.80438)
		(width 0.127)
		(layer "In5.Cu")
		(net "MEMDQ_15")
	)
	(segment
		(start 21.82368 -149.85492)
		(end 21.82368 -150.4188)
		(width 0.127)
		(layer "In5.Cu")
		(net "MEMDQ_15")
	)
	(segment
		(start 42.500296 -149.399752)
		(end 42.900092 -148.999956)
		(width 0.127)
		(layer "In5.Cu")
		(net "MEMDQ_15")
	)
	(segment
		(start 23.48992 -150.87346)
		(end 23.65756 -151.0411)
		(width 0.127)
		(layer "In5.Cu")
		(net "MEMDQ_15")
	)
	(segment
		(start 18.834354 -146.561302)
		(end 18.834608 -146.561302)
		(width 0.127)
		(layer "F.Cu")
		(net "MEMDQ_14")
	)
	(segment
		(start 18.434558 -146.161506)
		(end 18.834354 -146.561302)
		(width 0.127)
		(layer "F.Cu")
		(net "MEMDQ_14")
	)
	(segment
		(start 42.500042 -148.599906)
		(end 42.099992 -148.999956)
		(width 0.127)
		(layer "F.Cu")
		(net "MEMDQ_14")
	)
	(via
		(at 18.834608 -146.561302)
		(size 0.508)
		(drill 0.254)
		(layers "F.Cu" "B.Cu")
		(net "MEMDQ_14")
	)
	(via
		(at 42.099992 -148.999956)
		(size 0.4572)
		(drill 0.2032)
		(layers "F.Cu" "B.Cu")
		(net "MEMDQ_14")
	)
	(segment
		(start 39.60114 -148.47316)
		(end 40.64 -148.47316)
		(width 0.127)
		(layer "In2.Cu")
		(net "MEMDQ_14")
	)
	(segment
		(start 29.77896 -152.20188)
		(end 30.4038 -152.82672)
		(width 0.127)
		(layer "In2.Cu")
		(net "MEMDQ_14")
	)
	(segment
		(start 18.834608 -146.561302)
		(end 18.834608 -146.670268)
		(width 0.127)
		(layer "In2.Cu")
		(net "MEMDQ_14")
	)
	(segment
		(start 38.9763 -149.098)
		(end 39.60114 -148.47316)
		(width 0.127)
		(layer "In2.Cu")
		(net "MEMDQ_14")
	)
	(segment
		(start 38.9763 -150.32482)
		(end 38.9763 -149.098)
		(width 0.127)
		(layer "In2.Cu")
		(net "MEMDQ_14")
	)
	(segment
		(start 40.773604 -148.606764)
		(end 41.176956 -148.606764)
		(width 0.127)
		(layer "In2.Cu")
		(net "MEMDQ_14")
	)
	(segment
		(start 37.594032 -151.3078)
		(end 37.99332 -151.3078)
		(width 0.127)
		(layer "In2.Cu")
		(net "MEMDQ_14")
	)
	(segment
		(start 19.31416 -147.14982)
		(end 19.31416 -150.441914)
		(width 0.127)
		(layer "In2.Cu")
		(net "MEMDQ_14")
	)
	(segment
		(start 37.99332 -151.3078)
		(end 38.9763 -150.32482)
		(width 0.127)
		(layer "In2.Cu")
		(net "MEMDQ_14")
	)
	(segment
		(start 30.4038 -152.82672)
		(end 36.075112 -152.82672)
		(width 0.127)
		(layer "In2.Cu")
		(net "MEMDQ_14")
	)
	(segment
		(start 36.075112 -152.82672)
		(end 37.594032 -151.3078)
		(width 0.127)
		(layer "In2.Cu")
		(net "MEMDQ_14")
	)
	(segment
		(start 40.64 -148.47316)
		(end 40.773604 -148.606764)
		(width 0.127)
		(layer "In2.Cu")
		(net "MEMDQ_14")
	)
	(segment
		(start 21.074126 -152.20188)
		(end 29.77896 -152.20188)
		(width 0.127)
		(layer "In2.Cu")
		(net "MEMDQ_14")
	)
	(segment
		(start 18.834608 -146.670268)
		(end 19.31416 -147.14982)
		(width 0.127)
		(layer "In2.Cu")
		(net "MEMDQ_14")
	)
	(segment
		(start 19.31416 -150.441914)
		(end 21.074126 -152.20188)
		(width 0.127)
		(layer "In2.Cu")
		(net "MEMDQ_14")
	)
	(arc
		(start 41.176956 -148.606764)
		(mid 41.289562 -148.600394)
		(end 41.40073 -148.581364)
		(width 0.127)
		(layer "In2.Cu")
		(net "MEMDQ_14")
	)
	(arc
		(start 41.40073 -148.581364)
		(mid 41.834647 -148.649898)
		(end 42.099992 -148.999956)
		(width 0.127)
		(layer "In2.Cu")
		(net "MEMDQ_14")
	)
	(segment
		(start 22.834346 -146.56181)
		(end 22.834346 -146.561556)
		(width 0.127)
		(layer "F.Cu")
		(net "MEMDQ_13")
	)
	(segment
		(start 22.43455 -146.961606)
		(end 22.834346 -146.56181)
		(width 0.127)
		(layer "F.Cu")
		(net "MEMDQ_13")
	)
	(segment
		(start 41.699942 -148.599906)
		(end 41.299892 -148.999956)
		(width 0.127)
		(layer "F.Cu")
		(net "MEMDQ_13")
	)
	(via
		(at 22.834346 -146.561556)
		(size 0.508)
		(drill 0.254)
		(layers "F.Cu" "B.Cu")
		(net "MEMDQ_13")
	)
	(via
		(at 41.299892 -148.999956)
		(size 0.4572)
		(drill 0.2032)
		(layers "F.Cu" "B.Cu")
		(net "MEMDQ_13")
	)
	(segment
		(start 33.547558 -150.706582)
		(end 33.674558 -150.833582)
		(width 0.127)
		(layer "In5.Cu")
		(net "MEMDQ_13")
	)
	(segment
		(start 40.788336 -148.606256)
		(end 41.182036 -148.999956)
		(width 0.127)
		(layer "In5.Cu")
		(net "MEMDQ_13")
	)
	(segment
		(start 35.198558 -150.833582)
		(end 35.198558 -151.30272)
		(width 0.127)
		(layer "In5.Cu")
		(net "MEMDQ_13")
	)
	(segment
		(start 33.801558 -151.42972)
		(end 34.309558 -151.42972)
		(width 0.127)
		(layer "In5.Cu")
		(net "MEMDQ_13")
	)
	(segment
		(start 34.563558 -150.706582)
		(end 35.071558 -150.706582)
		(width 0.127)
		(layer "In5.Cu")
		(net "MEMDQ_13")
	)
	(segment
		(start 22.69744 -148.38172)
		(end 23.00732 -148.6916)
		(width 0.127)
		(layer "In5.Cu")
		(net "MEMDQ_13")
	)
	(segment
		(start 22.834346 -146.561556)
		(end 22.69744 -146.698462)
		(width 0.127)
		(layer "In5.Cu")
		(net "MEMDQ_13")
	)
	(segment
		(start 25.17902 -149.87524)
		(end 25.58288 -150.2791)
		(width 0.127)
		(layer "In5.Cu")
		(net "MEMDQ_13")
	)
	(segment
		(start 31.515558 -150.706582)
		(end 32.023558 -150.706582)
		(width 0.127)
		(layer "In5.Cu")
		(net "MEMDQ_13")
	)
	(segment
		(start 31.261558 -151.42972)
		(end 31.388558 -151.30272)
		(width 0.127)
		(layer "In5.Cu")
		(net "MEMDQ_13")
	)
	(segment
		(start 28.04668 -150.706582)
		(end 28.975558 -150.706582)
		(width 0.127)
		(layer "In5.Cu")
		(net "MEMDQ_13")
	)
	(segment
		(start 23.00732 -148.6916)
		(end 23.99538 -148.6916)
		(width 0.127)
		(layer "In5.Cu")
		(net "MEMDQ_13")
	)
	(segment
		(start 39.306246 -148.836634)
		(end 39.536624 -148.606256)
		(width 0.127)
		(layer "In5.Cu")
		(net "MEMDQ_13")
	)
	(segment
		(start 29.102558 -151.30272)
		(end 29.229558 -151.42972)
		(width 0.127)
		(layer "In5.Cu")
		(net "MEMDQ_13")
	)
	(segment
		(start 32.023558 -150.706582)
		(end 32.150558 -150.833582)
		(width 0.127)
		(layer "In5.Cu")
		(net "MEMDQ_13")
	)
	(segment
		(start 35.198558 -151.30272)
		(end 35.325558 -151.42972)
		(width 0.127)
		(layer "In5.Cu")
		(net "MEMDQ_13")
	)
	(segment
		(start 28.975558 -150.706582)
		(end 29.102558 -150.833582)
		(width 0.127)
		(layer "In5.Cu")
		(net "MEMDQ_13")
	)
	(segment
		(start 24.4602 -149.336252)
		(end 24.079962 -149.71649)
		(width 0.127)
		(layer "In5.Cu")
		(net "MEMDQ_13")
	)
	(segment
		(start 34.436558 -150.833582)
		(end 34.563558 -150.706582)
		(width 0.127)
		(layer "In5.Cu")
		(net "MEMDQ_13")
	)
	(segment
		(start 30.626558 -151.30272)
		(end 30.753558 -151.42972)
		(width 0.127)
		(layer "In5.Cu")
		(net "MEMDQ_13")
	)
	(segment
		(start 24.999188 -149.87524)
		(end 25.17902 -149.87524)
		(width 0.127)
		(layer "In5.Cu")
		(net "MEMDQ_13")
	)
	(segment
		(start 32.785558 -151.42972)
		(end 32.912558 -151.30272)
		(width 0.127)
		(layer "In5.Cu")
		(net "MEMDQ_13")
	)
	(segment
		(start 32.150558 -151.30272)
		(end 32.277558 -151.42972)
		(width 0.127)
		(layer "In5.Cu")
		(net "MEMDQ_13")
	)
	(segment
		(start 32.277558 -151.42972)
		(end 32.785558 -151.42972)
		(width 0.127)
		(layer "In5.Cu")
		(net "MEMDQ_13")
	)
	(segment
		(start 33.039558 -150.706582)
		(end 33.547558 -150.706582)
		(width 0.127)
		(layer "In5.Cu")
		(net "MEMDQ_13")
	)
	(segment
		(start 34.309558 -151.42972)
		(end 34.436558 -151.30272)
		(width 0.127)
		(layer "In5.Cu")
		(net "MEMDQ_13")
	)
	(segment
		(start 29.864558 -150.833582)
		(end 29.991558 -150.706582)
		(width 0.127)
		(layer "In5.Cu")
		(net "MEMDQ_13")
	)
	(segment
		(start 39.536624 -148.606256)
		(end 40.788336 -148.606256)
		(width 0.127)
		(layer "In5.Cu")
		(net "MEMDQ_13")
	)
	(segment
		(start 25.58288 -150.2791)
		(end 27.619198 -150.2791)
		(width 0.127)
		(layer "In5.Cu")
		(net "MEMDQ_13")
	)
	(segment
		(start 30.626558 -150.833582)
		(end 30.626558 -151.30272)
		(width 0.127)
		(layer "In5.Cu")
		(net "MEMDQ_13")
	)
	(segment
		(start 34.436558 -151.30272)
		(end 34.436558 -150.833582)
		(width 0.127)
		(layer "In5.Cu")
		(net "MEMDQ_13")
	)
	(segment
		(start 22.69744 -146.698462)
		(end 22.69744 -148.38172)
		(width 0.127)
		(layer "In5.Cu")
		(net "MEMDQ_13")
	)
	(segment
		(start 27.619198 -150.2791)
		(end 28.04668 -150.706582)
		(width 0.127)
		(layer "In5.Cu")
		(net "MEMDQ_13")
	)
	(segment
		(start 31.388558 -150.833582)
		(end 31.515558 -150.706582)
		(width 0.127)
		(layer "In5.Cu")
		(net "MEMDQ_13")
	)
	(segment
		(start 37.314378 -151.42972)
		(end 39.306246 -149.437852)
		(width 0.127)
		(layer "In5.Cu")
		(net "MEMDQ_13")
	)
	(segment
		(start 23.99538 -148.6916)
		(end 24.4602 -149.15642)
		(width 0.127)
		(layer "In5.Cu")
		(net "MEMDQ_13")
	)
	(segment
		(start 41.182036 -148.999956)
		(end 41.299892 -148.999956)
		(width 0.127)
		(layer "In5.Cu")
		(net "MEMDQ_13")
	)
	(segment
		(start 39.306246 -149.437852)
		(end 39.306246 -148.836634)
		(width 0.127)
		(layer "In5.Cu")
		(net "MEMDQ_13")
	)
	(segment
		(start 35.325558 -151.42972)
		(end 37.314378 -151.42972)
		(width 0.127)
		(layer "In5.Cu")
		(net "MEMDQ_13")
	)
	(segment
		(start 24.386286 -150.242016)
		(end 24.632412 -150.242016)
		(width 0.127)
		(layer "In5.Cu")
		(net "MEMDQ_13")
	)
	(segment
		(start 32.150558 -150.833582)
		(end 32.150558 -151.30272)
		(width 0.127)
		(layer "In5.Cu")
		(net "MEMDQ_13")
	)
	(segment
		(start 35.071558 -150.706582)
		(end 35.198558 -150.833582)
		(width 0.127)
		(layer "In5.Cu")
		(net "MEMDQ_13")
	)
	(segment
		(start 32.912558 -151.30272)
		(end 32.912558 -150.833582)
		(width 0.127)
		(layer "In5.Cu")
		(net "MEMDQ_13")
	)
	(segment
		(start 30.499558 -150.706582)
		(end 30.626558 -150.833582)
		(width 0.127)
		(layer "In5.Cu")
		(net "MEMDQ_13")
	)
	(segment
		(start 30.753558 -151.42972)
		(end 31.261558 -151.42972)
		(width 0.127)
		(layer "In5.Cu")
		(net "MEMDQ_13")
	)
	(segment
		(start 33.674558 -151.30272)
		(end 33.801558 -151.42972)
		(width 0.127)
		(layer "In5.Cu")
		(net "MEMDQ_13")
	)
	(segment
		(start 29.737558 -151.42972)
		(end 29.864558 -151.30272)
		(width 0.127)
		(layer "In5.Cu")
		(net "MEMDQ_13")
	)
	(segment
		(start 31.388558 -151.30272)
		(end 31.388558 -150.833582)
		(width 0.127)
		(layer "In5.Cu")
		(net "MEMDQ_13")
	)
	(segment
		(start 33.674558 -150.833582)
		(end 33.674558 -151.30272)
		(width 0.127)
		(layer "In5.Cu")
		(net "MEMDQ_13")
	)
	(segment
		(start 29.229558 -151.42972)
		(end 29.737558 -151.42972)
		(width 0.127)
		(layer "In5.Cu")
		(net "MEMDQ_13")
	)
	(segment
		(start 29.991558 -150.706582)
		(end 30.499558 -150.706582)
		(width 0.127)
		(layer "In5.Cu")
		(net "MEMDQ_13")
	)
	(segment
		(start 29.102558 -150.833582)
		(end 29.102558 -151.30272)
		(width 0.127)
		(layer "In5.Cu")
		(net "MEMDQ_13")
	)
	(segment
		(start 24.079962 -149.71649)
		(end 24.079962 -149.935692)
		(width 0.127)
		(layer "In5.Cu")
		(net "MEMDQ_13")
	)
	(segment
		(start 29.864558 -151.30272)
		(end 29.864558 -150.833582)
		(width 0.127)
		(layer "In5.Cu")
		(net "MEMDQ_13")
	)
	(segment
		(start 24.4602 -149.15642)
		(end 24.4602 -149.336252)
		(width 0.127)
		(layer "In5.Cu")
		(net "MEMDQ_13")
	)
	(segment
		(start 32.912558 -150.833582)
		(end 33.039558 -150.706582)
		(width 0.127)
		(layer "In5.Cu")
		(net "MEMDQ_13")
	)
	(segment
		(start 24.632412 -150.242016)
		(end 24.999188 -149.87524)
		(width 0.127)
		(layer "In5.Cu")
		(net "MEMDQ_13")
	)
	(segment
		(start 24.079962 -149.935692)
		(end 24.386286 -150.242016)
		(width 0.127)
		(layer "In5.Cu")
		(net "MEMDQ_13")
	)
	(segment
		(start 17.977358 -150.892764)
		(end 17.977358 -151.586438)
		(width 0.127)
		(layer "F.Cu")
		(net "MEMDQ_12")
	)
	(segment
		(start 21.10486 -152.69464)
		(end 23.77948 -152.69464)
		(width 0.127)
		(layer "F.Cu")
		(net "MEMDQ_12")
	)
	(segment
		(start 23.77948 -152.69464)
		(end 25.61844 -150.85568)
		(width 0.127)
		(layer "F.Cu")
		(net "MEMDQ_12")
	)
	(segment
		(start 18.104358 -150.765764)
		(end 17.977358 -150.892764)
		(width 0.127)
		(layer "F.Cu")
		(net "MEMDQ_12")
	)
	(segment
		(start 36.529264 -150.5585)
		(end 37.018722 -150.5585)
		(width 0.127)
		(layer "F.Cu")
		(net "MEMDQ_12")
	)
	(segment
		(start 18.87728 -150.638764)
		(end 18.75028 -150.765764)
		(width 0.127)
		(layer "F.Cu")
		(net "MEMDQ_12")
	)
	(segment
		(start 18.75028 -150.765764)
		(end 18.104358 -150.765764)
		(width 0.127)
		(layer "F.Cu")
		(net "MEMDQ_12")
	)
	(segment
		(start 28.78582 -150.220172)
		(end 36.190936 -150.220172)
		(width 0.127)
		(layer "F.Cu")
		(net "MEMDQ_12")
	)
	(segment
		(start 28.150312 -150.85568)
		(end 28.78582 -150.220172)
		(width 0.127)
		(layer "F.Cu")
		(net "MEMDQ_12")
	)
	(segment
		(start 19.61388 -153.22296)
		(end 20.57654 -153.22296)
		(width 0.127)
		(layer "F.Cu")
		(net "MEMDQ_12")
	)
	(segment
		(start 39.690802 -149.8092)
		(end 40.099996 -149.400006)
		(width 0.127)
		(layer "F.Cu")
		(net "MEMDQ_12")
	)
	(segment
		(start 20.57654 -153.22296)
		(end 21.10486 -152.69464)
		(width 0.127)
		(layer "F.Cu")
		(net "MEMDQ_12")
	)
	(segment
		(start 37.425122 -150.1521)
		(end 38.7985 -150.1521)
		(width 0.127)
		(layer "F.Cu")
		(net "MEMDQ_12")
	)
	(segment
		(start 17.977358 -151.586438)
		(end 19.61388 -153.22296)
		(width 0.127)
		(layer "F.Cu")
		(net "MEMDQ_12")
	)
	(segment
		(start 17.977358 -149.876764)
		(end 18.104358 -150.003764)
		(width 0.127)
		(layer "F.Cu")
		(net "MEMDQ_12")
	)
	(segment
		(start 37.018722 -150.5585)
		(end 37.425122 -150.1521)
		(width 0.127)
		(layer "F.Cu")
		(net "MEMDQ_12")
	)
	(segment
		(start 17.977358 -147.619212)
		(end 17.977358 -149.876764)
		(width 0.127)
		(layer "F.Cu")
		(net "MEMDQ_12")
	)
	(segment
		(start 18.87728 -150.130764)
		(end 18.87728 -150.638764)
		(width 0.127)
		(layer "F.Cu")
		(net "MEMDQ_12")
	)
	(segment
		(start 25.61844 -150.85568)
		(end 28.150312 -150.85568)
		(width 0.127)
		(layer "F.Cu")
		(net "MEMDQ_12")
	)
	(segment
		(start 36.190936 -150.220172)
		(end 36.529264 -150.5585)
		(width 0.127)
		(layer "F.Cu")
		(net "MEMDQ_12")
	)
	(segment
		(start 18.104358 -150.003764)
		(end 18.75028 -150.003764)
		(width 0.127)
		(layer "F.Cu")
		(net "MEMDQ_12")
	)
	(segment
		(start 38.7985 -150.1521)
		(end 39.1414 -149.8092)
		(width 0.127)
		(layer "F.Cu")
		(net "MEMDQ_12")
	)
	(segment
		(start 18.75028 -150.003764)
		(end 18.87728 -150.130764)
		(width 0.127)
		(layer "F.Cu")
		(net "MEMDQ_12")
	)
	(segment
		(start 39.1414 -149.8092)
		(end 39.690802 -149.8092)
		(width 0.127)
		(layer "F.Cu")
		(net "MEMDQ_12")
	)
	(segment
		(start 17.634458 -147.276312)
		(end 17.977358 -147.619212)
		(width 0.127)
		(layer "F.Cu")
		(net "MEMDQ_12")
	)
	(segment
		(start 17.634458 -146.961606)
		(end 17.634458 -147.276312)
		(width 0.127)
		(layer "F.Cu")
		(net "MEMDQ_12")
	)
	(segment
		(start 21.63445 -146.96186)
		(end 21.234654 -147.361656)
		(width 0.127)
		(layer "F.Cu")
		(net "MEMDQ_11")
	)
	(segment
		(start 21.63445 -146.961606)
		(end 21.63445 -146.96186)
		(width 0.127)
		(layer "F.Cu")
		(net "MEMDQ_11")
	)
	(segment
		(start 41.699942 -147.80006)
		(end 41.299892 -147.40001)
		(width 0.127)
		(layer "F.Cu")
		(net "MEMDQ_11")
	)
	(via
		(at 41.299892 -147.40001)
		(size 0.4572)
		(drill 0.2032)
		(layers "F.Cu" "B.Cu")
		(net "MEMDQ_11")
	)
	(via
		(at 21.234654 -147.361656)
		(size 0.508)
		(drill 0.254)
		(layers "F.Cu" "B.Cu")
		(net "MEMDQ_11")
	)
	(segment
		(start 33.071308 -148.5646)
		(end 33.198308 -148.6916)
		(width 0.127)
		(layer "In2.Cu")
		(net "MEMDQ_11")
	)
	(segment
		(start 33.960308 -149.45614)
		(end 33.960308 -148.6916)
		(width 0.127)
		(layer "In2.Cu")
		(net "MEMDQ_11")
	)
	(segment
		(start 35.678872 -147.771612)
		(end 35.829748 -147.620736)
		(width 0.127)
		(layer "In2.Cu")
		(net "MEMDQ_11")
	)
	(segment
		(start 22.321012 -147.647914)
		(end 22.453854 -147.780756)
		(width 0.127)
		(layer "In2.Cu")
		(net "MEMDQ_11")
	)
	(segment
		(start 34.486596 -148.5646)
		(end 35.279584 -147.771612)
		(width 0.127)
		(layer "In2.Cu")
		(net "MEMDQ_11")
	)
	(segment
		(start 26.416 -148.5646)
		(end 33.071308 -148.5646)
		(width 0.127)
		(layer "In2.Cu")
		(net "MEMDQ_11")
	)
	(segment
		(start 20.252944 -149.324314)
		(end 20.884134 -149.324314)
		(width 0.127)
		(layer "In2.Cu")
		(net "MEMDQ_11")
	)
	(segment
		(start 35.279584 -147.771612)
		(end 35.678872 -147.771612)
		(width 0.127)
		(layer "In2.Cu")
		(net "MEMDQ_11")
	)
	(segment
		(start 23.872444 -147.780756)
		(end 24.499824 -147.153376)
		(width 0.127)
		(layer "In2.Cu")
		(net "MEMDQ_11")
	)
	(segment
		(start 21.031454 -146.79168)
		(end 20.252944 -146.79168)
		(width 0.127)
		(layer "In2.Cu")
		(net "MEMDQ_11")
	)
	(segment
		(start 34.087308 -148.5646)
		(end 34.486596 -148.5646)
		(width 0.127)
		(layer "In2.Cu")
		(net "MEMDQ_11")
	)
	(segment
		(start 33.325308 -149.58314)
		(end 33.833308 -149.58314)
		(width 0.127)
		(layer "In2.Cu")
		(net "MEMDQ_11")
	)
	(segment
		(start 21.234654 -146.99488)
		(end 21.031454 -146.79168)
		(width 0.127)
		(layer "In2.Cu")
		(net "MEMDQ_11")
	)
	(segment
		(start 41.015412 -147.684236)
		(end 41.299892 -147.40001)
		(width 0.127)
		(layer "In2.Cu")
		(net "MEMDQ_11")
	)
	(segment
		(start 21.234654 -147.361656)
		(end 21.234654 -146.99488)
		(width 0.127)
		(layer "In2.Cu")
		(net "MEMDQ_11")
	)
	(segment
		(start 37.194236 -147.620736)
		(end 37.5031 -147.9296)
		(width 0.127)
		(layer "In2.Cu")
		(net "MEMDQ_11")
	)
	(segment
		(start 21.914866 -147.647914)
		(end 22.321012 -147.647914)
		(width 0.127)
		(layer "In2.Cu")
		(net "MEMDQ_11")
	)
	(segment
		(start 33.198308 -148.6916)
		(end 33.198308 -149.45614)
		(width 0.127)
		(layer "In2.Cu")
		(net "MEMDQ_11")
	)
	(segment
		(start 21.087334 -148.475446)
		(end 21.914866 -147.647914)
		(width 0.127)
		(layer "In2.Cu")
		(net "MEMDQ_11")
	)
	(segment
		(start 20.884134 -149.324314)
		(end 21.087334 -149.121114)
		(width 0.127)
		(layer "In2.Cu")
		(net "MEMDQ_11")
	)
	(segment
		(start 20.049744 -146.99488)
		(end 20.049744 -149.121114)
		(width 0.127)
		(layer "In2.Cu")
		(net "MEMDQ_11")
	)
	(segment
		(start 21.087334 -149.121114)
		(end 21.087334 -148.475446)
		(width 0.127)
		(layer "In2.Cu")
		(net "MEMDQ_11")
	)
	(segment
		(start 38.2524 -147.9296)
		(end 38.464236 -147.717764)
		(width 0.127)
		(layer "In2.Cu")
		(net "MEMDQ_11")
	)
	(segment
		(start 38.464236 -147.717764)
		(end 39.41953 -147.717764)
		(width 0.127)
		(layer "In2.Cu")
		(net "MEMDQ_11")
	)
	(segment
		(start 33.833308 -149.58314)
		(end 33.960308 -149.45614)
		(width 0.127)
		(layer "In2.Cu")
		(net "MEMDQ_11")
	)
	(segment
		(start 33.960308 -148.6916)
		(end 34.087308 -148.5646)
		(width 0.127)
		(layer "In2.Cu")
		(net "MEMDQ_11")
	)
	(segment
		(start 37.5031 -147.9296)
		(end 38.2524 -147.9296)
		(width 0.127)
		(layer "In2.Cu")
		(net "MEMDQ_11")
	)
	(segment
		(start 25.004776 -147.153376)
		(end 26.416 -148.5646)
		(width 0.127)
		(layer "In2.Cu")
		(net "MEMDQ_11")
	)
	(segment
		(start 22.453854 -147.780756)
		(end 23.872444 -147.780756)
		(width 0.127)
		(layer "In2.Cu")
		(net "MEMDQ_11")
	)
	(segment
		(start 33.198308 -149.45614)
		(end 33.325308 -149.58314)
		(width 0.127)
		(layer "In2.Cu")
		(net "MEMDQ_11")
	)
	(segment
		(start 35.829748 -147.620736)
		(end 37.194236 -147.620736)
		(width 0.127)
		(layer "In2.Cu")
		(net "MEMDQ_11")
	)
	(segment
		(start 24.499824 -147.153376)
		(end 25.004776 -147.153376)
		(width 0.127)
		(layer "In2.Cu")
		(net "MEMDQ_11")
	)
	(segment
		(start 20.049744 -149.121114)
		(end 20.252944 -149.324314)
		(width 0.127)
		(layer "In2.Cu")
		(net "MEMDQ_11")
	)
	(segment
		(start 39.664894 -147.819364)
		(end 40.68953 -147.819364)
		(width 0.127)
		(layer "In2.Cu")
		(net "MEMDQ_11")
	)
	(segment
		(start 20.252944 -146.79168)
		(end 20.049744 -146.99488)
		(width 0.127)
		(layer "In2.Cu")
		(net "MEMDQ_11")
	)
	(arc
		(start 39.41953 -147.717764)
		(mid 39.532104 -147.792984)
		(end 39.664894 -147.819364)
		(width 0.127)
		(layer "In2.Cu")
		(net "MEMDQ_11")
	)
	(arc
		(start 40.68953 -147.819364)
		(mid 40.865897 -147.784189)
		(end 41.015412 -147.684236)
		(width 0.127)
		(layer "In2.Cu")
		(net "MEMDQ_11")
	)
	(segment
		(start 40.500046 -148.999956)
		(end 40.899842 -148.60016)
		(width 0.127)
		(layer "F.Cu")
		(net "MEMDQ_10")
	)
	(segment
		(start 18.434558 -146.961606)
		(end 18.434812 -146.961606)
		(width 0.127)
		(layer "F.Cu")
		(net "MEMDQ_10")
	)
	(segment
		(start 40.899842 -148.60016)
		(end 40.899842 -148.599906)
		(width 0.127)
		(layer "F.Cu")
		(net "MEMDQ_10")
	)
	(segment
		(start 18.434812 -146.961606)
		(end 18.834608 -147.361402)
		(width 0.127)
		(layer "F.Cu")
		(net "MEMDQ_10")
	)
	(via
		(at 40.500046 -148.999956)
		(size 0.4572)
		(drill 0.2032)
		(layers "F.Cu" "B.Cu")
		(net "MEMDQ_10")
	)
	(via
		(at 18.834608 -147.361402)
		(size 0.508)
		(drill 0.254)
		(layers "F.Cu" "B.Cu")
		(net "MEMDQ_10")
	)
	(segment
		(start 29.72943 -153.61158)
		(end 36.477956 -153.61158)
		(width 0.127)
		(layer "In2.Cu")
		(net "MEMDQ_10")
	)
	(segment
		(start 29.31795 -153.2001)
		(end 29.72943 -153.61158)
		(width 0.127)
		(layer "In2.Cu")
		(net "MEMDQ_10")
	)
	(segment
		(start 38.19398 -152.13584)
		(end 38.88994 -151.43988)
		(width 0.127)
		(layer "In2.Cu")
		(net "MEMDQ_10")
	)
	(segment
		(start 18.668238 -147.361402)
		(end 17.96288 -148.06676)
		(width 0.127)
		(layer "In2.Cu")
		(net "MEMDQ_10")
	)
	(segment
		(start 38.88994 -150.95982)
		(end 40.02786 -149.8219)
		(width 0.127)
		(layer "In2.Cu")
		(net "MEMDQ_10")
	)
	(segment
		(start 40.02786 -149.472142)
		(end 40.500046 -148.999956)
		(width 0.127)
		(layer "In2.Cu")
		(net "MEMDQ_10")
	)
	(segment
		(start 36.477956 -153.61158)
		(end 37.953696 -152.13584)
		(width 0.127)
		(layer "In2.Cu")
		(net "MEMDQ_10")
	)
	(segment
		(start 17.96288 -148.06676)
		(end 17.96288 -151.396192)
		(width 0.127)
		(layer "In2.Cu")
		(net "MEMDQ_10")
	)
	(segment
		(start 17.96288 -151.396192)
		(end 19.766788 -153.2001)
		(width 0.127)
		(layer "In2.Cu")
		(net "MEMDQ_10")
	)
	(segment
		(start 18.834608 -147.361402)
		(end 18.668238 -147.361402)
		(width 0.127)
		(layer "In2.Cu")
		(net "MEMDQ_10")
	)
	(segment
		(start 38.88994 -151.43988)
		(end 38.88994 -150.95982)
		(width 0.127)
		(layer "In2.Cu")
		(net "MEMDQ_10")
	)
	(segment
		(start 37.953696 -152.13584)
		(end 38.19398 -152.13584)
		(width 0.127)
		(layer "In2.Cu")
		(net "MEMDQ_10")
	)
	(segment
		(start 40.02786 -149.8219)
		(end 40.02786 -149.472142)
		(width 0.127)
		(layer "In2.Cu")
		(net "MEMDQ_10")
	)
	(segment
		(start 19.766788 -153.2001)
		(end 29.31795 -153.2001)
		(width 0.127)
		(layer "In2.Cu")
		(net "MEMDQ_10")
	)
	(segment
		(start 34.907728 -147.09902)
		(end 35.034728 -146.97202)
		(width 0.127)
		(layer "F.Cu")
		(net "MEMDQ_1")
	)
	(segment
		(start 27.21229 -147.934172)
		(end 34.552128 -147.934172)
		(width 0.127)
		(layer "F.Cu")
		(net "MEMDQ_1")
	)
	(segment
		(start 27.08529 -147.807172)
		(end 27.21229 -147.934172)
		(width 0.127)
		(layer "F.Cu")
		(net "MEMDQ_1")
	)
	(segment
		(start 21.63445 -144.56156)
		(end 21.63445 -144.82191)
		(width 0.127)
		(layer "F.Cu")
		(net "MEMDQ_1")
	)
	(segment
		(start 24.3078 -147.08124)
		(end 24.47036 -147.2438)
		(width 0.127)
		(layer "F.Cu")
		(net "MEMDQ_1")
	)
	(segment
		(start 35.034728 -146.97202)
		(end 37.143944 -146.97202)
		(width 0.127)
		(layer "F.Cu")
		(net "MEMDQ_1")
	)
	(segment
		(start 24.39924 -145.43786)
		(end 24.600662 -145.639282)
		(width 0.127)
		(layer "F.Cu")
		(net "MEMDQ_1")
	)
	(segment
		(start 37.143944 -146.97202)
		(end 37.270944 -146.84502)
		(width 0.127)
		(layer "F.Cu")
		(net "MEMDQ_1")
	)
	(segment
		(start 26.133298 -145.766282)
		(end 26.133298 -146.324828)
		(width 0.127)
		(layer "F.Cu")
		(net "MEMDQ_1")
	)
	(segment
		(start 26.22677 -148.56968)
		(end 26.32329 -148.47316)
		(width 0.127)
		(layer "F.Cu")
		(net "MEMDQ_1")
	)
	(segment
		(start 37.270944 -146.84502)
		(end 37.270944 -146.516344)
		(width 0.127)
		(layer "F.Cu")
		(net "MEMDQ_1")
	)
	(segment
		(start 26.32329 -148.47316)
		(end 26.32329 -147.59432)
		(width 0.127)
		(layer "F.Cu")
		(net "MEMDQ_1")
	)
	(segment
		(start 26.133044 -146.325082)
		(end 26.01976 -146.43862)
		(width 0.127)
		(layer "F.Cu")
		(net "MEMDQ_1")
	)
	(segment
		(start 25.05964 -147.2438)
		(end 25.3365 -147.52066)
		(width 0.127)
		(layer "F.Cu")
		(net "MEMDQ_1")
	)
	(segment
		(start 27.08529 -147.56765)
		(end 27.08529 -147.807172)
		(width 0.127)
		(layer "F.Cu")
		(net "MEMDQ_1")
	)
	(segment
		(start 26.006298 -145.639282)
		(end 26.133298 -145.766282)
		(width 0.127)
		(layer "F.Cu")
		(net "MEMDQ_1")
	)
	(segment
		(start 24.27224 -144.83334)
		(end 24.39924 -144.96034)
		(width 0.127)
		(layer "F.Cu")
		(net "MEMDQ_1")
	)
	(segment
		(start 38.921944 -145.812764)
		(end 40.99433 -145.812764)
		(width 0.127)
		(layer "F.Cu")
		(net "MEMDQ_1")
	)
	(segment
		(start 37.07892 -146.32432)
		(end 37.07892 -146.078448)
		(width 0.127)
		(layer "F.Cu")
		(net "MEMDQ_1")
	)
	(segment
		(start 26.463752 -147.453858)
		(end 26.971498 -147.453858)
		(width 0.127)
		(layer "F.Cu")
		(net "MEMDQ_1")
	)
	(segment
		(start 26.32329 -147.59432)
		(end 26.463752 -147.453858)
		(width 0.127)
		(layer "F.Cu")
		(net "MEMDQ_1")
	)
	(segment
		(start 34.552128 -147.934172)
		(end 34.907728 -147.578572)
		(width 0.127)
		(layer "F.Cu")
		(net "MEMDQ_1")
	)
	(segment
		(start 38.66134 -145.55216)
		(end 38.921944 -145.812764)
		(width 0.127)
		(layer "F.Cu")
		(net "MEMDQ_1")
	)
	(segment
		(start 26.133298 -146.324828)
		(end 26.133044 -146.325082)
		(width 0.127)
		(layer "F.Cu")
		(net "MEMDQ_1")
	)
	(segment
		(start 41.53789 -146.038062)
		(end 41.699942 -146.19986)
		(width 0.127)
		(layer "F.Cu")
		(net "MEMDQ_1")
	)
	(segment
		(start 24.39924 -144.96034)
		(end 24.39924 -145.43786)
		(width 0.127)
		(layer "F.Cu")
		(net "MEMDQ_1")
	)
	(segment
		(start 26.971498 -147.453858)
		(end 27.08529 -147.56765)
		(width 0.127)
		(layer "F.Cu")
		(net "MEMDQ_1")
	)
	(segment
		(start 24.3078 -146.56562)
		(end 24.3078 -147.08124)
		(width 0.127)
		(layer "F.Cu")
		(net "MEMDQ_1")
	)
	(segment
		(start 25.3365 -147.52066)
		(end 25.3365 -148.47316)
		(width 0.127)
		(layer "F.Cu")
		(net "MEMDQ_1")
	)
	(segment
		(start 24.600662 -145.639282)
		(end 26.006298 -145.639282)
		(width 0.127)
		(layer "F.Cu")
		(net "MEMDQ_1")
	)
	(segment
		(start 21.63445 -144.82191)
		(end 21.8313 -145.01876)
		(width 0.127)
		(layer "F.Cu")
		(net "MEMDQ_1")
	)
	(segment
		(start 24.47036 -147.2438)
		(end 25.05964 -147.2438)
		(width 0.127)
		(layer "F.Cu")
		(net "MEMDQ_1")
	)
	(segment
		(start 25.43302 -148.56968)
		(end 26.22677 -148.56968)
		(width 0.127)
		(layer "F.Cu")
		(net "MEMDQ_1")
	)
	(segment
		(start 21.8313 -145.01876)
		(end 23.45182 -145.01876)
		(width 0.127)
		(layer "F.Cu")
		(net "MEMDQ_1")
	)
	(segment
		(start 23.45182 -145.01876)
		(end 23.63724 -144.83334)
		(width 0.127)
		(layer "F.Cu")
		(net "MEMDQ_1")
	)
	(segment
		(start 25.3365 -148.47316)
		(end 25.43302 -148.56968)
		(width 0.127)
		(layer "F.Cu")
		(net "MEMDQ_1")
	)
	(segment
		(start 37.270944 -146.516344)
		(end 37.07892 -146.32432)
		(width 0.127)
		(layer "F.Cu")
		(net "MEMDQ_1")
	)
	(segment
		(start 24.4348 -146.43862)
		(end 24.3078 -146.56562)
		(width 0.127)
		(layer "F.Cu")
		(net "MEMDQ_1")
	)
	(segment
		(start 23.63724 -144.83334)
		(end 24.27224 -144.83334)
		(width 0.127)
		(layer "F.Cu")
		(net "MEMDQ_1")
	)
	(segment
		(start 37.07892 -146.078448)
		(end 37.605208 -145.55216)
		(width 0.127)
		(layer "F.Cu")
		(net "MEMDQ_1")
	)
	(segment
		(start 37.605208 -145.55216)
		(end 38.66134 -145.55216)
		(width 0.127)
		(layer "F.Cu")
		(net "MEMDQ_1")
	)
	(segment
		(start 34.907728 -147.578572)
		(end 34.907728 -147.09902)
		(width 0.127)
		(layer "F.Cu")
		(net "MEMDQ_1")
	)
	(segment
		(start 26.01976 -146.43862)
		(end 24.4348 -146.43862)
		(width 0.127)
		(layer "F.Cu")
		(net "MEMDQ_1")
	)
	(arc
		(start 40.99433 -145.812764)
		(mid 41.288531 -145.87132)
		(end 41.53789 -146.038062)
		(width 0.127)
		(layer "F.Cu")
		(net "MEMDQ_1")
	)
	(segment
		(start 17.634712 -143.76146)
		(end 18.034508 -143.361664)
		(width 0.127)
		(layer "F.Cu")
		(net "MEMDQ_0")
	)
	(segment
		(start 18.034508 -143.361664)
		(end 18.034508 -143.356584)
		(width 0.127)
		(layer "F.Cu")
		(net "MEMDQ_0")
	)
	(segment
		(start 43.299888 -146.200114)
		(end 43.299888 -146.19986)
		(width 0.127)
		(layer "F.Cu")
		(net "MEMDQ_0")
	)
	(segment
		(start 17.634458 -143.76146)
		(end 17.634712 -143.76146)
		(width 0.127)
		(layer "F.Cu")
		(net "MEMDQ_0")
	)
	(segment
		(start 42.900092 -146.59991)
		(end 43.299888 -146.200114)
		(width 0.127)
		(layer "F.Cu")
		(net "MEMDQ_0")
	)
	(via
		(at 42.900092 -146.59991)
		(size 0.4572)
		(drill 0.2032)
		(layers "F.Cu" "B.Cu")
		(net "MEMDQ_0")
	)
	(via
		(at 18.034508 -143.356584)
		(size 0.508)
		(drill 0.254)
		(layers "F.Cu" "B.Cu")
		(net "MEMDQ_0")
	)
	(segment
		(start 19.456146 -144.80921)
		(end 19.350736 -144.7038)
		(width 0.127)
		(layer "In5.Cu")
		(net "MEMDQ_0")
	)
	(segment
		(start 25.041098 -145.984976)
		(end 25.041098 -145.928588)
		(width 0.127)
		(layer "In5.Cu")
		(net "MEMDQ_0")
	)
	(segment
		(start 43.08856 -146.07032)
		(end 42.90568 -145.88744)
		(width 0.127)
		(layer "In5.Cu")
		(net "MEMDQ_0")
	)
	(segment
		(start 42.0624 -146.705574)
		(end 41.774364 -146.99361)
		(width 0.127)
		(layer "In5.Cu")
		(net "MEMDQ_0")
	)
	(segment
		(start 42.0624 -146.42084)
		(end 42.0624 -146.705574)
		(width 0.127)
		(layer "In5.Cu")
		(net "MEMDQ_0")
	)
	(segment
		(start 28.566364 -147.9931)
		(end 27.049222 -147.9931)
		(width 0.127)
		(layer "In5.Cu")
		(net "MEMDQ_0")
	)
	(segment
		(start 37.160454 -147.698206)
		(end 36.90874 -147.446492)
		(width 0.127)
		(layer "In5.Cu")
		(net "MEMDQ_0")
	)
	(segment
		(start 41.774364 -146.99361)
		(end 39.536624 -146.99361)
		(width 0.127)
		(layer "In5.Cu")
		(net "MEMDQ_0")
	)
	(segment
		(start 28.837128 -148.263864)
		(end 28.566364 -147.9931)
		(width 0.127)
		(layer "In5.Cu")
		(net "MEMDQ_0")
	)
	(segment
		(start 18.803366 -144.7038)
		(end 18.784316 -144.68475)
		(width 0.127)
		(layer "In5.Cu")
		(net "MEMDQ_0")
	)
	(segment
		(start 38.832028 -147.698206)
		(end 37.160454 -147.698206)
		(width 0.127)
		(layer "In5.Cu")
		(net "MEMDQ_0")
	)
	(segment
		(start 18.434558 -144.334992)
		(end 18.434558 -143.913098)
		(width 0.0889)
		(layer "In5.Cu")
		(net "MEMDQ_0")
	)
	(segment
		(start 35.887406 -147.446492)
		(end 35.070034 -148.263864)
		(width 0.127)
		(layer "In5.Cu")
		(net "MEMDQ_0")
	)
	(segment
		(start 18.784316 -144.68475)
		(end 18.434558 -144.334992)
		(width 0.0889)
		(layer "In5.Cu")
		(net "MEMDQ_0")
	)
	(segment
		(start 35.070034 -148.263864)
		(end 28.837128 -148.263864)
		(width 0.127)
		(layer "In5.Cu")
		(net "MEMDQ_0")
	)
	(segment
		(start 25.041098 -145.928588)
		(end 23.92172 -144.80921)
		(width 0.127)
		(layer "In5.Cu")
		(net "MEMDQ_0")
	)
	(segment
		(start 42.900092 -146.59991)
		(end 43.08856 -146.411442)
		(width 0.127)
		(layer "In5.Cu")
		(net "MEMDQ_0")
	)
	(segment
		(start 23.92172 -144.80921)
		(end 19.456146 -144.80921)
		(width 0.127)
		(layer "In5.Cu")
		(net "MEMDQ_0")
	)
	(segment
		(start 43.08856 -146.411442)
		(end 43.08856 -146.07032)
		(width 0.127)
		(layer "In5.Cu")
		(net "MEMDQ_0")
	)
	(segment
		(start 27.049222 -147.9931)
		(end 25.041098 -145.984976)
		(width 0.127)
		(layer "In5.Cu")
		(net "MEMDQ_0")
	)
	(segment
		(start 42.90568 -145.88744)
		(end 42.5958 -145.88744)
		(width 0.127)
		(layer "In5.Cu")
		(net "MEMDQ_0")
	)
	(segment
		(start 18.434558 -143.913098)
		(end 18.034508 -143.513048)
		(width 0.0889)
		(layer "In5.Cu")
		(net "MEMDQ_0")
	)
	(segment
		(start 42.5958 -145.88744)
		(end 42.0624 -146.42084)
		(width 0.127)
		(layer "In5.Cu")
		(net "MEMDQ_0")
	)
	(segment
		(start 19.350736 -144.7038)
		(end 18.803366 -144.7038)
		(width 0.127)
		(layer "In5.Cu")
		(net "MEMDQ_0")
	)
	(segment
		(start 39.536624 -146.99361)
		(end 38.832028 -147.698206)
		(width 0.127)
		(layer "In5.Cu")
		(net "MEMDQ_0")
	)
	(segment
		(start 18.034508 -143.513048)
		(end 18.034508 -143.356584)
		(width 0.0889)
		(layer "In5.Cu")
		(net "MEMDQ_0")
	)
	(segment
		(start 36.90874 -147.446492)
		(end 35.887406 -147.446492)
		(width 0.127)
		(layer "In5.Cu")
		(net "MEMDQ_0")
	)
	(segment
		(start 39.25062 -148.648928)
		(end 39.299896 -148.599906)
		(width 0.12446)
		(layer "F.Cu")
		(net "MEMDQS_P1")
	)
	(segment
		(start 22.0345 -148.161502)
		(end 21.63445 -147.761452)
		(width 0.12446)
		(layer "F.Cu")
		(net "MEMDQS_P1")
	)
	(segment
		(start 38.7096 -148.771356)
		(end 38.955472 -148.771356)
		(width 0.12446)
		(layer "F.Cu")
		(net "MEMDQS_P1")
	)
	(segment
		(start 37.267896 -149.3774)
		(end 37.5285 -149.3774)
		(width 0.12446)
		(layer "F.Cu")
		(net "MEMDQS_P1")
	)
	(segment
		(start 36.798504 -149.141942)
		(end 36.868608 -149.212046)
		(width 0.12446)
		(layer "F.Cu")
		(net "MEMDQS_P1")
	)
	(segment
		(start 38.1127 -149.018244)
		(end 38.1127 -149.018498)
		(width 0.12446)
		(layer "F.Cu")
		(net "MEMDQS_P1")
	)
	(segment
		(start 37.913056 -149.217888)
		(end 38.1127 -149.018244)
		(width 0.12446)
		(layer "F.Cu")
		(net "MEMDQS_P1")
	)
	(via
		(at 36.798504 -149.141942)
		(size 0.508)
		(drill 0.254)
		(layers "F.Cu" "B.Cu")
		(net "MEMDQS_P1")
	)
	(via
		(at 22.0345 -148.161502)
		(size 0.508)
		(drill 0.254)
		(layers "F.Cu" "B.Cu")
		(net "MEMDQS_P1")
	)
	(arc
		(start 38.1127 -149.018498)
		(mid 38.386547 -148.835486)
		(end 38.7096 -148.771356)
		(width 0.12446)
		(layer "F.Cu")
		(net "MEMDQS_P1")
	)
	(arc
		(start 36.868608 -149.212046)
		(mid 37.051803 -149.334453)
		(end 37.267896 -149.3774)
		(width 0.12446)
		(layer "F.Cu")
		(net "MEMDQS_P1")
	)
	(arc
		(start 37.5285 -149.3774)
		(mid 37.736652 -149.335902)
		(end 37.913056 -149.217888)
		(width 0.12446)
		(layer "F.Cu")
		(net "MEMDQS_P1")
	)
	(arc
		(start 38.955472 -148.771356)
		(mid 39.115218 -148.739487)
		(end 39.25062 -148.648928)
		(width 0.12446)
		(layer "F.Cu")
		(net "MEMDQS_P1")
	)
	(segment
		(start 35.58286 -150.145242)
		(end 35.58286 -151.423878)
		(width 0.1016)
		(layer "In2.Cu")
		(net "MEMDQS_P1")
	)
	(segment
		(start 29.791914 -150.872444)
		(end 29.264356 -150.872444)
		(width 0.1016)
		(layer "In2.Cu")
		(net "MEMDQS_P1")
	)
	(segment
		(start 21.419058 -150.012654)
		(end 23.843234 -150.012654)
		(width 0.1016)
		(layer "In2.Cu")
		(net "MEMDQS_P1")
	)
	(segment
		(start 35.234118 -151.77262)
		(end 31.528512 -151.77262)
		(width 0.1016)
		(layer "In2.Cu")
		(net "MEMDQS_P1")
	)
	(segment
		(start 36.44138 -149.456902)
		(end 36.2712 -149.456902)
		(width 0.1016)
		(layer "In2.Cu")
		(net "MEMDQS_P1")
	)
	(segment
		(start 30.769052 -151.458168)
		(end 30.454346 -151.143462)
		(width 0.1016)
		(layer "In2.Cu")
		(net "MEMDQS_P1")
	)
	(segment
		(start 25.132792 -150.872444)
		(end 21.419058 -150.872444)
		(width 0.1016)
		(layer "In2.Cu")
		(net "MEMDQS_P1")
	)
	(segment
		(start 22.095968 -148.222716)
		(end 22.0345 -148.161502)
		(width 0.1016)
		(layer "In2.Cu")
		(net "MEMDQS_P1")
	)
	(segment
		(start 23.843234 -148.372068)
		(end 22.45614 -148.372068)
		(width 0.1016)
		(layer "In2.Cu")
		(net "MEMDQS_P1")
	)
	(arc
		(start 36.2712 -149.456902)
		(mid 35.78447 -149.658512)
		(end 35.58286 -150.145242)
		(width 0.1016)
		(layer "In2.Cu")
		(net "MEMDQS_P1")
	)
	(arc
		(start 28.902152 -150.60295)
		(mid 28.657498 -150.237819)
		(end 28.241244 -150.096728)
		(width 0.1016)
		(layer "In2.Cu")
		(net "MEMDQS_P1")
	)
	(arc
		(start 30.454346 -151.143462)
		(mid 30.149775 -150.94283)
		(end 29.791914 -150.872444)
		(width 0.1016)
		(layer "In2.Cu")
		(net "MEMDQS_P1")
	)
	(arc
		(start 25.499822 -150.651464)
		(mid 25.347002 -150.812937)
		(end 25.132792 -150.872444)
		(width 0.1016)
		(layer "In2.Cu")
		(net "MEMDQS_P1")
	)
	(arc
		(start 28.241244 -150.096728)
		(mid 27.852022 -150.215325)
		(end 27.595068 -150.530814)
		(width 0.1016)
		(layer "In2.Cu")
		(net "MEMDQS_P1")
	)
	(arc
		(start 22.45614 -148.372068)
		(mid 22.261207 -148.3332)
		(end 22.095968 -148.222716)
		(width 0.1016)
		(layer "In2.Cu")
		(net "MEMDQS_P1")
	)
	(arc
		(start 36.798504 -149.141942)
		(mid 36.679473 -149.366929)
		(end 36.44138 -149.456902)
		(width 0.1016)
		(layer "In2.Cu")
		(net "MEMDQS_P1")
	)
	(arc
		(start 26.208482 -150.088346)
		(mid 25.755909 -150.246267)
		(end 25.499822 -150.651464)
		(width 0.1016)
		(layer "In2.Cu")
		(net "MEMDQS_P1")
	)
	(arc
		(start 29.264356 -150.872444)
		(mid 29.036515 -150.800552)
		(end 28.902152 -150.60295)
		(width 0.1016)
		(layer "In2.Cu")
		(net "MEMDQS_P1")
	)
	(arc
		(start 31.528512 -151.77262)
		(mid 31.117515 -151.690903)
		(end 30.769052 -151.458168)
		(width 0.1016)
		(layer "In2.Cu")
		(net "MEMDQS_P1")
	)
	(arc
		(start 21.419058 -150.872444)
		(mid 20.98929 -150.442676)
		(end 21.419058 -150.012654)
		(width 0.1016)
		(layer "In2.Cu")
		(net "MEMDQS_P1")
	)
	(arc
		(start 27.595068 -150.530814)
		(mid 27.183028 -150.761881)
		(end 26.795984 -150.490936)
		(width 0.1016)
		(layer "In2.Cu")
		(net "MEMDQS_P1")
	)
	(arc
		(start 35.58286 -151.423878)
		(mid 35.480716 -151.670476)
		(end 35.234118 -151.77262)
		(width 0.1016)
		(layer "In2.Cu")
		(net "MEMDQS_P1")
	)
	(arc
		(start 23.843234 -150.012654)
		(mid 24.6634 -149.192488)
		(end 23.843234 -148.372068)
		(width 0.1016)
		(layer "In2.Cu")
		(net "MEMDQS_P1")
	)
	(arc
		(start 26.795984 -150.490936)
		(mid 26.564594 -150.19863)
		(end 26.208482 -150.088346)
		(width 0.1016)
		(layer "In2.Cu")
		(net "MEMDQS_P1")
	)
	(segment
		(start 18.434558 -143.76146)
		(end 18.034508 -144.16151)
		(width 0.12446)
		(layer "F.Cu")
		(net "MEMDQS_P0")
	)
	(segment
		(start 38.065456 -146.84502)
		(end 39.022528 -146.84502)
		(width 0.12446)
		(layer "F.Cu")
		(net "MEMDQS_P0")
	)
	(via
		(at 37.695886 -147.155662)
		(size 0.508)
		(drill 0.254)
		(layers "F.Cu" "B.Cu")
		(net "MEMDQS_P0")
	)
	(via
		(at 18.034508 -144.16151)
		(size 0.508)
		(drill 0.254)
		(layers "F.Cu" "B.Cu")
		(net "MEMDQS_P0")
	)
	(arc
		(start 39.054024 -146.846544)
		(mid 39.194949 -146.894412)
		(end 39.299896 -146.99996)
		(width 0.12446)
		(layer "F.Cu")
		(net "MEMDQS_P0")
	)
	(arc
		(start 39.022528 -146.84502)
		(mid 39.038294 -146.845402)
		(end 39.054024 -146.846544)
		(width 0.12446)
		(layer "F.Cu")
		(net "MEMDQS_P0")
	)
	(arc
		(start 37.695886 -147.155662)
		(mid 37.824064 -146.932995)
		(end 38.065456 -146.84502)
		(width 0.12446)
		(layer "F.Cu")
		(net "MEMDQS_P0")
	)
	(segment
		(start 18.174716 -144.500092)
		(end 18.174716 -145.286984)
		(width 0.1016)
		(layer "In2.Cu")
		(net "MEMDQS_P0")
	)
	(segment
		(start 19.816572 -145.477992)
		(end 19.816572 -142.804388)
		(width 0.1016)
		(layer "In2.Cu")
		(net "MEMDQS_P0")
	)
	(segment
		(start 24.228044 -145.297906)
		(end 26.495248 -147.564856)
		(width 0.1016)
		(layer "In2.Cu")
		(net "MEMDQS_P0")
	)
	(segment
		(start 27.100022 -147.8153)
		(end 33.250124 -147.8153)
		(width 0.1016)
		(layer "In2.Cu")
		(net "MEMDQS_P0")
	)
	(segment
		(start 20.506944 -142.804388)
		(end 20.506944 -144.659858)
		(width 0.1016)
		(layer "In2.Cu")
		(net "MEMDQS_P0")
	)
	(segment
		(start 33.982406 -147.512278)
		(end 34.295588 -147.199096)
		(width 0.1016)
		(layer "In2.Cu")
		(net "MEMDQS_P0")
	)
	(segment
		(start 20.97532 -145.128234)
		(end 23.81885 -145.128234)
		(width 0.1016)
		(layer "In2.Cu")
		(net "MEMDQS_P0")
	)
	(segment
		(start 35.103816 -146.864324)
		(end 37.221668 -146.864324)
		(width 0.1016)
		(layer "In2.Cu")
		(net "MEMDQS_P0")
	)
	(segment
		(start 18.416524 -145.871184)
		(end 18.42897 -145.88363)
		(width 0.1016)
		(layer "In2.Cu")
		(net "MEMDQS_P0")
	)
	(segment
		(start 18.983198 -146.112992)
		(end 19.181572 -146.112992)
		(width 0.1016)
		(layer "In2.Cu")
		(net "MEMDQS_P0")
	)
	(arc
		(start 19.630644 -145.927572)
		(mid 19.768303 -145.721273)
		(end 19.816572 -145.477992)
		(width 0.1016)
		(layer "In2.Cu")
		(net "MEMDQS_P0")
	)
	(arc
		(start 19.816572 -142.804388)
		(mid 20.161758 -142.459202)
		(end 20.506944 -142.804388)
		(width 0.1016)
		(layer "In2.Cu")
		(net "MEMDQS_P0")
	)
	(arc
		(start 20.506944 -144.659858)
		(mid 20.644128 -144.99105)
		(end 20.97532 -145.128234)
		(width 0.1016)
		(layer "In2.Cu")
		(net "MEMDQS_P0")
	)
	(arc
		(start 26.495248 -147.564856)
		(mid 26.772735 -147.750204)
		(end 27.100022 -147.8153)
		(width 0.1016)
		(layer "In2.Cu")
		(net "MEMDQS_P0")
	)
	(arc
		(start 18.034508 -144.16151)
		(mid 18.138305 -144.316853)
		(end 18.174716 -144.500092)
		(width 0.1016)
		(layer "In2.Cu")
		(net "MEMDQS_P0")
	)
	(arc
		(start 18.174716 -145.286984)
		(mid 18.237509 -145.603137)
		(end 18.416524 -145.871184)
		(width 0.1016)
		(layer "In2.Cu")
		(net "MEMDQS_P0")
	)
	(arc
		(start 18.42897 -145.88363)
		(mid 18.683281 -146.053399)
		(end 18.983198 -146.112992)
		(width 0.1016)
		(layer "In2.Cu")
		(net "MEMDQS_P0")
	)
	(arc
		(start 23.81885 -145.128234)
		(mid 24.040319 -145.172381)
		(end 24.228044 -145.297906)
		(width 0.1016)
		(layer "In2.Cu")
		(net "MEMDQS_P0")
	)
	(arc
		(start 19.181572 -146.112992)
		(mid 19.424546 -146.06492)
		(end 19.630644 -145.927572)
		(width 0.1016)
		(layer "In2.Cu")
		(net "MEMDQS_P0")
	)
	(arc
		(start 33.250124 -147.8153)
		(mid 33.646411 -147.736643)
		(end 33.982406 -147.512278)
		(width 0.1016)
		(layer "In2.Cu")
		(net "MEMDQS_P0")
	)
	(arc
		(start 34.295588 -147.199096)
		(mid 34.666406 -146.951323)
		(end 35.103816 -146.864324)
		(width 0.1016)
		(layer "In2.Cu")
		(net "MEMDQS_P0")
	)
	(arc
		(start 37.221668 -146.864324)
		(mid 37.499949 -146.942976)
		(end 37.695886 -147.155662)
		(width 0.1016)
		(layer "In2.Cu")
		(net "MEMDQS_P0")
	)
	(segment
		(start 38.200584 -149.505416)
		(end 38.400228 -149.305772)
		(width 0.12446)
		(layer "F.Cu")
		(net "MEMDQS_N1")
	)
	(segment
		(start 38.709346 -149.177756)
		(end 38.955472 -149.177756)
		(width 0.12446)
		(layer "F.Cu")
		(net "MEMDQS_N1")
	)
	(segment
		(start 39.164006 -149.264116)
		(end 39.299896 -149.400006)
		(width 0.12446)
		(layer "F.Cu")
		(net "MEMDQS_N1")
	)
	(segment
		(start 37.267896 -149.7838)
		(end 37.5285 -149.7838)
		(width 0.12446)
		(layer "F.Cu")
		(net "MEMDQS_N1")
	)
	(segment
		(start 22.0345 -148.961602)
		(end 21.63445 -148.561552)
		(width 0.12446)
		(layer "F.Cu")
		(net "MEMDQS_N1")
	)
	(segment
		(start 36.798504 -150.076916)
		(end 36.96716 -149.908514)
		(width 0.12446)
		(layer "F.Cu")
		(net "MEMDQS_N1")
	)
	(via
		(at 22.0345 -148.961602)
		(size 0.508)
		(drill 0.254)
		(layers "F.Cu" "B.Cu")
		(net "MEMDQS_N1")
	)
	(via
		(at 36.798504 -150.076916)
		(size 0.508)
		(drill 0.254)
		(layers "F.Cu" "B.Cu")
		(net "MEMDQS_N1")
	)
	(arc
		(start 38.400228 -149.305772)
		(mid 38.542053 -149.211008)
		(end 38.709346 -149.177756)
		(width 0.12446)
		(layer "F.Cu")
		(net "MEMDQS_N1")
	)
	(arc
		(start 37.5285 -149.7838)
		(mid 37.892228 -149.71145)
		(end 38.200584 -149.505416)
		(width 0.12446)
		(layer "F.Cu")
		(net "MEMDQS_N1")
	)
	(arc
		(start 38.955472 -149.177756)
		(mid 39.068323 -149.200203)
		(end 39.164006 -149.264116)
		(width 0.12446)
		(layer "F.Cu")
		(net "MEMDQS_N1")
	)
	(arc
		(start 36.96716 -149.908514)
		(mid 37.105124 -149.816237)
		(end 37.267896 -149.7838)
		(width 0.12446)
		(layer "F.Cu")
		(net "MEMDQS_N1")
	)
	(segment
		(start 36.2712 -149.761702)
		(end 36.441126 -149.761702)
		(width 0.1016)
		(layer "In2.Cu")
		(net "MEMDQS_N1")
	)
	(segment
		(start 29.272992 -151.177244)
		(end 29.791914 -151.177244)
		(width 0.1016)
		(layer "In2.Cu")
		(net "MEMDQS_N1")
	)
	(segment
		(start 23.843234 -149.707854)
		(end 21.419058 -149.707854)
		(width 0.1016)
		(layer "In2.Cu")
		(net "MEMDQS_N1")
	)
	(segment
		(start 28.607512 -150.682198)
		(end 28.607766 -150.682198)
		(width 0.1016)
		(layer "In2.Cu")
		(net "MEMDQS_N1")
	)
	(segment
		(start 30.239716 -151.360124)
		(end 30.553406 -151.673814)
		(width 0.1016)
		(layer "In2.Cu")
		(net "MEMDQS_N1")
	)
	(segment
		(start 21.419058 -151.177244)
		(end 25.132792 -151.177244)
		(width 0.1016)
		(layer "In2.Cu")
		(net "MEMDQS_N1")
	)
	(segment
		(start 22.45614 -148.676868)
		(end 23.843234 -148.676868)
		(width 0.1016)
		(layer "In2.Cu")
		(net "MEMDQS_N1")
	)
	(segment
		(start 25.76957 -150.794212)
		(end 25.769316 -150.793958)
		(width 0.1016)
		(layer "In2.Cu")
		(net "MEMDQS_N1")
	)
	(segment
		(start 31.528258 -152.07742)
		(end 35.234118 -152.07742)
		(width 0.1016)
		(layer "In2.Cu")
		(net "MEMDQS_N1")
	)
	(segment
		(start 35.88766 -151.423878)
		(end 35.88766 -150.145242)
		(width 0.1016)
		(layer "In2.Cu")
		(net "MEMDQS_N1")
	)
	(segment
		(start 22.0345 -148.961602)
		(end 22.22246 -148.773642)
		(width 0.1016)
		(layer "In2.Cu")
		(net "MEMDQS_N1")
	)
	(segment
		(start 26.515314 -150.6093)
		(end 26.51506 -150.6093)
		(width 0.1016)
		(layer "In2.Cu")
		(net "MEMDQS_N1")
	)
	(arc
		(start 22.22246 -148.773642)
		(mid 22.329673 -148.702004)
		(end 22.45614 -148.676868)
		(width 0.1016)
		(layer "In2.Cu")
		(net "MEMDQS_N1")
	)
	(arc
		(start 30.553406 -151.673814)
		(mid 31.000715 -151.972506)
		(end 31.528258 -152.07742)
		(width 0.1016)
		(layer "In2.Cu")
		(net "MEMDQS_N1")
	)
	(arc
		(start 23.843234 -148.676868)
		(mid 24.358854 -149.192488)
		(end 23.843234 -149.707854)
		(width 0.1016)
		(layer "In2.Cu")
		(net "MEMDQS_N1")
	)
	(arc
		(start 27.881326 -150.636224)
		(mid 28.026425 -150.465436)
		(end 28.241244 -150.401528)
		(width 0.1016)
		(layer "In2.Cu")
		(net "MEMDQS_N1")
	)
	(arc
		(start 26.51506 -150.6093)
		(mid 27.1678 -151.066432)
		(end 27.862784 -150.67661)
		(width 0.1016)
		(layer "In2.Cu")
		(net "MEMDQS_N1")
	)
	(arc
		(start 35.88766 -150.145242)
		(mid 35.999996 -149.874038)
		(end 36.2712 -149.761702)
		(width 0.1016)
		(layer "In2.Cu")
		(net "MEMDQS_N1")
	)
	(arc
		(start 25.796748 -150.720298)
		(mid 25.945537 -150.484885)
		(end 26.208482 -150.393146)
		(width 0.1016)
		(layer "In2.Cu")
		(net "MEMDQS_N1")
	)
	(arc
		(start 26.208482 -150.393146)
		(mid 26.39219 -150.450077)
		(end 26.511504 -150.600918)
		(width 0.1016)
		(layer "In2.Cu")
		(net "MEMDQS_N1")
	)
	(arc
		(start 26.511504 -150.600918)
		(mid 26.513483 -150.605075)
		(end 26.515314 -150.6093)
		(width 0.1016)
		(layer "In2.Cu")
		(net "MEMDQS_N1")
	)
	(arc
		(start 27.862784 -150.67661)
		(mid 27.872741 -150.656732)
		(end 27.881326 -150.636224)
		(width 0.1016)
		(layer "In2.Cu")
		(net "MEMDQS_N1")
	)
	(arc
		(start 28.607766 -150.682198)
		(mid 28.854434 -151.045231)
		(end 29.272992 -151.177244)
		(width 0.1016)
		(layer "In2.Cu")
		(net "MEMDQS_N1")
	)
	(arc
		(start 36.441126 -149.761702)
		(mid 36.679382 -149.851767)
		(end 36.798504 -150.076916)
		(width 0.1016)
		(layer "In2.Cu")
		(net "MEMDQS_N1")
	)
	(arc
		(start 21.419058 -149.707854)
		(mid 20.684236 -150.442676)
		(end 21.419058 -151.177244)
		(width 0.1016)
		(layer "In2.Cu")
		(net "MEMDQS_N1")
	)
	(arc
		(start 35.234118 -152.07742)
		(mid 35.696242 -151.886002)
		(end 35.88766 -151.423878)
		(width 0.1016)
		(layer "In2.Cu")
		(net "MEMDQS_N1")
	)
	(arc
		(start 28.241244 -150.401528)
		(mid 28.471942 -150.479772)
		(end 28.607512 -150.682198)
		(width 0.1016)
		(layer "In2.Cu")
		(net "MEMDQS_N1")
	)
	(arc
		(start 25.132792 -151.177244)
		(mid 25.504371 -151.074163)
		(end 25.76957 -150.794212)
		(width 0.1016)
		(layer "In2.Cu")
		(net "MEMDQS_N1")
	)
	(arc
		(start 25.769316 -150.793958)
		(mid 25.785413 -150.758016)
		(end 25.796748 -150.720298)
		(width 0.1016)
		(layer "In2.Cu")
		(net "MEMDQS_N1")
	)
	(arc
		(start 29.791914 -151.177244)
		(mid 30.033736 -151.224786)
		(end 30.239716 -151.360124)
		(width 0.1016)
		(layer "In2.Cu")
		(net "MEMDQS_N1")
	)
	(segment
		(start 39.022274 -146.43862)
		(end 38.090602 -146.43862)
		(width 0.12446)
		(layer "F.Cu")
		(net "MEMDQS_N0")
	)
	(segment
		(start 18.434558 -144.56156)
		(end 18.834608 -144.16151)
		(width 0.12446)
		(layer "F.Cu")
		(net "MEMDQS_N0")
	)
	(via
		(at 37.695886 -146.220688)
		(size 0.508)
		(drill 0.254)
		(layers "F.Cu" "B.Cu")
		(net "MEMDQS_N0")
	)
	(via
		(at 18.834608 -144.16151)
		(size 0.508)
		(drill 0.254)
		(layers "F.Cu" "B.Cu")
		(net "MEMDQS_N0")
	)
	(arc
		(start 39.299896 -146.19986)
		(mid 39.205391 -146.370785)
		(end 39.022274 -146.43862)
		(width 0.12446)
		(layer "F.Cu")
		(net "MEMDQS_N0")
	)
	(arc
		(start 38.090602 -146.43862)
		(mid 37.865169 -146.380512)
		(end 37.695886 -146.220688)
		(width 0.12446)
		(layer "F.Cu")
		(net "MEMDQS_N0")
	)
	(segment
		(start 19.181572 -145.808192)
		(end 18.983198 -145.808192)
		(width 0.1016)
		(layer "In2.Cu")
		(net "MEMDQS_N0")
	)
	(segment
		(start 19.511772 -142.804388)
		(end 19.511772 -145.478246)
		(width 0.1016)
		(layer "In2.Cu")
		(net "MEMDQS_N0")
	)
	(segment
		(start 37.221668 -146.559524)
		(end 35.103816 -146.559524)
		(width 0.1016)
		(layer "In2.Cu")
		(net "MEMDQS_N0")
	)
	(segment
		(start 22.530054 -144.823434)
		(end 22.225254 -144.823434)
		(width 0.1016)
		(layer "In2.Cu")
		(net "MEMDQS_N0")
	)
	(segment
		(start 23.819104 -144.823434)
		(end 23.637494 -144.823434)
		(width 0.1016)
		(layer "In2.Cu")
		(net "MEMDQS_N0")
	)
	(segment
		(start 26.710894 -147.34921)
		(end 24.687022 -145.325338)
		(width 0.1016)
		(layer "In2.Cu")
		(net "MEMDQS_N0")
	)
	(segment
		(start 19.414998 -145.711926)
		(end 19.414998 -145.711672)
		(width 0.1016)
		(layer "In2.Cu")
		(net "MEMDQS_N0")
	)
	(segment
		(start 34.079942 -146.98345)
		(end 33.76676 -147.296632)
		(width 0.1016)
		(layer "In2.Cu")
		(net "MEMDQS_N0")
	)
	(segment
		(start 23.236174 -144.622774)
		(end 22.931374 -144.622774)
		(width 0.1016)
		(layer "In2.Cu")
		(net "MEMDQS_N0")
	)
	(segment
		(start 18.734532 -144.16151)
		(end 18.834608 -144.16151)
		(width 0.1016)
		(layer "In2.Cu")
		(net "MEMDQS_N0")
	)
	(segment
		(start 24.687022 -145.325338)
		(end 24.44369 -145.08226)
		(width 0.1016)
		(layer "In2.Cu")
		(net "MEMDQS_N0")
	)
	(segment
		(start 21.823934 -144.622774)
		(end 21.519134 -144.622774)
		(width 0.1016)
		(layer "In2.Cu")
		(net "MEMDQS_N0")
	)
	(segment
		(start 20.811744 -144.659858)
		(end 20.811744 -142.804388)
		(width 0.1016)
		(layer "In2.Cu")
		(net "MEMDQS_N0")
	)
	(segment
		(start 18.479516 -145.286984)
		(end 18.479516 -144.416526)
		(width 0.1016)
		(layer "In2.Cu")
		(net "MEMDQS_N0")
	)
	(segment
		(start 18.644616 -145.667984)
		(end 18.63217 -145.655538)
		(width 0.1016)
		(layer "In2.Cu")
		(net "MEMDQS_N0")
	)
	(segment
		(start 21.117814 -144.823434)
		(end 20.97532 -144.823434)
		(width 0.1016)
		(layer "In2.Cu")
		(net "MEMDQS_N0")
	)
	(segment
		(start 33.250124 -147.5105)
		(end 27.100276 -147.5105)
		(width 0.1016)
		(layer "In2.Cu")
		(net "MEMDQS_N0")
	)
	(arc
		(start 18.63217 -145.655538)
		(mid 18.519185 -145.486444)
		(end 18.479516 -145.286984)
		(width 0.1016)
		(layer "In2.Cu")
		(net "MEMDQS_N0")
	)
	(arc
		(start 22.730714 -144.723104)
		(mid 22.642188 -144.796864)
		(end 22.530054 -144.823434)
		(width 0.1016)
		(layer "In2.Cu")
		(net "MEMDQS_N0")
	)
	(arc
		(start 21.318474 -144.723104)
		(mid 21.229948 -144.796864)
		(end 21.117814 -144.823434)
		(width 0.1016)
		(layer "In2.Cu")
		(net "MEMDQS_N0")
	)
	(arc
		(start 27.100276 -147.5105)
		(mid 26.889543 -147.468583)
		(end 26.710894 -147.34921)
		(width 0.1016)
		(layer "In2.Cu")
		(net "MEMDQS_N0")
	)
	(arc
		(start 37.695886 -146.220688)
		(mid 37.513108 -146.466167)
		(end 37.221668 -146.559524)
		(width 0.1016)
		(layer "In2.Cu")
		(net "MEMDQS_N0")
	)
	(arc
		(start 19.511772 -145.478246)
		(mid 19.486633 -145.604719)
		(end 19.414998 -145.711926)
		(width 0.1016)
		(layer "In2.Cu")
		(net "MEMDQS_N0")
	)
	(arc
		(start 21.519134 -144.622774)
		(mid 21.406977 -144.649298)
		(end 21.318474 -144.723104)
		(width 0.1016)
		(layer "In2.Cu")
		(net "MEMDQS_N0")
	)
	(arc
		(start 23.637494 -144.823434)
		(mid 23.525337 -144.79691)
		(end 23.436834 -144.723104)
		(width 0.1016)
		(layer "In2.Cu")
		(net "MEMDQS_N0")
	)
	(arc
		(start 20.811744 -142.804388)
		(mid 20.161758 -142.154402)
		(end 19.511772 -142.804388)
		(width 0.1016)
		(layer "In2.Cu")
		(net "MEMDQS_N0")
	)
	(arc
		(start 24.44369 -145.08226)
		(mid 24.157128 -144.890756)
		(end 23.819104 -144.823434)
		(width 0.1016)
		(layer "In2.Cu")
		(net "MEMDQS_N0")
	)
	(arc
		(start 19.414998 -145.711672)
		(mid 19.307873 -145.783125)
		(end 19.181572 -145.808192)
		(width 0.1016)
		(layer "In2.Cu")
		(net "MEMDQS_N0")
	)
	(arc
		(start 33.76676 -147.296632)
		(mid 33.529725 -147.454984)
		(end 33.250124 -147.5105)
		(width 0.1016)
		(layer "In2.Cu")
		(net "MEMDQS_N0")
	)
	(arc
		(start 35.103816 -146.559524)
		(mid 34.549713 -146.669648)
		(end 34.079942 -146.98345)
		(width 0.1016)
		(layer "In2.Cu")
		(net "MEMDQS_N0")
	)
	(arc
		(start 18.983198 -145.808192)
		(mid 18.799959 -145.771761)
		(end 18.644616 -145.667984)
		(width 0.1016)
		(layer "In2.Cu")
		(net "MEMDQS_N0")
	)
	(arc
		(start 22.024594 -144.723104)
		(mid 21.936068 -144.649344)
		(end 21.823934 -144.622774)
		(width 0.1016)
		(layer "In2.Cu")
		(net "MEMDQS_N0")
	)
	(arc
		(start 22.225254 -144.823434)
		(mid 22.113097 -144.79691)
		(end 22.024594 -144.723104)
		(width 0.1016)
		(layer "In2.Cu")
		(net "MEMDQS_N0")
	)
	(arc
		(start 23.436834 -144.723104)
		(mid 23.348308 -144.649344)
		(end 23.236174 -144.622774)
		(width 0.1016)
		(layer "In2.Cu")
		(net "MEMDQS_N0")
	)
	(arc
		(start 22.931374 -144.622774)
		(mid 22.819217 -144.649298)
		(end 22.730714 -144.723104)
		(width 0.1016)
		(layer "In2.Cu")
		(net "MEMDQS_N0")
	)
	(arc
		(start 18.479516 -144.416526)
		(mid 18.554208 -144.236202)
		(end 18.734532 -144.16151)
		(width 0.1016)
		(layer "In2.Cu")
		(net "MEMDQS_N0")
	)
	(arc
		(start 20.97532 -144.823434)
		(mid 20.859654 -144.775524)
		(end 20.811744 -144.659858)
		(width 0.1016)
		(layer "In2.Cu")
		(net "MEMDQS_N0")
	)
	(segment
		(start 20.243292 -143.342106)
		(end 20.388072 -143.486886)
		(width 0.127)
		(layer "F.Cu")
		(net "MEMDM_1")
	)
	(segment
		(start 19.554952 -145.549874)
		(end 19.554952 -143.486886)
		(width 0.127)
		(layer "F.Cu")
		(net "MEMDM_1")
	)
	(segment
		(start 19.252946 -145.85188)
		(end 19.554952 -145.549874)
		(width 0.127)
		(layer "F.Cu")
		(net "MEMDM_1")
	)
	(segment
		(start 36.16706 -147.7772)
		(end 39.277036 -147.7772)
		(width 0.127)
		(layer "F.Cu")
		(net "MEMDM_1")
	)
	(segment
		(start 20.388072 -149.129242)
		(end 20.894294 -149.635464)
		(width 0.127)
		(layer "F.Cu")
		(net "MEMDM_1")
	)
	(segment
		(start 18.768314 -145.85188)
		(end 19.252946 -145.85188)
		(width 0.127)
		(layer "F.Cu")
		(net "MEMDM_1")
	)
	(segment
		(start 35.900106 -148.044154)
		(end 36.16706 -147.7772)
		(width 0.127)
		(layer "F.Cu")
		(net "MEMDM_1")
	)
	(segment
		(start 35.22345 -148.696172)
		(end 35.875468 -148.044154)
		(width 0.127)
		(layer "F.Cu")
		(net "MEMDM_1")
	)
	(segment
		(start 39.277036 -147.7772)
		(end 39.299896 -147.80006)
		(width 0.127)
		(layer "F.Cu")
		(net "MEMDM_1")
	)
	(segment
		(start 20.894294 -149.635464)
		(end 24.31796 -149.635464)
		(width 0.127)
		(layer "F.Cu")
		(net "MEMDM_1")
	)
	(segment
		(start 26.983436 -149.33168)
		(end 27.618944 -148.696172)
		(width 0.127)
		(layer "F.Cu")
		(net "MEMDM_1")
	)
	(segment
		(start 18.6436 -145.727166)
		(end 18.768314 -145.85188)
		(width 0.127)
		(layer "F.Cu")
		(net "MEMDM_1")
	)
	(segment
		(start 17.999964 -145.727166)
		(end 18.6436 -145.727166)
		(width 0.127)
		(layer "F.Cu")
		(net "MEMDM_1")
	)
	(segment
		(start 19.699732 -143.342106)
		(end 20.243292 -143.342106)
		(width 0.127)
		(layer "F.Cu")
		(net "MEMDM_1")
	)
	(segment
		(start 24.31796 -149.635464)
		(end 24.621744 -149.33168)
		(width 0.127)
		(layer "F.Cu")
		(net "MEMDM_1")
	)
	(segment
		(start 19.554952 -143.486886)
		(end 19.699732 -143.342106)
		(width 0.127)
		(layer "F.Cu")
		(net "MEMDM_1")
	)
	(segment
		(start 17.634458 -145.36166)
		(end 17.999964 -145.727166)
		(width 0.127)
		(layer "F.Cu")
		(net "MEMDM_1")
	)
	(segment
		(start 20.388072 -143.486886)
		(end 20.388072 -149.129242)
		(width 0.127)
		(layer "F.Cu")
		(net "MEMDM_1")
	)
	(segment
		(start 24.621744 -149.33168)
		(end 26.983436 -149.33168)
		(width 0.127)
		(layer "F.Cu")
		(net "MEMDM_1")
	)
	(segment
		(start 27.618944 -148.696172)
		(end 35.22345 -148.696172)
		(width 0.127)
		(layer "F.Cu")
		(net "MEMDM_1")
	)
	(segment
		(start 35.875468 -148.044154)
		(end 35.900106 -148.044154)
		(width 0.127)
		(layer "F.Cu")
		(net "MEMDM_1")
	)
	(segment
		(start 21.63445 -145.36166)
		(end 21.2344 -145.76171)
		(width 0.127)
		(layer "F.Cu")
		(net "MEMDM_0")
	)
	(segment
		(start 43.299888 -147.80006)
		(end 42.900092 -148.199856)
		(width 0.127)
		(layer "F.Cu")
		(net "MEMDM_0")
	)
	(via
		(at 42.900092 -148.199856)
		(size 0.4572)
		(drill 0.2032)
		(layers "F.Cu" "B.Cu")
		(net "MEMDM_0")
	)
	(via
		(at 21.2344 -145.76171)
		(size 0.508)
		(drill 0.254)
		(layers "F.Cu" "B.Cu")
		(net "MEMDM_0")
	)
	(segment
		(start 40.919146 -148.377656)
		(end 39.441882 -148.377656)
		(width 0.127)
		(layer "In5.Cu")
		(net "MEMDM_0")
	)
	(segment
		(start 24.053546 -147.877022)
		(end 24.053546 -145.58772)
		(width 0.127)
		(layer "In5.Cu")
		(net "MEMDM_0")
	)
	(segment
		(start 28.362402 -149.944582)
		(end 27.93492 -149.5171)
		(width 0.127)
		(layer "In5.Cu")
		(net "MEMDM_0")
	)
	(segment
		(start 26.058622 -149.5171)
		(end 24.952198 -148.410676)
		(width 0.127)
		(layer "In5.Cu")
		(net "MEMDM_0")
	)
	(segment
		(start 36.295838 -150.65375)
		(end 35.58667 -149.944582)
		(width 0.127)
		(layer "In5.Cu")
		(net "MEMDM_0")
	)
	(segment
		(start 20.03298 -145.498566)
		(end 20.03298 -145.899378)
		(width 0.127)
		(layer "In5.Cu")
		(net "MEMDM_0")
	)
	(segment
		(start 42.506392 -148.593556)
		(end 41.135046 -148.593556)
		(width 0.127)
		(layer "In5.Cu")
		(net "MEMDM_0")
	)
	(segment
		(start 27.93492 -149.5171)
		(end 26.058622 -149.5171)
		(width 0.127)
		(layer "In5.Cu")
		(net "MEMDM_0")
	)
	(segment
		(start 24.952198 -148.410676)
		(end 24.5872 -148.410676)
		(width 0.127)
		(layer "In5.Cu")
		(net "MEMDM_0")
	)
	(segment
		(start 23.732236 -145.26641)
		(end 20.265136 -145.26641)
		(width 0.127)
		(layer "In5.Cu")
		(net "MEMDM_0")
	)
	(segment
		(start 20.919948 -146.076162)
		(end 21.2344 -145.76171)
		(width 0.127)
		(layer "In5.Cu")
		(net "MEMDM_0")
	)
	(segment
		(start 37.165788 -150.65375)
		(end 36.295838 -150.65375)
		(width 0.127)
		(layer "In5.Cu")
		(net "MEMDM_0")
	)
	(segment
		(start 42.900092 -148.199856)
		(end 42.506392 -148.593556)
		(width 0.127)
		(layer "In5.Cu")
		(net "MEMDM_0")
	)
	(segment
		(start 39.441882 -148.377656)
		(end 37.165788 -150.65375)
		(width 0.127)
		(layer "In5.Cu")
		(net "MEMDM_0")
	)
	(segment
		(start 20.265136 -145.26641)
		(end 20.03298 -145.498566)
		(width 0.127)
		(layer "In5.Cu")
		(net "MEMDM_0")
	)
	(segment
		(start 20.03298 -145.899378)
		(end 20.209764 -146.076162)
		(width 0.127)
		(layer "In5.Cu")
		(net "MEMDM_0")
	)
	(segment
		(start 24.053546 -145.58772)
		(end 23.732236 -145.26641)
		(width 0.127)
		(layer "In5.Cu")
		(net "MEMDM_0")
	)
	(segment
		(start 24.5872 -148.410676)
		(end 24.053546 -147.877022)
		(width 0.127)
		(layer "In5.Cu")
		(net "MEMDM_0")
	)
	(segment
		(start 35.58667 -149.944582)
		(end 28.362402 -149.944582)
		(width 0.127)
		(layer "In5.Cu")
		(net "MEMDM_0")
	)
	(segment
		(start 20.209764 -146.076162)
		(end 20.919948 -146.076162)
		(width 0.127)
		(layer "In5.Cu")
		(net "MEMDM_0")
	)
	(segment
		(start 41.135046 -148.593556)
		(end 40.919146 -148.377656)
		(width 0.127)
		(layer "In5.Cu")
		(net "MEMDM_0")
	)
	(segment
		(start 26.70302 -144.20596)
		(end 29.79674 -144.20596)
		(width 0.127)
		(layer "F.Cu")
		(net "MEMCSN")
	)
	(segment
		(start 31.120334 -144.08404)
		(end 30.993334 -144.21104)
		(width 0.127)
		(layer "F.Cu")
		(net "MEMCSN")
	)
	(segment
		(start 30.485334 -143.47698)
		(end 26.70302 -143.47698)
		(width 0.127)
		(layer "F.Cu")
		(net "MEMCSN")
	)
	(segment
		(start 30.612334 -144.08404)
		(end 30.612334 -143.60398)
		(width 0.127)
		(layer "F.Cu")
		(net "MEMCSN")
	)
	(segment
		(start 30.739334 -144.21104)
		(end 30.612334 -144.08404)
		(width 0.127)
		(layer "F.Cu")
		(net "MEMCSN")
	)
	(segment
		(start 30.993334 -144.21104)
		(end 30.739334 -144.21104)
		(width 0.127)
		(layer "F.Cu")
		(net "MEMCSN")
	)
	(segment
		(start 40.099996 -144.599914)
		(end 40.061134 -144.599914)
		(width 0.1016)
		(layer "F.Cu")
		(net "MEMCSN")
	)
	(segment
		(start 34.125408 -144.092168)
		(end 33.51022 -143.47698)
		(width 0.127)
		(layer "F.Cu")
		(net "MEMCSN")
	)
	(segment
		(start 39.80053 -144.491964)
		(end 39.67353 -144.364964)
		(width 0.1016)
		(layer "F.Cu")
		(net "MEMCSN")
	)
	(segment
		(start 20.301204 -138.400028)
		(end 20.2946 -138.393424)
		(width 0.127)
		(layer "F.Cu")
		(net "MEMCSN")
	)
	(segment
		(start 19.15287 -130.562858)
		(end 19.15287 -129.530094)
		(width 0.127)
		(layer "F.Cu")
		(net "MEMCSN")
	)
	(segment
		(start 19.15287 -129.530094)
		(end 19.144742 -129.521966)
		(width 0.127)
		(layer "F.Cu")
		(net "MEMCSN")
	)
	(segment
		(start 20.825968 -140.161264)
		(end 20.225004 -139.5603)
		(width 0.127)
		(layer "F.Cu")
		(net "MEMCSN")
	)
	(segment
		(start 21.234146 -140.161264)
		(end 20.825968 -140.161264)
		(width 0.127)
		(layer "F.Cu")
		(net "MEMCSN")
	)
	(segment
		(start 20.2946 -138.393424)
		(end 20.2946 -134.04723)
		(width 0.127)
		(layer "F.Cu")
		(net "MEMCSN")
	)
	(segment
		(start 26.57602 -144.07896)
		(end 26.70302 -144.20596)
		(width 0.127)
		(layer "F.Cu")
		(net "MEMCSN")
	)
	(segment
		(start 20.2946 -138.963146)
		(end 20.2946 -138.754104)
		(width 0.127)
		(layer "F.Cu")
		(net "MEMCSN")
	)
	(segment
		(start 20.2946 -138.754104)
		(end 20.301204 -138.7475)
		(width 0.127)
		(layer "F.Cu")
		(net "MEMCSN")
	)
	(segment
		(start 20.2946 -134.04723)
		(end 19.85137 -133.604)
		(width 0.127)
		(layer "F.Cu")
		(net "MEMCSN")
	)
	(segment
		(start 39.67353 -144.364964)
		(end 39.62908 -144.32026)
		(width 0.1016)
		(layer "F.Cu")
		(net "MEMCSN")
	)
	(segment
		(start 20.225004 -139.032742)
		(end 20.2946 -138.963146)
		(width 0.127)
		(layer "F.Cu")
		(net "MEMCSN")
	)
	(segment
		(start 33.51022 -143.47698)
		(end 31.247334 -143.47698)
		(width 0.127)
		(layer "F.Cu")
		(net "MEMCSN")
	)
	(segment
		(start 20.225004 -139.5603)
		(end 20.225004 -139.032742)
		(width 0.127)
		(layer "F.Cu")
		(net "MEMCSN")
	)
	(segment
		(start 34.125408 -144.104106)
		(end 34.125408 -144.092168)
		(width 0.127)
		(layer "F.Cu")
		(net "MEMCSN")
	)
	(segment
		(start 31.120334 -143.60398)
		(end 31.120334 -144.08404)
		(width 0.127)
		(layer "F.Cu")
		(net "MEMCSN")
	)
	(segment
		(start 36.971224 -144.52854)
		(end 34.549842 -144.52854)
		(width 0.127)
		(layer "F.Cu")
		(net "MEMCSN")
	)
	(segment
		(start 39.36873 -144.212564)
		(end 37.2872 -144.212564)
		(width 0.127)
		(layer "F.Cu")
		(net "MEMCSN")
	)
	(segment
		(start 31.247334 -143.47698)
		(end 31.120334 -143.60398)
		(width 0.127)
		(layer "F.Cu")
		(net "MEMCSN")
	)
	(segment
		(start 37.2872 -144.212564)
		(end 36.971224 -144.52854)
		(width 0.127)
		(layer "F.Cu")
		(net "MEMCSN")
	)
	(segment
		(start 21.63445 -140.561568)
		(end 21.2344 -140.161518)
		(width 0.127)
		(layer "F.Cu")
		(net "MEMCSN")
	)
	(segment
		(start 19.85137 -133.604)
		(end 19.85137 -131.261358)
		(width 0.127)
		(layer "F.Cu")
		(net "MEMCSN")
	)
	(segment
		(start 26.70302 -143.47698)
		(end 26.57602 -143.60398)
		(width 0.127)
		(layer "F.Cu")
		(net "MEMCSN")
	)
	(segment
		(start 20.301204 -138.7475)
		(end 20.301204 -138.400028)
		(width 0.127)
		(layer "F.Cu")
		(net "MEMCSN")
	)
	(segment
		(start 30.612334 -143.60398)
		(end 30.485334 -143.47698)
		(width 0.127)
		(layer "F.Cu")
		(net "MEMCSN")
	)
	(segment
		(start 19.85137 -131.261358)
		(end 19.15287 -130.562858)
		(width 0.127)
		(layer "F.Cu")
		(net "MEMCSN")
	)
	(segment
		(start 29.79674 -144.20596)
		(end 29.8196 -144.1831)
		(width 0.127)
		(layer "F.Cu")
		(net "MEMCSN")
	)
	(segment
		(start 21.2344 -140.161518)
		(end 21.234146 -140.161264)
		(width 0.127)
		(layer "F.Cu")
		(net "MEMCSN")
	)
	(segment
		(start 34.549842 -144.52854)
		(end 34.125408 -144.104106)
		(width 0.127)
		(layer "F.Cu")
		(net "MEMCSN")
	)
	(segment
		(start 26.57602 -143.60398)
		(end 26.57602 -144.07896)
		(width 0.127)
		(layer "F.Cu")
		(net "MEMCSN")
	)
	(via
		(at 21.2344 -140.161518)
		(size 0.508)
		(drill 0.254)
		(layers "F.Cu" "B.Cu")
		(net "MEMCSN")
	)
	(via
		(at 29.8196 -144.1831)
		(size 0.508)
		(drill 0.254)
		(layers "F.Cu" "B.Cu")
		(net "MEMCSN")
	)
	(arc
		(start 40.061134 -144.599914)
		(mid 39.920094 -144.571859)
		(end 39.80053 -144.491964)
		(width 0.1016)
		(layer "F.Cu")
		(net "MEMCSN")
	)
	(arc
		(start 39.62908 -144.32026)
		(mid 39.509602 -144.240554)
		(end 39.36873 -144.212564)
		(width 0.1016)
		(layer "F.Cu")
		(net "MEMCSN")
	)
	(segment
		(start 29.8196 -144.1831)
		(end 28.983178 -143.346678)
		(width 0.127)
		(layer "In2.Cu")
		(net "MEMCSN")
	)
	(segment
		(start 28.983178 -143.346678)
		(end 27.546046 -143.346678)
		(width 0.127)
		(layer "In2.Cu")
		(net "MEMCSN")
	)
	(segment
		(start 25.383744 -141.184376)
		(end 24.426164 -141.184376)
		(width 0.127)
		(layer "In2.Cu")
		(net "MEMCSN")
	)
	(segment
		(start 23.288498 -140.656818)
		(end 23.19274 -140.56106)
		(width 0.0889)
		(layer "In2.Cu")
		(net "MEMCSN")
	)
	(segment
		(start 24.426164 -141.184376)
		(end 24.34082 -141.099032)
		(width 0.127)
		(layer "In2.Cu")
		(net "MEMCSN")
	)
	(segment
		(start 24.34082 -141.099032)
		(end 23.730712 -141.099032)
		(width 0.127)
		(layer "In2.Cu")
		(net "MEMCSN")
	)
	(segment
		(start 27.546046 -143.346678)
		(end 25.383744 -141.184376)
		(width 0.127)
		(layer "In2.Cu")
		(net "MEMCSN")
	)
	(segment
		(start 23.730712 -141.099032)
		(end 23.288498 -140.656818)
		(width 0.127)
		(layer "In2.Cu")
		(net "MEMCSN")
	)
	(segment
		(start 23.19274 -140.56106)
		(end 21.633942 -140.56106)
		(width 0.0889)
		(layer "In2.Cu")
		(net "MEMCSN")
	)
	(segment
		(start 21.633942 -140.56106)
		(end 21.2344 -140.161518)
		(width 0.0889)
		(layer "In2.Cu")
		(net "MEMCSN")
	)
	(segment
		(start 32.38246 -145.044414)
		(end 32.38246 -144.957546)
		(width 0.12446)
		(layer "F.Cu")
		(net "MEMCK_P")
	)
	(segment
		(start 21.634958 -141.361668)
		(end 22.0345 -141.76121)
		(width 0.12446)
		(layer "F.Cu")
		(net "MEMCK_P")
	)
	(segment
		(start 37.053774 -145.590006)
		(end 37.013134 -145.630646)
		(width 0.12446)
		(layer "F.Cu")
		(net "MEMCK_P")
	)
	(segment
		(start 36.115244 -146.002502)
		(end 34.69005 -146.002502)
		(width 0.12446)
		(layer "F.Cu")
		(net "MEMCK_P")
	)
	(segment
		(start 29.651452 -145.19148)
		(end 32.244538 -145.19148)
		(width 0.12446)
		(layer "F.Cu")
		(net "MEMCK_P")
	)
	(segment
		(start 32.332676 -145.15465)
		(end 32.339026 -145.1483)
		(width 0.12446)
		(layer "F.Cu")
		(net "MEMCK_P")
	)
	(segment
		(start 21.63445 -141.361668)
		(end 21.634958 -141.361668)
		(width 0.12446)
		(layer "F.Cu")
		(net "MEMCK_P")
	)
	(segment
		(start 33.79216 -146.374358)
		(end 33.568132 -146.598386)
		(width 0.12446)
		(layer "F.Cu")
		(net "MEMCK_P")
	)
	(segment
		(start 38.9636 -145.21815)
		(end 37.951664 -145.21815)
		(width 0.12446)
		(layer "F.Cu")
		(net "MEMCK_P")
	)
	(segment
		(start 32.339026 -145.1483)
		(end 32.33928 -145.1483)
		(width 0.12446)
		(layer "F.Cu")
		(net "MEMCK_P")
	)
	(segment
		(start 32.670242 -146.970242)
		(end 29.651198 -146.970242)
		(width 0.12446)
		(layer "F.Cu")
		(net "MEMCK_P")
	)
	(via
		(at 22.0345 -141.76121)
		(size 0.508)
		(drill 0.254)
		(layers "F.Cu" "B.Cu")
		(net "MEMCK_P")
	)
	(via
		(at 32.092138 -144.667224)
		(size 0.508)
		(drill 0.254)
		(layers "F.Cu" "B.Cu")
		(net "MEMCK_P")
	)
	(arc
		(start 32.38246 -144.957546)
		(mid 32.297427 -144.752257)
		(end 32.092138 -144.667224)
		(width 0.12446)
		(layer "F.Cu")
		(net "MEMCK_P")
	)
	(arc
		(start 32.33928 -145.1483)
		(mid 32.371264 -145.100666)
		(end 32.38246 -145.044414)
		(width 0.12446)
		(layer "F.Cu")
		(net "MEMCK_P")
	)
	(arc
		(start 29.651198 -146.970242)
		(mid 29.0224 -146.709786)
		(end 28.761944 -146.080988)
		(width 0.12446)
		(layer "F.Cu")
		(net "MEMCK_P")
	)
	(arc
		(start 34.69005 -146.002502)
		(mid 34.204125 -146.099141)
		(end 33.79216 -146.374358)
		(width 0.12446)
		(layer "F.Cu")
		(net "MEMCK_P")
	)
	(arc
		(start 39.299896 -145.400014)
		(mid 39.154765 -145.266516)
		(end 38.9636 -145.21815)
		(width 0.12446)
		(layer "F.Cu")
		(net "MEMCK_P")
	)
	(arc
		(start 37.951664 -145.21815)
		(mid 37.465739 -145.314789)
		(end 37.053774 -145.590006)
		(width 0.12446)
		(layer "F.Cu")
		(net "MEMCK_P")
	)
	(arc
		(start 32.244538 -145.19148)
		(mid 32.292279 -145.181854)
		(end 32.332676 -145.15465)
		(width 0.12446)
		(layer "F.Cu")
		(net "MEMCK_P")
	)
	(arc
		(start 33.568132 -146.598386)
		(mid 33.156162 -146.873592)
		(end 32.670242 -146.970242)
		(width 0.12446)
		(layer "F.Cu")
		(net "MEMCK_P")
	)
	(arc
		(start 37.013134 -145.630646)
		(mid 36.601164 -145.905852)
		(end 36.115244 -146.002502)
		(width 0.12446)
		(layer "F.Cu")
		(net "MEMCK_P")
	)
	(arc
		(start 28.761944 -146.080988)
		(mid 29.022475 -145.452011)
		(end 29.651452 -145.19148)
		(width 0.12446)
		(layer "F.Cu")
		(net "MEMCK_P")
	)
	(segment
		(start 21.79701 -141.52372)
		(end 22.0345 -141.76121)
		(width 0.12446)
		(layer "B.Cu")
		(net "MEMCK_P")
	)
	(segment
		(start 21.130768 -141.52372)
		(end 21.79701 -141.52372)
		(width 0.12446)
		(layer "B.Cu")
		(net "MEMCK_P")
	)
	(segment
		(start 20.821396 -141.833092)
		(end 21.130768 -141.52372)
		(width 0.12446)
		(layer "B.Cu")
		(net "MEMCK_P")
	)
	(segment
		(start 28.605226 -144.52727)
		(end 27.669236 -144.52727)
		(width 0.1016)
		(layer "In2.Cu")
		(net "MEMCK_P")
	)
	(segment
		(start 22.28215 -141.51356)
		(end 22.0345 -141.76121)
		(width 0.1016)
		(layer "In2.Cu")
		(net "MEMCK_P")
	)
	(segment
		(start 32.325818 -144.071594)
		(end 31.583376 -144.071594)
		(width 0.1016)
		(layer "In2.Cu")
		(net "MEMCK_P")
	)
	(segment
		(start 29.160978 -144.999202)
		(end 28.748736 -144.58696)
		(width 0.1016)
		(layer "In2.Cu")
		(net "MEMCK_P")
	)
	(segment
		(start 22.480778 -141.51356)
		(end 22.28215 -141.51356)
		(width 0.1016)
		(layer "In2.Cu")
		(net "MEMCK_P")
	)
	(segment
		(start 23.255224 -141.633448)
		(end 23.255224 -141.497558)
		(width 0.1016)
		(layer "In2.Cu")
		(net "MEMCK_P")
	)
	(segment
		(start 24.959818 -142.238476)
		(end 23.887176 -142.238476)
		(width 0.1016)
		(layer "In2.Cu")
		(net "MEMCK_P")
	)
	(segment
		(start 31.242 -144.41297)
		(end 31.242 -144.532858)
		(width 0.1016)
		(layer "In2.Cu")
		(net "MEMCK_P")
	)
	(segment
		(start 30.551882 -145.2372)
		(end 29.73578 -145.2372)
		(width 0.1016)
		(layer "In2.Cu")
		(net "MEMCK_P")
	)
	(segment
		(start 22.696678 -141.29766)
		(end 22.480778 -141.51356)
		(width 0.1016)
		(layer "In2.Cu")
		(net "MEMCK_P")
	)
	(segment
		(start 27.094434 -144.289272)
		(end 25.103328 -142.298166)
		(width 0.1016)
		(layer "In2.Cu")
		(net "MEMCK_P")
	)
	(segment
		(start 32.455358 -144.304004)
		(end 32.455358 -144.201134)
		(width 0.1016)
		(layer "In2.Cu")
		(net "MEMCK_P")
	)
	(segment
		(start 23.055326 -141.29766)
		(end 22.696678 -141.29766)
		(width 0.1016)
		(layer "In2.Cu")
		(net "MEMCK_P")
	)
	(arc
		(start 29.73578 -145.2372)
		(mid 29.424695 -145.175397)
		(end 29.160978 -144.999202)
		(width 0.1016)
		(layer "In2.Cu")
		(net "MEMCK_P")
	)
	(arc
		(start 31.242 -144.532858)
		(mid 31.040722 -145.025937)
		(end 30.551882 -145.2372)
		(width 0.1016)
		(layer "In2.Cu")
		(net "MEMCK_P")
	)
	(arc
		(start 23.19655 -141.356334)
		(mid 23.131771 -141.312957)
		(end 23.055326 -141.29766)
		(width 0.1016)
		(layer "In2.Cu")
		(net "MEMCK_P")
	)
	(arc
		(start 23.887176 -142.238476)
		(mid 23.625174 -142.185083)
		(end 23.405084 -142.033244)
		(width 0.1016)
		(layer "In2.Cu")
		(net "MEMCK_P")
	)
	(arc
		(start 25.103328 -142.298166)
		(mid 25.037514 -142.254034)
		(end 24.959818 -142.238476)
		(width 0.1016)
		(layer "In2.Cu")
		(net "MEMCK_P")
	)
	(arc
		(start 28.748736 -144.58696)
		(mid 28.682922 -144.542828)
		(end 28.605226 -144.52727)
		(width 0.1016)
		(layer "In2.Cu")
		(net "MEMCK_P")
	)
	(arc
		(start 23.255224 -141.497558)
		(mid 23.239925 -141.421114)
		(end 23.19655 -141.356334)
		(width 0.1016)
		(layer "In2.Cu")
		(net "MEMCK_P")
	)
	(arc
		(start 32.092138 -144.667224)
		(mid 32.348973 -144.560839)
		(end 32.455358 -144.304004)
		(width 0.1016)
		(layer "In2.Cu")
		(net "MEMCK_P")
	)
	(arc
		(start 32.455358 -144.201134)
		(mid 32.417417 -144.109535)
		(end 32.325818 -144.071594)
		(width 0.1016)
		(layer "In2.Cu")
		(net "MEMCK_P")
	)
	(arc
		(start 27.669236 -144.52727)
		(mid 27.358151 -144.465467)
		(end 27.094434 -144.289272)
		(width 0.1016)
		(layer "In2.Cu")
		(net "MEMCK_P")
	)
	(arc
		(start 31.583376 -144.071594)
		(mid 31.341987 -144.171581)
		(end 31.242 -144.41297)
		(width 0.1016)
		(layer "In2.Cu")
		(net "MEMCK_P")
	)
	(arc
		(start 23.405084 -142.033244)
		(mid 23.293869 -141.846952)
		(end 23.255224 -141.633448)
		(width 0.1016)
		(layer "In2.Cu")
		(net "MEMCK_P")
	)
	(segment
		(start 33.504632 -146.08683)
		(end 33.280604 -146.310858)
		(width 0.12446)
		(layer "F.Cu")
		(net "MEMCK_N")
	)
	(segment
		(start 22.43455 -141.361668)
		(end 22.43455 -141.36116)
		(width 0.12446)
		(layer "F.Cu")
		(net "MEMCK_N")
	)
	(segment
		(start 36.766246 -145.302478)
		(end 36.725606 -145.343118)
		(width 0.12446)
		(layer "F.Cu")
		(net "MEMCK_N")
	)
	(segment
		(start 29.651452 -145.59788)
		(end 32.244538 -145.59788)
		(width 0.12446)
		(layer "F.Cu")
		(net "MEMCK_N")
	)
	(segment
		(start 32.670242 -146.563842)
		(end 29.651198 -146.563842)
		(width 0.12446)
		(layer "F.Cu")
		(net "MEMCK_N")
	)
	(segment
		(start 32.620712 -145.44167)
		(end 32.626554 -145.435828)
		(width 0.12446)
		(layer "F.Cu")
		(net "MEMCK_N")
	)
	(segment
		(start 32.78886 -145.044668)
		(end 32.78886 -145.026126)
		(width 0.12446)
		(layer "F.Cu")
		(net "MEMCK_N")
	)
	(segment
		(start 36.115244 -145.596102)
		(end 34.69005 -145.596102)
		(width 0.12446)
		(layer "F.Cu")
		(net "MEMCK_N")
	)
	(segment
		(start 22.43455 -141.36116)
		(end 22.0345 -140.96111)
		(width 0.12446)
		(layer "F.Cu")
		(net "MEMCK_N")
	)
	(segment
		(start 38.9636 -144.81175)
		(end 37.951664 -144.81175)
		(width 0.12446)
		(layer "F.Cu")
		(net "MEMCK_N")
	)
	(via
		(at 33.174178 -144.687544)
		(size 0.508)
		(drill 0.254)
		(layers "F.Cu" "B.Cu")
		(net "MEMCK_N")
	)
	(via
		(at 22.0345 -140.96111)
		(size 0.508)
		(drill 0.254)
		(layers "F.Cu" "B.Cu")
		(net "MEMCK_N")
	)
	(arc
		(start 37.951664 -144.81175)
		(mid 37.310163 -144.939241)
		(end 36.766246 -145.302478)
		(width 0.12446)
		(layer "F.Cu")
		(net "MEMCK_N")
	)
	(arc
		(start 36.725606 -145.343118)
		(mid 36.445585 -145.530315)
		(end 36.115244 -145.596102)
		(width 0.12446)
		(layer "F.Cu")
		(net "MEMCK_N")
	)
	(arc
		(start 29.168344 -146.080988)
		(mid 29.309843 -145.739379)
		(end 29.651452 -145.59788)
		(width 0.12446)
		(layer "F.Cu")
		(net "MEMCK_N")
	)
	(arc
		(start 39.299896 -144.599914)
		(mid 39.162325 -144.754371)
		(end 38.9636 -144.81175)
		(width 0.12446)
		(layer "F.Cu")
		(net "MEMCK_N")
	)
	(arc
		(start 33.280604 -146.310858)
		(mid 33.000583 -146.498055)
		(end 32.670242 -146.563842)
		(width 0.12446)
		(layer "F.Cu")
		(net "MEMCK_N")
	)
	(arc
		(start 32.244538 -145.59788)
		(mid 32.448201 -145.557279)
		(end 32.620712 -145.44167)
		(width 0.12446)
		(layer "F.Cu")
		(net "MEMCK_N")
	)
	(arc
		(start 29.651198 -146.563842)
		(mid 29.309769 -146.422417)
		(end 29.168344 -146.080988)
		(width 0.12446)
		(layer "F.Cu")
		(net "MEMCK_N")
	)
	(arc
		(start 32.78886 -145.026126)
		(mid 32.904915 -144.769673)
		(end 33.174178 -144.687544)
		(width 0.12446)
		(layer "F.Cu")
		(net "MEMCK_N")
	)
	(arc
		(start 32.626554 -145.435828)
		(mid 32.746606 -145.256392)
		(end 32.78886 -145.044668)
		(width 0.12446)
		(layer "F.Cu")
		(net "MEMCK_N")
	)
	(arc
		(start 34.69005 -145.596102)
		(mid 34.048549 -145.723593)
		(end 33.504632 -146.08683)
		(width 0.12446)
		(layer "F.Cu")
		(net "MEMCK_N")
	)
	(segment
		(start 21.130768 -141.11732)
		(end 21.87829 -141.11732)
		(width 0.12446)
		(layer "B.Cu")
		(net "MEMCK_N")
	)
	(segment
		(start 21.87829 -141.11732)
		(end 22.0345 -140.96111)
		(width 0.12446)
		(layer "B.Cu")
		(net "MEMCK_N")
	)
	(segment
		(start 20.82165 -140.808202)
		(end 21.130768 -141.11732)
		(width 0.12446)
		(layer "B.Cu")
		(net "MEMCK_N")
	)
	(segment
		(start 27.31008 -144.073626)
		(end 25.318974 -142.08252)
		(width 0.1016)
		(layer "In2.Cu")
		(net "MEMCK_N")
	)
	(segment
		(start 28.605226 -144.22247)
		(end 27.669236 -144.22247)
		(width 0.1016)
		(layer "In2.Cu")
		(net "MEMCK_N")
	)
	(segment
		(start 32.760158 -144.273524)
		(end 32.760158 -144.201134)
		(width 0.1016)
		(layer "In2.Cu")
		(net "MEMCK_N")
	)
	(segment
		(start 22.28215 -141.20876)
		(end 22.0345 -140.96111)
		(width 0.1016)
		(layer "In2.Cu")
		(net "MEMCK_N")
	)
	(segment
		(start 30.545786 -144.9324)
		(end 29.73578 -144.9324)
		(width 0.1016)
		(layer "In2.Cu")
		(net "MEMCK_N")
	)
	(segment
		(start 24.959818 -141.933676)
		(end 23.887176 -141.933676)
		(width 0.1016)
		(layer "In2.Cu")
		(net "MEMCK_N")
	)
	(segment
		(start 22.570186 -140.99286)
		(end 22.354286 -141.20876)
		(width 0.1016)
		(layer "In2.Cu")
		(net "MEMCK_N")
	)
	(segment
		(start 23.05558 -140.99286)
		(end 22.570186 -140.99286)
		(width 0.1016)
		(layer "In2.Cu")
		(net "MEMCK_N")
	)
	(segment
		(start 22.354286 -141.20876)
		(end 22.28215 -141.20876)
		(width 0.1016)
		(layer "In2.Cu")
		(net "MEMCK_N")
	)
	(segment
		(start 32.325818 -143.766794)
		(end 31.583376 -143.766794)
		(width 0.1016)
		(layer "In2.Cu")
		(net "MEMCK_N")
	)
	(segment
		(start 29.376624 -144.783556)
		(end 28.964382 -144.371314)
		(width 0.1016)
		(layer "In2.Cu")
		(net "MEMCK_N")
	)
	(segment
		(start 23.560024 -141.633448)
		(end 23.560024 -141.497558)
		(width 0.1016)
		(layer "In2.Cu")
		(net "MEMCK_N")
	)
	(segment
		(start 30.9372 -144.41297)
		(end 30.9372 -144.532858)
		(width 0.1016)
		(layer "In2.Cu")
		(net "MEMCK_N")
	)
	(arc
		(start 27.669236 -144.22247)
		(mid 27.474847 -144.183786)
		(end 27.31008 -144.073626)
		(width 0.1016)
		(layer "In2.Cu")
		(net "MEMCK_N")
	)
	(arc
		(start 23.887176 -141.933676)
		(mid 23.748081 -141.906008)
		(end 23.630128 -141.82725)
		(width 0.1016)
		(layer "In2.Cu")
		(net "MEMCK_N")
	)
	(arc
		(start 32.760158 -144.201134)
		(mid 32.632943 -143.894009)
		(end 32.325818 -143.766794)
		(width 0.1016)
		(layer "In2.Cu")
		(net "MEMCK_N")
	)
	(arc
		(start 33.174178 -144.687544)
		(mid 32.881422 -144.56628)
		(end 32.760158 -144.273524)
		(width 0.1016)
		(layer "In2.Cu")
		(net "MEMCK_N")
	)
	(arc
		(start 30.9372 -144.532858)
		(mid 30.823035 -144.812489)
		(end 30.545786 -144.9324)
		(width 0.1016)
		(layer "In2.Cu")
		(net "MEMCK_N")
	)
	(arc
		(start 31.583376 -143.766794)
		(mid 31.126461 -143.956055)
		(end 30.9372 -144.41297)
		(width 0.1016)
		(layer "In2.Cu")
		(net "MEMCK_N")
	)
	(arc
		(start 23.560024 -141.497558)
		(mid 23.521606 -141.304418)
		(end 23.412196 -141.140688)
		(width 0.1016)
		(layer "In2.Cu")
		(net "MEMCK_N")
	)
	(arc
		(start 28.964382 -144.371314)
		(mid 28.799614 -144.261156)
		(end 28.605226 -144.22247)
		(width 0.1016)
		(layer "In2.Cu")
		(net "MEMCK_N")
	)
	(arc
		(start 23.412196 -141.140688)
		(mid 23.24858 -141.031333)
		(end 23.05558 -140.99286)
		(width 0.1016)
		(layer "In2.Cu")
		(net "MEMCK_N")
	)
	(arc
		(start 23.630128 -141.82725)
		(mid 23.578051 -141.736508)
		(end 23.560024 -141.633448)
		(width 0.1016)
		(layer "In2.Cu")
		(net "MEMCK_N")
	)
	(arc
		(start 29.73578 -144.9324)
		(mid 29.541391 -144.893716)
		(end 29.376624 -144.783556)
		(width 0.1016)
		(layer "In2.Cu")
		(net "MEMCK_N")
	)
	(arc
		(start 25.318974 -142.08252)
		(mid 25.154206 -141.972362)
		(end 24.959818 -141.933676)
		(width 0.1016)
		(layer "In2.Cu")
		(net "MEMCK_N")
	)
	(segment
		(start 40.899842 -145.39976)
		(end 40.899842 -145.400014)
		(width 0.127)
		(layer "F.Cu")
		(net "MEMCKE")
	)
	(segment
		(start 40.500046 -144.999964)
		(end 40.899842 -145.39976)
		(width 0.127)
		(layer "F.Cu")
		(net "MEMCKE")
	)
	(segment
		(start 17.634458 -141.361668)
		(end 18.034508 -141.761718)
		(width 0.127)
		(layer "F.Cu")
		(net "MEMCKE")
	)
	(via
		(at 40.500046 -144.999964)
		(size 0.4572)
		(drill 0.2032)
		(layers "F.Cu" "B.Cu")
		(net "MEMCKE")
	)
	(via
		(at 18.034508 -141.761718)
		(size 0.508)
		(drill 0.254)
		(layers "F.Cu" "B.Cu")
		(net "MEMCKE")
	)
	(segment
		(start 16.599916 -144.561814)
		(end 16.834612 -144.327118)
		(width 0.0889)
		(layer "B.Cu")
		(net "MEMCKE")
	)
	(segment
		(start 15.06347 -143.947134)
		(end 15.19047 -144.074134)
		(width 0.127)
		(layer "B.Cu")
		(net "MEMCKE")
	)
	(segment
		(start 15.31747 -145.168366)
		(end 15.581122 -145.168366)
		(width 0.127)
		(layer "B.Cu")
		(net "MEMCKE")
	)
	(segment
		(start 13.768324 -145.23593)
		(end 13.768324 -146.051524)
		(width 0.127)
		(layer "B.Cu")
		(net "MEMCKE")
	)
	(segment
		(start 17.634458 -141.361668)
		(end 18.034508 -141.761718)
		(width 0.0889)
		(layer "B.Cu")
		(net "MEMCKE")
	)
	(segment
		(start 16.834612 -141.508988)
		(end 16.981932 -141.361668)
		(width 0.0889)
		(layer "B.Cu")
		(net "MEMCKE")
	)
	(segment
		(start 16.834612 -144.327118)
		(end 16.834612 -141.508988)
		(width 0.0889)
		(layer "B.Cu")
		(net "MEMCKE")
	)
	(segment
		(start 16.0147 -144.734788)
		(end 16.187674 -144.561814)
		(width 0.0889)
		(layer "B.Cu")
		(net "MEMCKE")
	)
	(segment
		(start 16.981932 -141.361668)
		(end 17.634458 -141.361668)
		(width 0.0889)
		(layer "B.Cu")
		(net "MEMCKE")
	)
	(segment
		(start 14.80947 -143.947134)
		(end 15.06347 -143.947134)
		(width 0.127)
		(layer "B.Cu")
		(net "MEMCKE")
	)
	(segment
		(start 14.55547 -145.168366)
		(end 14.68247 -145.041366)
		(width 0.127)
		(layer "B.Cu")
		(net "MEMCKE")
	)
	(segment
		(start 13.835888 -145.168366)
		(end 14.55547 -145.168366)
		(width 0.127)
		(layer "B.Cu")
		(net "MEMCKE")
	)
	(segment
		(start 15.19047 -144.074134)
		(end 15.19047 -145.041366)
		(width 0.127)
		(layer "B.Cu")
		(net "MEMCKE")
	)
	(segment
		(start 16.187674 -144.561814)
		(end 16.599916 -144.561814)
		(width 0.0889)
		(layer "B.Cu")
		(net "MEMCKE")
	)
	(segment
		(start 14.68247 -145.041366)
		(end 14.68247 -144.074134)
		(width 0.127)
		(layer "B.Cu")
		(net "MEMCKE")
	)
	(segment
		(start 15.581122 -145.168366)
		(end 16.0147 -144.734788)
		(width 0.127)
		(layer "B.Cu")
		(net "MEMCKE")
	)
	(segment
		(start 14.68247 -144.074134)
		(end 14.80947 -143.947134)
		(width 0.127)
		(layer "B.Cu")
		(net "MEMCKE")
	)
	(segment
		(start 15.19047 -145.041366)
		(end 15.31747 -145.168366)
		(width 0.127)
		(layer "B.Cu")
		(net "MEMCKE")
	)
	(segment
		(start 13.768324 -145.23593)
		(end 13.835888 -145.168366)
		(width 0.127)
		(layer "B.Cu")
		(net "MEMCKE")
	)
	(segment
		(start 13.768324 -146.051524)
		(end 13.9827 -146.2659)
		(width 0.127)
		(layer "B.Cu")
		(net "MEMCKE")
	)
	(segment
		(start 34.216086 -144.028668)
		(end 34.216086 -144.58696)
		(width 0.127)
		(layer "In5.Cu")
		(net "MEMCKE")
	)
	(segment
		(start 34.216086 -144.58696)
		(end 34.089086 -144.71396)
		(width 0.127)
		(layer "In5.Cu")
		(net "MEMCKE")
	)
	(segment
		(start 33.708086 -144.028668)
		(end 33.581086 -143.901668)
		(width 0.127)
		(layer "In5.Cu")
		(net "MEMCKE")
	)
	(segment
		(start 18.109946 -141.68628)
		(end 18.034508 -141.761718)
		(width 0.0889)
		(layer "In5.Cu")
		(net "MEMCKE")
	)
	(segment
		(start 32.649668 -144.118076)
		(end 31.66745 -144.118076)
		(width 0.127)
		(layer "In5.Cu")
		(net "MEMCKE")
	)
	(segment
		(start 37.73678 -143.901668)
		(end 34.343086 -143.901668)
		(width 0.127)
		(layer "In5.Cu")
		(net "MEMCKE")
	)
	(segment
		(start 21.213572 -141.56182)
		(end 21.124672 -141.65072)
		(width 0.0889)
		(layer "In5.Cu")
		(net "MEMCKE")
	)
	(segment
		(start 23.885652 -141.959076)
		(end 23.683468 -142.16126)
		(width 0.127)
		(layer "In5.Cu")
		(net "MEMCKE")
	)
	(segment
		(start 31.03245 -145.034)
		(end 31.03245 -144.245076)
		(width 0.127)
		(layer "In5.Cu")
		(net "MEMCKE")
	)
	(segment
		(start 31.54045 -145.034)
		(end 31.41345 -145.161)
		(width 0.127)
		(layer "In5.Cu")
		(net "MEMCKE")
	)
	(segment
		(start 31.41345 -145.161)
		(end 31.15945 -145.161)
		(width 0.127)
		(layer "In5.Cu")
		(net "MEMCKE")
	)
	(segment
		(start 30.36824 -144.653)
		(end 30.24124 -144.78)
		(width 0.127)
		(layer "In5.Cu")
		(net "MEMCKE")
	)
	(segment
		(start 18.59534 -141.68628)
		(end 18.109946 -141.68628)
		(width 0.0889)
		(layer "In5.Cu")
		(net "MEMCKE")
	)
	(segment
		(start 28.097734 -144.157446)
		(end 25.899364 -141.959076)
		(width 0.127)
		(layer "In5.Cu")
		(net "MEMCKE")
	)
	(segment
		(start 33.581086 -143.901668)
		(end 32.866076 -143.901668)
		(width 0.127)
		(layer "In5.Cu")
		(net "MEMCKE")
	)
	(segment
		(start 34.089086 -144.71396)
		(end 33.835086 -144.71396)
		(width 0.127)
		(layer "In5.Cu")
		(net "MEMCKE")
	)
	(segment
		(start 29.2989 -144.78)
		(end 28.676346 -144.157446)
		(width 0.127)
		(layer "In5.Cu")
		(net "MEMCKE")
	)
	(segment
		(start 21.569172 -142.16126)
		(end 21.480272 -142.07236)
		(width 0.0889)
		(layer "In5.Cu")
		(net "MEMCKE")
	)
	(segment
		(start 40.500046 -144.999964)
		(end 40.106346 -145.393664)
		(width 0.127)
		(layer "In5.Cu")
		(net "MEMCKE")
	)
	(segment
		(start 25.899364 -141.959076)
		(end 23.885652 -141.959076)
		(width 0.127)
		(layer "In5.Cu")
		(net "MEMCKE")
	)
	(segment
		(start 21.035772 -142.16126)
		(end 19.07032 -142.16126)
		(width 0.0889)
		(layer "In5.Cu")
		(net "MEMCKE")
	)
	(segment
		(start 23.683468 -142.16126)
		(end 21.569172 -142.16126)
		(width 0.0889)
		(layer "In5.Cu")
		(net "MEMCKE")
	)
	(segment
		(start 32.866076 -143.901668)
		(end 32.649668 -144.118076)
		(width 0.127)
		(layer "In5.Cu")
		(net "MEMCKE")
	)
	(segment
		(start 31.54045 -144.245076)
		(end 31.54045 -145.034)
		(width 0.127)
		(layer "In5.Cu")
		(net "MEMCKE")
	)
	(segment
		(start 19.07032 -142.16126)
		(end 18.59534 -141.68628)
		(width 0.0889)
		(layer "In5.Cu")
		(net "MEMCKE")
	)
	(segment
		(start 31.66745 -144.118076)
		(end 31.54045 -144.245076)
		(width 0.127)
		(layer "In5.Cu")
		(net "MEMCKE")
	)
	(segment
		(start 28.676346 -144.157446)
		(end 28.097734 -144.157446)
		(width 0.127)
		(layer "In5.Cu")
		(net "MEMCKE")
	)
	(segment
		(start 30.24124 -144.78)
		(end 29.2989 -144.78)
		(width 0.127)
		(layer "In5.Cu")
		(net "MEMCKE")
	)
	(segment
		(start 30.90545 -144.118076)
		(end 30.501844 -144.118076)
		(width 0.127)
		(layer "In5.Cu")
		(net "MEMCKE")
	)
	(segment
		(start 21.480272 -141.65072)
		(end 21.391372 -141.56182)
		(width 0.0889)
		(layer "In5.Cu")
		(net "MEMCKE")
	)
	(segment
		(start 21.391372 -141.56182)
		(end 21.213572 -141.56182)
		(width 0.0889)
		(layer "In5.Cu")
		(net "MEMCKE")
	)
	(segment
		(start 21.124672 -141.65072)
		(end 21.124672 -142.07236)
		(width 0.0889)
		(layer "In5.Cu")
		(net "MEMCKE")
	)
	(segment
		(start 33.835086 -144.71396)
		(end 33.708086 -144.58696)
		(width 0.127)
		(layer "In5.Cu")
		(net "MEMCKE")
	)
	(segment
		(start 40.106346 -145.393664)
		(end 39.228776 -145.393664)
		(width 0.127)
		(layer "In5.Cu")
		(net "MEMCKE")
	)
	(segment
		(start 39.228776 -145.393664)
		(end 37.73678 -143.901668)
		(width 0.127)
		(layer "In5.Cu")
		(net "MEMCKE")
	)
	(segment
		(start 21.480272 -142.07236)
		(end 21.480272 -141.65072)
		(width 0.0889)
		(layer "In5.Cu")
		(net "MEMCKE")
	)
	(segment
		(start 30.501844 -144.118076)
		(end 30.36824 -144.25168)
		(width 0.127)
		(layer "In5.Cu")
		(net "MEMCKE")
	)
	(segment
		(start 31.03245 -144.245076)
		(end 30.90545 -144.118076)
		(width 0.127)
		(layer "In5.Cu")
		(net "MEMCKE")
	)
	(segment
		(start 33.708086 -144.58696)
		(end 33.708086 -144.028668)
		(width 0.127)
		(layer "In5.Cu")
		(net "MEMCKE")
	)
	(segment
		(start 31.15945 -145.161)
		(end 31.03245 -145.034)
		(width 0.127)
		(layer "In5.Cu")
		(net "MEMCKE")
	)
	(segment
		(start 21.124672 -142.07236)
		(end 21.035772 -142.16126)
		(width 0.0889)
		(layer "In5.Cu")
		(net "MEMCKE")
	)
	(segment
		(start 30.36824 -144.25168)
		(end 30.36824 -144.653)
		(width 0.127)
		(layer "In5.Cu")
		(net "MEMCKE")
	)
	(segment
		(start 34.343086 -143.901668)
		(end 34.216086 -144.028668)
		(width 0.127)
		(layer "In5.Cu")
		(net "MEMCKE")
	)
	(segment
		(start 25.416002 -142.95882)
		(end 25.543002 -143.08582)
		(width 0.127)
		(layer "F.Cu")
		(net "MEMCASN")
	)
	(segment
		(start 33.710626 -142.95882)
		(end 34.772346 -144.02054)
		(width 0.127)
		(layer "F.Cu")
		(net "MEMCASN")
	)
	(segment
		(start 24.527002 -143.88084)
		(end 24.654002 -144.00784)
		(width 0.127)
		(layer "F.Cu")
		(net "MEMCASN")
	)
	(segment
		(start 24.68626 -141.56182)
		(end 24.68626 -141.81582)
		(width 0.127)
		(layer "F.Cu")
		(net "MEMCASN")
	)
	(segment
		(start 20.582128 -129.527808)
		(end 20.591272 -129.518664)
		(width 0.127)
		(layer "F.Cu")
		(net "MEMCASN")
	)
	(segment
		(start 37.0586 -143.907764)
		(end 39.1922 -143.907764)
		(width 0.127)
		(layer "F.Cu")
		(net "MEMCASN")
	)
	(segment
		(start 26.72588 -142.06982)
		(end 26.72588 -142.32382)
		(width 0.127)
		(layer "F.Cu")
		(net "MEMCASN")
	)
	(segment
		(start 26.02484 -141.30782)
		(end 25.89784 -141.43482)
		(width 0.127)
		(layer "F.Cu")
		(net "MEMCASN")
	)
	(segment
		(start 26.72588 -142.32382)
		(end 26.59888 -142.45082)
		(width 0.127)
		(layer "F.Cu")
		(net "MEMCASN")
	)
	(segment
		(start 25.924002 -144.00784)
		(end 26.051002 -143.88084)
		(width 0.127)
		(layer "F.Cu")
		(net "MEMCASN")
	)
	(segment
		(start 25.543002 -143.88084)
		(end 25.670002 -144.00784)
		(width 0.127)
		(layer "F.Cu")
		(net "MEMCASN")
	)
	(segment
		(start 36.945824 -144.02054)
		(end 37.0586 -143.907764)
		(width 0.127)
		(layer "F.Cu")
		(net "MEMCASN")
	)
	(segment
		(start 20.582128 -130.562858)
		(end 21.2852 -131.26593)
		(width 0.127)
		(layer "F.Cu")
		(net "MEMCASN")
	)
	(segment
		(start 24.083264 -140.358368)
		(end 25.89784 -140.358368)
		(width 0.127)
		(layer "F.Cu")
		(net "MEMCASN")
	)
	(segment
		(start 26.59888 -141.94282)
		(end 26.72588 -142.06982)
		(width 0.127)
		(layer "F.Cu")
		(net "MEMCASN")
	)
	(segment
		(start 22.034246 -139.361164)
		(end 22.43455 -139.761468)
		(width 0.127)
		(layer "F.Cu")
		(net "MEMCASN")
	)
	(segment
		(start 24.638 -142.45082)
		(end 24.527002 -142.561818)
		(width 0.127)
		(layer "F.Cu")
		(net "MEMCASN")
	)
	(segment
		(start 24.68626 -141.81582)
		(end 24.81326 -141.94282)
		(width 0.127)
		(layer "F.Cu")
		(net "MEMCASN")
	)
	(segment
		(start 25.035002 -143.08582)
		(end 25.162002 -142.95882)
		(width 0.127)
		(layer "F.Cu")
		(net "MEMCASN")
	)
	(segment
		(start 24.908002 -144.00784)
		(end 25.035002 -143.88084)
		(width 0.127)
		(layer "F.Cu")
		(net "MEMCASN")
	)
	(segment
		(start 25.035002 -143.88084)
		(end 25.035002 -143.08582)
		(width 0.127)
		(layer "F.Cu")
		(net "MEMCASN")
	)
	(segment
		(start 20.5994 -138.7348)
		(end 21.225764 -139.361164)
		(width 0.127)
		(layer "F.Cu")
		(net "MEMCASN")
	)
	(segment
		(start 24.81326 -141.94282)
		(end 26.59888 -141.94282)
		(width 0.127)
		(layer "F.Cu")
		(net "MEMCASN")
	)
	(segment
		(start 23.87346 -140.148564)
		(end 24.083264 -140.358368)
		(width 0.127)
		(layer "F.Cu")
		(net "MEMCASN")
	)
	(segment
		(start 21.2852 -131.26593)
		(end 21.2852 -133.2738)
		(width 0.127)
		(layer "F.Cu")
		(net "MEMCASN")
	)
	(segment
		(start 20.582128 -130.562858)
		(end 20.582128 -129.527808)
		(width 0.127)
		(layer "F.Cu")
		(net "MEMCASN")
	)
	(segment
		(start 25.670002 -144.00784)
		(end 25.924002 -144.00784)
		(width 0.127)
		(layer "F.Cu")
		(net "MEMCASN")
	)
	(segment
		(start 21.2852 -133.2738)
		(end 20.5994 -133.9596)
		(width 0.127)
		(layer "F.Cu")
		(net "MEMCASN")
	)
	(segment
		(start 26.178002 -142.95882)
		(end 33.710626 -142.95882)
		(width 0.127)
		(layer "F.Cu")
		(net "MEMCASN")
	)
	(segment
		(start 25.162002 -142.95882)
		(end 25.416002 -142.95882)
		(width 0.127)
		(layer "F.Cu")
		(net "MEMCASN")
	)
	(segment
		(start 22.821646 -140.148564)
		(end 23.87346 -140.148564)
		(width 0.127)
		(layer "F.Cu")
		(net "MEMCASN")
	)
	(segment
		(start 39.1922 -143.907764)
		(end 39.299896 -143.800068)
		(width 0.127)
		(layer "F.Cu")
		(net "MEMCASN")
	)
	(segment
		(start 24.527002 -142.561818)
		(end 24.527002 -143.88084)
		(width 0.127)
		(layer "F.Cu")
		(net "MEMCASN")
	)
	(segment
		(start 26.051002 -143.08582)
		(end 26.178002 -142.95882)
		(width 0.127)
		(layer "F.Cu")
		(net "MEMCASN")
	)
	(segment
		(start 25.89784 -140.358368)
		(end 26.02484 -140.485368)
		(width 0.127)
		(layer "F.Cu")
		(net "MEMCASN")
	)
	(segment
		(start 26.02484 -140.485368)
		(end 26.02484 -141.30782)
		(width 0.127)
		(layer "F.Cu")
		(net "MEMCASN")
	)
	(segment
		(start 22.43455 -139.761468)
		(end 22.821646 -140.148564)
		(width 0.127)
		(layer "F.Cu")
		(net "MEMCASN")
	)
	(segment
		(start 26.051002 -143.88084)
		(end 26.051002 -143.08582)
		(width 0.127)
		(layer "F.Cu")
		(net "MEMCASN")
	)
	(segment
		(start 21.225764 -139.361164)
		(end 22.034246 -139.361164)
		(width 0.127)
		(layer "F.Cu")
		(net "MEMCASN")
	)
	(segment
		(start 25.543002 -143.08582)
		(end 25.543002 -143.88084)
		(width 0.127)
		(layer "F.Cu")
		(net "MEMCASN")
	)
	(segment
		(start 25.89784 -141.43482)
		(end 24.81326 -141.43482)
		(width 0.127)
		(layer "F.Cu")
		(net "MEMCASN")
	)
	(segment
		(start 34.772346 -144.02054)
		(end 36.945824 -144.02054)
		(width 0.127)
		(layer "F.Cu")
		(net "MEMCASN")
	)
	(segment
		(start 26.59888 -142.45082)
		(end 24.638 -142.45082)
		(width 0.127)
		(layer "F.Cu")
		(net "MEMCASN")
	)
	(segment
		(start 20.5994 -133.9596)
		(end 20.5994 -138.7348)
		(width 0.127)
		(layer "F.Cu")
		(net "MEMCASN")
	)
	(segment
		(start 24.654002 -144.00784)
		(end 24.908002 -144.00784)
		(width 0.127)
		(layer "F.Cu")
		(net "MEMCASN")
	)
	(segment
		(start 24.81326 -141.43482)
		(end 24.68626 -141.56182)
		(width 0.127)
		(layer "F.Cu")
		(net "MEMCASN")
	)
	(segment
		(start 22.43455 -138.961622)
		(end 22.85365 -139.380722)
		(width 0.127)
		(layer "F.Cu")
		(net "MEMBA_1")
	)
	(segment
		(start 25.682702 -131.909058)
		(end 25.682702 -130.902202)
		(width 0.127)
		(layer "F.Cu")
		(net "MEMBA_1")
	)
	(segment
		(start 22.0345 -138.561572)
		(end 22.43455 -138.961622)
		(width 0.127)
		(layer "F.Cu")
		(net "MEMBA_1")
	)
	(segment
		(start 40.615616 -143.516604)
		(end 40.899334 -143.800068)
		(width 0.1016)
		(layer "F.Cu")
		(net "MEMBA_1")
	)
	(segment
		(start 40.899334 -143.800068)
		(end 40.899842 -143.800068)
		(width 0.1016)
		(layer "F.Cu")
		(net "MEMBA_1")
	)
	(segment
		(start 27.4066 -141.59992)
		(end 27.2796 -141.72692)
		(width 0.127)
		(layer "F.Cu")
		(net "MEMBA_1")
	)
	(segment
		(start 27.4066 -142.45082)
		(end 33.921192 -142.45082)
		(width 0.127)
		(layer "F.Cu")
		(net "MEMBA_1")
	)
	(segment
		(start 22.85365 -139.380722)
		(end 24.274272 -139.380722)
		(width 0.127)
		(layer "F.Cu")
		(net "MEMBA_1")
	)
	(segment
		(start 36.514278 -143.399764)
		(end 40.33393 -143.399764)
		(width 0.127)
		(layer "F.Cu")
		(net "MEMBA_1")
	)
	(segment
		(start 36.401502 -143.51254)
		(end 36.514278 -143.399764)
		(width 0.127)
		(layer "F.Cu")
		(net "MEMBA_1")
	)
	(segment
		(start 24.274272 -139.380722)
		(end 26.162 -137.492994)
		(width 0.127)
		(layer "F.Cu")
		(net "MEMBA_1")
	)
	(segment
		(start 25.682702 -130.902202)
		(end 25.6794 -130.8989)
		(width 0.127)
		(layer "F.Cu")
		(net "MEMBA_1")
	)
	(segment
		(start 27.2796 -141.72692)
		(end 27.2796 -142.32382)
		(width 0.127)
		(layer "F.Cu")
		(net "MEMBA_1")
	)
	(segment
		(start 31.1404 -141.59992)
		(end 27.4066 -141.59992)
		(width 0.127)
		(layer "F.Cu")
		(net "MEMBA_1")
	)
	(segment
		(start 34.982912 -143.51254)
		(end 36.401502 -143.51254)
		(width 0.127)
		(layer "F.Cu")
		(net "MEMBA_1")
	)
	(segment
		(start 33.921192 -142.45082)
		(end 34.982912 -143.51254)
		(width 0.127)
		(layer "F.Cu")
		(net "MEMBA_1")
	)
	(segment
		(start 26.162 -132.388356)
		(end 25.682702 -131.909058)
		(width 0.127)
		(layer "F.Cu")
		(net "MEMBA_1")
	)
	(segment
		(start 26.162 -137.492994)
		(end 26.162 -132.388356)
		(width 0.127)
		(layer "F.Cu")
		(net "MEMBA_1")
	)
	(segment
		(start 27.2796 -142.32382)
		(end 27.4066 -142.45082)
		(width 0.127)
		(layer "F.Cu")
		(net "MEMBA_1")
	)
	(via
		(at 31.1404 -141.59992)
		(size 0.508)
		(drill 0.254)
		(layers "F.Cu" "B.Cu")
		(net "MEMBA_1")
	)
	(via
		(at 22.0345 -138.561572)
		(size 0.508)
		(drill 0.254)
		(layers "F.Cu" "B.Cu")
		(net "MEMBA_1")
	)
	(arc
		(start 40.33393 -143.399764)
		(mid 40.486411 -143.43013)
		(end 40.615616 -143.516604)
		(width 0.1016)
		(layer "F.Cu")
		(net "MEMBA_1")
	)
	(segment
		(start 30.60192 -141.06144)
		(end 28.80614 -141.06144)
		(width 0.126746)
		(layer "In2.Cu")
		(net "MEMBA_1")
	)
	(segment
		(start 28.80614 -141.06144)
		(end 27.27833 -139.53363)
		(width 0.126746)
		(layer "In2.Cu")
		(net "MEMBA_1")
	)
	(segment
		(start 24.569674 -138.942318)
		(end 24.169878 -138.542522)
		(width 0.127)
		(layer "In2.Cu")
		(net "MEMBA_1")
	)
	(segment
		(start 23.008082 -138.980672)
		(end 22.4536 -138.980672)
		(width 0.127)
		(layer "In2.Cu")
		(net "MEMBA_1")
	)
	(segment
		(start 23.446232 -138.542522)
		(end 23.008082 -138.980672)
		(width 0.127)
		(layer "In2.Cu")
		(net "MEMBA_1")
	)
	(segment
		(start 31.1404 -141.59992)
		(end 30.60192 -141.06144)
		(width 0.126746)
		(layer "In2.Cu")
		(net "MEMBA_1")
	)
	(segment
		(start 26.090626 -138.942318)
		(end 24.569674 -138.942318)
		(width 0.127)
		(layer "In2.Cu")
		(net "MEMBA_1")
	)
	(segment
		(start 26.681938 -139.53363)
		(end 26.090626 -138.942318)
		(width 0.127)
		(layer "In2.Cu")
		(net "MEMBA_1")
	)
	(segment
		(start 24.169878 -138.542522)
		(end 23.446232 -138.542522)
		(width 0.127)
		(layer "In2.Cu")
		(net "MEMBA_1")
	)
	(segment
		(start 27.27833 -139.53363)
		(end 26.681938 -139.53363)
		(width 0.127)
		(layer "In2.Cu")
		(net "MEMBA_1")
	)
	(segment
		(start 22.4536 -138.980672)
		(end 22.0345 -138.561572)
		(width 0.127)
		(layer "In2.Cu")
		(net "MEMBA_1")
	)
	(segment
		(start 15.893542 -138.324336)
		(end 15.327376 -138.324336)
		(width 0.127)
		(layer "F.Cu")
		(net "MEMBA_0")
	)
	(segment
		(start 14.565376 -138.324336)
		(end 14.20368 -138.324336)
		(width 0.127)
		(layer "F.Cu")
		(net "MEMBA_0")
	)
	(segment
		(start 18.034508 -138.561572)
		(end 16.130778 -138.561572)
		(width 0.127)
		(layer "F.Cu")
		(net "MEMBA_0")
	)
	(segment
		(start 15.073376 -137.32129)
		(end 14.819376 -137.32129)
		(width 0.127)
		(layer "F.Cu")
		(net "MEMBA_0")
	)
	(segment
		(start 14.692376 -137.44829)
		(end 14.692376 -138.197336)
		(width 0.127)
		(layer "F.Cu")
		(net "MEMBA_0")
	)
	(segment
		(start 10.350754 -138.145774)
		(end 9.349232 -138.145774)
		(width 0.127)
		(layer "F.Cu")
		(net "MEMBA_0")
	)
	(segment
		(start 15.327376 -138.324336)
		(end 15.200376 -138.197336)
		(width 0.127)
		(layer "F.Cu")
		(net "MEMBA_0")
	)
	(segment
		(start 14.20368 -138.324336)
		(end 14.07541 -138.196066)
		(width 0.127)
		(layer "F.Cu")
		(net "MEMBA_0")
	)
	(segment
		(start 16.130778 -138.561572)
		(end 15.893542 -138.324336)
		(width 0.127)
		(layer "F.Cu")
		(net "MEMBA_0")
	)
	(segment
		(start 14.07541 -138.196066)
		(end 14.07541 -137.694416)
		(width 0.127)
		(layer "F.Cu")
		(net "MEMBA_0")
	)
	(segment
		(start 10.352024 -137.574274)
		(end 10.352024 -138.144504)
		(width 0.127)
		(layer "F.Cu")
		(net "MEMBA_0")
	)
	(segment
		(start 10.500106 -137.426192)
		(end 10.352024 -137.574274)
		(width 0.127)
		(layer "F.Cu")
		(net "MEMBA_0")
	)
	(segment
		(start 15.200376 -137.44829)
		(end 15.073376 -137.32129)
		(width 0.127)
		(layer "F.Cu")
		(net "MEMBA_0")
	)
	(segment
		(start 14.692376 -138.197336)
		(end 14.565376 -138.324336)
		(width 0.127)
		(layer "F.Cu")
		(net "MEMBA_0")
	)
	(segment
		(start 14.819376 -137.32129)
		(end 14.692376 -137.44829)
		(width 0.127)
		(layer "F.Cu")
		(net "MEMBA_0")
	)
	(segment
		(start 18.034508 -138.561572)
		(end 17.634458 -138.961622)
		(width 0.127)
		(layer "F.Cu")
		(net "MEMBA_0")
	)
	(segment
		(start 15.200376 -138.197336)
		(end 15.200376 -137.44829)
		(width 0.127)
		(layer "F.Cu")
		(net "MEMBA_0")
	)
	(segment
		(start 14.07541 -137.694416)
		(end 13.807186 -137.426192)
		(width 0.127)
		(layer "F.Cu")
		(net "MEMBA_0")
	)
	(segment
		(start 10.352024 -138.144504)
		(end 10.350754 -138.145774)
		(width 0.127)
		(layer "F.Cu")
		(net "MEMBA_0")
	)
	(segment
		(start 13.807186 -137.426192)
		(end 10.500106 -137.426192)
		(width 0.127)
		(layer "F.Cu")
		(net "MEMBA_0")
	)
	(segment
		(start 43.299888 -144.599914)
		(end 42.900092 -144.200118)
		(width 0.127)
		(layer "F.Cu")
		(net "MEMBA_0")
	)
	(via
		(at 42.900092 -144.200118)
		(size 0.4572)
		(drill 0.2032)
		(layers "F.Cu" "B.Cu")
		(net "MEMBA_0")
	)
	(via
		(at 18.034508 -138.561572)
		(size 0.508)
		(drill 0.254)
		(layers "F.Cu" "B.Cu")
		(net "MEMBA_0")
	)
	(segment
		(start 32.20974 -139.4206)
		(end 31.364936 -139.4206)
		(width 0.127)
		(layer "In5.Cu")
		(net "MEMBA_0")
	)
	(segment
		(start 39.551356 -141.271244)
		(end 38.309804 -140.029692)
		(width 0.127)
		(layer "In5.Cu")
		(net "MEMBA_0")
	)
	(segment
		(start 18.240502 -138.354816)
		(end 18.240502 -138.355578)
		(width 0.0889)
		(layer "In5.Cu")
		(net "MEMBA_0")
	)
	(segment
		(start 42.900092 -144.200118)
		(end 42.699178 -143.999204)
		(width 0.127)
		(layer "In5.Cu")
		(net "MEMBA_0")
	)
	(segment
		(start 19.383502 -138.141964)
		(end 18.754344 -138.141964)
		(width 0.0889)
		(layer "In5.Cu")
		(net "MEMBA_0")
	)
	(segment
		(start 18.240502 -138.355578)
		(end 18.034508 -138.561572)
		(width 0.0889)
		(layer "In5.Cu")
		(net "MEMBA_0")
	)
	(segment
		(start 20.983194 -136.542272)
		(end 19.383502 -138.141964)
		(width 0.127)
		(layer "In5.Cu")
		(net "MEMBA_0")
	)
	(segment
		(start 40.022526 -141.51356)
		(end 40.013128 -141.503908)
		(width 0.127)
		(layer "In5.Cu")
		(net "MEMBA_0")
	)
	(segment
		(start 41.70553 -142.60322)
		(end 41.693592 -142.516606)
		(width 0.127)
		(layer "In5.Cu")
		(net "MEMBA_0")
	)
	(segment
		(start 41.463214 -142.206218)
		(end 41.193466 -142.206218)
		(width 0.127)
		(layer "In5.Cu")
		(net "MEMBA_0")
	)
	(segment
		(start 23.827994 -136.542272)
		(end 20.983194 -136.542272)
		(width 0.127)
		(layer "In5.Cu")
		(net "MEMBA_0")
	)
	(segment
		(start 31.364936 -139.4206)
		(end 30.158436 -138.2141)
		(width 0.127)
		(layer "In5.Cu")
		(net "MEMBA_0")
	)
	(segment
		(start 32.818832 -140.029692)
		(end 32.20974 -139.4206)
		(width 0.127)
		(layer "In5.Cu")
		(net "MEMBA_0")
	)
	(segment
		(start 41.835324 -142.894558)
		(end 41.81983 -142.879064)
		(width 0.127)
		(layer "In5.Cu")
		(net "MEMBA_0")
	)
	(segment
		(start 41.02862 -142.138654)
		(end 40.723058 -141.833092)
		(width 0.127)
		(layer "In5.Cu")
		(net "MEMBA_0")
	)
	(segment
		(start 30.158436 -138.2141)
		(end 28.995624 -138.2141)
		(width 0.127)
		(layer "In5.Cu")
		(net "MEMBA_0")
	)
	(segment
		(start 38.309804 -140.029692)
		(end 32.818832 -140.029692)
		(width 0.127)
		(layer "In5.Cu")
		(net "MEMBA_0")
	)
	(segment
		(start 27.819604 -137.03808)
		(end 24.323802 -137.03808)
		(width 0.127)
		(layer "In5.Cu")
		(net "MEMBA_0")
	)
	(segment
		(start 41.693592 -142.516606)
		(end 41.693592 -142.436596)
		(width 0.127)
		(layer "In5.Cu")
		(net "MEMBA_0")
	)
	(segment
		(start 42.49293 -143.501364)
		(end 42.49293 -143.30426)
		(width 0.127)
		(layer "In5.Cu")
		(net "MEMBA_0")
	)
	(segment
		(start 41.193466 -142.206218)
		(end 41.19118 -142.205964)
		(width 0.127)
		(layer "In5.Cu")
		(net "MEMBA_0")
	)
	(segment
		(start 24.323802 -137.03808)
		(end 23.827994 -136.542272)
		(width 0.127)
		(layer "In5.Cu")
		(net "MEMBA_0")
	)
	(segment
		(start 28.995624 -138.2141)
		(end 27.819604 -137.03808)
		(width 0.127)
		(layer "In5.Cu")
		(net "MEMBA_0")
	)
	(segment
		(start 41.693592 -142.436596)
		(end 41.463214 -142.206218)
		(width 0.127)
		(layer "In5.Cu")
		(net "MEMBA_0")
	)
	(arc
		(start 40.013128 -141.503908)
		(mid 39.903461 -141.419094)
		(end 39.776146 -141.364208)
		(width 0.127)
		(layer "In5.Cu")
		(net "MEMBA_0")
	)
	(arc
		(start 42.41673 -143.120364)
		(mid 42.256656 -143.026156)
		(end 42.07383 -142.993364)
		(width 0.127)
		(layer "In5.Cu")
		(net "MEMBA_0")
	)
	(arc
		(start 41.19118 -142.205964)
		(mid 41.103213 -142.188466)
		(end 41.02862 -142.138654)
		(width 0.127)
		(layer "In5.Cu")
		(net "MEMBA_0")
	)
	(arc
		(start 42.07383 -142.993364)
		(mid 41.944746 -142.967688)
		(end 41.835324 -142.894558)
		(width 0.127)
		(layer "In5.Cu")
		(net "MEMBA_0")
	)
	(arc
		(start 39.776146 -141.364208)
		(mid 39.654518 -141.34005)
		(end 39.551356 -141.271244)
		(width 0.127)
		(layer "In5.Cu")
		(net "MEMBA_0")
	)
	(arc
		(start 18.754344 -138.141964)
		(mid 18.47625 -138.19728)
		(end 18.240502 -138.354816)
		(width 0.0889)
		(layer "In5.Cu")
		(net "MEMBA_0")
	)
	(arc
		(start 42.49293 -143.30426)
		(mid 42.473131 -143.204726)
		(end 42.41673 -143.120364)
		(width 0.127)
		(layer "In5.Cu")
		(net "MEMBA_0")
	)
	(arc
		(start 40.43553 -141.723364)
		(mid 40.212352 -141.651291)
		(end 40.022526 -141.51356)
		(width 0.127)
		(layer "In5.Cu")
		(net "MEMBA_0")
	)
	(arc
		(start 40.723058 -141.833092)
		(mid 40.585073 -141.763084)
		(end 40.43553 -141.723364)
		(width 0.127)
		(layer "In5.Cu")
		(net "MEMBA_0")
	)
	(arc
		(start 42.699178 -143.999204)
		(mid 42.546559 -143.770793)
		(end 42.49293 -143.501364)
		(width 0.127)
		(layer "In5.Cu")
		(net "MEMBA_0")
	)
	(arc
		(start 41.81983 -142.879064)
		(mid 41.735213 -142.75252)
		(end 41.70553 -142.60322)
		(width 0.127)
		(layer "In5.Cu")
		(net "MEMBA_0")
	)
	(segment
		(start 40.500046 -140.999972)
		(end 40.899842 -141.399768)
		(width 0.127)
		(layer "F.Cu")
		(net "MEMA_9")
	)
	(segment
		(start 21.2344 -136.961626)
		(end 21.63445 -137.361676)
		(width 0.127)
		(layer "F.Cu")
		(net "MEMA_9")
	)
	(segment
		(start 40.899842 -141.399768)
		(end 40.899842 -141.400022)
		(width 0.127)
		(layer "F.Cu")
		(net "MEMA_9")
	)
	(via
		(at 40.500046 -140.999972)
		(size 0.4572)
		(drill 0.2032)
		(layers "F.Cu" "B.Cu")
		(net "MEMA_9")
	)
	(via
		(at 21.2344 -136.961626)
		(size 0.508)
		(drill 0.254)
		(layers "F.Cu" "B.Cu")
		(net "MEMA_9")
	)
	(segment
		(start 21.493988 -135.451088)
		(end 21.366988 -135.578088)
		(width 0.127)
		(layer "B.Cu")
		(net "MEMA_9")
	)
	(segment
		(start 20.871688 -130.753358)
		(end 21.280628 -131.162298)
		(width 0.127)
		(layer "B.Cu")
		(net "MEMA_9")
	)
	(segment
		(start 20.772628 -130.753358)
		(end 20.871688 -130.753358)
		(width 0.127)
		(layer "B.Cu")
		(net "MEMA_9")
	)
	(segment
		(start 21.366988 -134.562088)
		(end 20.688046 -134.562088)
		(width 0.127)
		(layer "B.Cu")
		(net "MEMA_9")
	)
	(segment
		(start 20.688046 -135.578088)
		(end 20.561046 -135.705088)
		(width 0.127)
		(layer "B.Cu")
		(net "MEMA_9")
	)
	(segment
		(start 20.561046 -135.959088)
		(end 20.688046 -136.086088)
		(width 0.127)
		(layer "B.Cu")
		(net "MEMA_9")
	)
	(segment
		(start 21.493988 -136.702038)
		(end 21.2344 -136.961626)
		(width 0.127)
		(layer "B.Cu")
		(net "MEMA_9")
	)
	(segment
		(start 21.366988 -135.578088)
		(end 20.688046 -135.578088)
		(width 0.127)
		(layer "B.Cu")
		(net "MEMA_9")
	)
	(segment
		(start 20.561046 -134.689088)
		(end 20.561046 -134.943088)
		(width 0.127)
		(layer "B.Cu")
		(net "MEMA_9")
	)
	(segment
		(start 21.280628 -131.162298)
		(end 21.280628 -132.815076)
		(width 0.127)
		(layer "B.Cu")
		(net "MEMA_9")
	)
	(segment
		(start 20.688046 -135.070088)
		(end 21.366988 -135.070088)
		(width 0.127)
		(layer "B.Cu")
		(net "MEMA_9")
	)
	(segment
		(start 21.493988 -134.435088)
		(end 21.366988 -134.562088)
		(width 0.127)
		(layer "B.Cu")
		(net "MEMA_9")
	)
	(segment
		(start 21.280628 -132.815076)
		(end 21.493988 -133.028436)
		(width 0.127)
		(layer "B.Cu")
		(net "MEMA_9")
	)
	(segment
		(start 20.591272 -130.553714)
		(end 20.582128 -130.562858)
		(width 0.127)
		(layer "B.Cu")
		(net "MEMA_9")
	)
	(segment
		(start 21.366988 -136.086088)
		(end 21.493988 -136.213088)
		(width 0.127)
		(layer "B.Cu")
		(net "MEMA_9")
	)
	(segment
		(start 20.561046 -135.705088)
		(end 20.561046 -135.959088)
		(width 0.127)
		(layer "B.Cu")
		(net "MEMA_9")
	)
	(segment
		(start 20.688046 -136.086088)
		(end 21.366988 -136.086088)
		(width 0.127)
		(layer "B.Cu")
		(net "MEMA_9")
	)
	(segment
		(start 21.366988 -135.070088)
		(end 21.493988 -135.197088)
		(width 0.127)
		(layer "B.Cu")
		(net "MEMA_9")
	)
	(segment
		(start 20.582128 -130.562858)
		(end 20.772628 -130.753358)
		(width 0.127)
		(layer "B.Cu")
		(net "MEMA_9")
	)
	(segment
		(start 20.561046 -134.943088)
		(end 20.688046 -135.070088)
		(width 0.127)
		(layer "B.Cu")
		(net "MEMA_9")
	)
	(segment
		(start 21.493988 -136.213088)
		(end 21.493988 -136.702038)
		(width 0.127)
		(layer "B.Cu")
		(net "MEMA_9")
	)
	(segment
		(start 20.688046 -134.562088)
		(end 20.561046 -134.689088)
		(width 0.127)
		(layer "B.Cu")
		(net "MEMA_9")
	)
	(segment
		(start 20.591272 -129.518664)
		(end 20.591272 -130.553714)
		(width 0.127)
		(layer "B.Cu")
		(net "MEMA_9")
	)
	(segment
		(start 21.493988 -133.028436)
		(end 21.493988 -134.435088)
		(width 0.127)
		(layer "B.Cu")
		(net "MEMA_9")
	)
	(segment
		(start 21.493988 -135.197088)
		(end 21.493988 -135.451088)
		(width 0.127)
		(layer "B.Cu")
		(net "MEMA_9")
	)
	(segment
		(start 29.724096 -135.71728)
		(end 29.597096 -135.84428)
		(width 0.127)
		(layer "In2.Cu")
		(net "MEMA_9")
	)
	(segment
		(start 29.597096 -135.84428)
		(end 29.597096 -137.36066)
		(width 0.127)
		(layer "In2.Cu")
		(net "MEMA_9")
	)
	(segment
		(start 21.728684 -136.467342)
		(end 21.2344 -136.961626)
		(width 0.127)
		(layer "In2.Cu")
		(net "MEMA_9")
	)
	(segment
		(start 30.613096 -137.74674)
		(end 30.486096 -137.87374)
		(width 0.127)
		(layer "In2.Cu")
		(net "MEMA_9")
	)
	(segment
		(start 31.248096 -137.2997)
		(end 31.121096 -137.1727)
		(width 0.127)
		(layer "In2.Cu")
		(net "MEMA_9")
	)
	(segment
		(start 29.470096 -137.48766)
		(end 29.216096 -137.48766)
		(width 0.127)
		(layer "In2.Cu")
		(net "MEMA_9")
	)
	(segment
		(start 31.629096 -137.1727)
		(end 31.502096 -137.2997)
		(width 0.127)
		(layer "In2.Cu")
		(net "MEMA_9")
	)
	(segment
		(start 29.597096 -137.36066)
		(end 29.470096 -137.48766)
		(width 0.127)
		(layer "In2.Cu")
		(net "MEMA_9")
	)
	(segment
		(start 30.613096 -136.37514)
		(end 30.613096 -137.74674)
		(width 0.127)
		(layer "In2.Cu")
		(net "MEMA_9")
	)
	(segment
		(start 30.105096 -137.74674)
		(end 30.105096 -135.84428)
		(width 0.127)
		(layer "In2.Cu")
		(net "MEMA_9")
	)
	(segment
		(start 29.216096 -137.48766)
		(end 29.089096 -137.36066)
		(width 0.127)
		(layer "In2.Cu")
		(net "MEMA_9")
	)
	(segment
		(start 40.500046 -140.999972)
		(end 40.423592 -140.999972)
		(width 0.127)
		(layer "In2.Cu")
		(net "MEMA_9")
	)
	(segment
		(start 36.64712 -137.2235)
		(end 33.155382 -137.2235)
		(width 0.127)
		(layer "In2.Cu")
		(net "MEMA_9")
	)
	(segment
		(start 29.089096 -136.529318)
		(end 28.962096 -136.402318)
		(width 0.127)
		(layer "In2.Cu")
		(net "MEMA_9")
	)
	(segment
		(start 33.155382 -137.2235)
		(end 32.3342 -136.402318)
		(width 0.127)
		(layer "In2.Cu")
		(net "MEMA_9")
	)
	(segment
		(start 40.423592 -140.999972)
		(end 36.64712 -137.2235)
		(width 0.127)
		(layer "In2.Cu")
		(net "MEMA_9")
	)
	(segment
		(start 31.502096 -137.2997)
		(end 31.248096 -137.2997)
		(width 0.127)
		(layer "In2.Cu")
		(net "MEMA_9")
	)
	(segment
		(start 31.121096 -136.37514)
		(end 30.994096 -136.24814)
		(width 0.127)
		(layer "In2.Cu")
		(net "MEMA_9")
	)
	(segment
		(start 30.486096 -137.87374)
		(end 30.232096 -137.87374)
		(width 0.127)
		(layer "In2.Cu")
		(net "MEMA_9")
	)
	(segment
		(start 30.994096 -136.24814)
		(end 30.740096 -136.24814)
		(width 0.127)
		(layer "In2.Cu")
		(net "MEMA_9")
	)
	(segment
		(start 31.756096 -136.402318)
		(end 31.629096 -136.529318)
		(width 0.127)
		(layer "In2.Cu")
		(net "MEMA_9")
	)
	(segment
		(start 30.105096 -135.84428)
		(end 29.978096 -135.71728)
		(width 0.127)
		(layer "In2.Cu")
		(net "MEMA_9")
	)
	(segment
		(start 23.694136 -136.467342)
		(end 21.728684 -136.467342)
		(width 0.127)
		(layer "In2.Cu")
		(net "MEMA_9")
	)
	(segment
		(start 29.978096 -135.71728)
		(end 29.724096 -135.71728)
		(width 0.127)
		(layer "In2.Cu")
		(net "MEMA_9")
	)
	(segment
		(start 28.962096 -136.402318)
		(end 23.75916 -136.402318)
		(width 0.127)
		(layer "In2.Cu")
		(net "MEMA_9")
	)
	(segment
		(start 30.740096 -136.24814)
		(end 30.613096 -136.37514)
		(width 0.127)
		(layer "In2.Cu")
		(net "MEMA_9")
	)
	(segment
		(start 32.3342 -136.402318)
		(end 31.756096 -136.402318)
		(width 0.127)
		(layer "In2.Cu")
		(net "MEMA_9")
	)
	(segment
		(start 31.121096 -137.1727)
		(end 31.121096 -136.37514)
		(width 0.127)
		(layer "In2.Cu")
		(net "MEMA_9")
	)
	(segment
		(start 30.232096 -137.87374)
		(end 30.105096 -137.74674)
		(width 0.127)
		(layer "In2.Cu")
		(net "MEMA_9")
	)
	(segment
		(start 31.629096 -136.529318)
		(end 31.629096 -137.1727)
		(width 0.127)
		(layer "In2.Cu")
		(net "MEMA_9")
	)
	(segment
		(start 23.75916 -136.402318)
		(end 23.694136 -136.467342)
		(width 0.127)
		(layer "In2.Cu")
		(net "MEMA_9")
	)
	(segment
		(start 29.089096 -137.36066)
		(end 29.089096 -136.529318)
		(width 0.127)
		(layer "In2.Cu")
		(net "MEMA_9")
	)
	(segment
		(start 17.234408 -136.961626)
		(end 17.634458 -137.361676)
		(width 0.127)
		(layer "F.Cu")
		(net "MEMA_8")
	)
	(segment
		(start 41.699942 -141.400022)
		(end 42.099992 -140.999972)
		(width 0.127)
		(layer "F.Cu")
		(net "MEMA_8")
	)
	(via
		(at 17.234408 -136.961626)
		(size 0.508)
		(drill 0.254)
		(layers "F.Cu" "B.Cu")
		(net "MEMA_8")
	)
	(via
		(at 42.099992 -140.999972)
		(size 0.4572)
		(drill 0.2032)
		(layers "F.Cu" "B.Cu")
		(net "MEMA_8")
	)
	(segment
		(start 14.12875 -137.413746)
		(end 14.244066 -137.29843)
		(width 0.127)
		(layer "B.Cu")
		(net "MEMA_8")
	)
	(segment
		(start 15.768066 -136.56183)
		(end 15.768066 -137.182352)
		(width 0.127)
		(layer "B.Cu")
		(net "MEMA_8")
	)
	(segment
		(start 15.923514 -137.3378)
		(end 16.858234 -137.3378)
		(width 0.127)
		(layer "B.Cu")
		(net "MEMA_8")
	)
	(segment
		(start 14.752066 -136.56183)
		(end 14.752066 -137.55497)
		(width 0.127)
		(layer "B.Cu")
		(net "MEMA_8")
	)
	(segment
		(start 15.387066 -136.43483)
		(end 15.641066 -136.43483)
		(width 0.127)
		(layer "B.Cu")
		(net "MEMA_8")
	)
	(segment
		(start 11.647424 -136.715246)
		(end 11.647424 -137.132822)
		(width 0.127)
		(layer "B.Cu")
		(net "MEMA_8")
	)
	(segment
		(start 15.641066 -136.43483)
		(end 15.768066 -136.56183)
		(width 0.127)
		(layer "B.Cu")
		(net "MEMA_8")
	)
	(segment
		(start 14.625066 -136.43483)
		(end 14.752066 -136.56183)
		(width 0.127)
		(layer "B.Cu")
		(net "MEMA_8")
	)
	(segment
		(start 11.646154 -136.716516)
		(end 11.647424 -136.715246)
		(width 0.127)
		(layer "B.Cu")
		(net "MEMA_8")
	)
	(segment
		(start 15.11554 -137.664444)
		(end 15.260066 -137.519918)
		(width 0.127)
		(layer "B.Cu")
		(net "MEMA_8")
	)
	(segment
		(start 15.260066 -137.519918)
		(end 15.260066 -136.56183)
		(width 0.127)
		(layer "B.Cu")
		(net "MEMA_8")
	)
	(segment
		(start 11.647424 -137.132822)
		(end 11.928348 -137.413746)
		(width 0.127)
		(layer "B.Cu")
		(net "MEMA_8")
	)
	(segment
		(start 14.752066 -137.55497)
		(end 14.86154 -137.664444)
		(width 0.127)
		(layer "B.Cu")
		(net "MEMA_8")
	)
	(segment
		(start 14.371066 -136.43483)
		(end 14.625066 -136.43483)
		(width 0.127)
		(layer "B.Cu")
		(net "MEMA_8")
	)
	(segment
		(start 15.768066 -137.182352)
		(end 15.923514 -137.3378)
		(width 0.127)
		(layer "B.Cu")
		(net "MEMA_8")
	)
	(segment
		(start 14.244066 -136.56183)
		(end 14.371066 -136.43483)
		(width 0.127)
		(layer "B.Cu")
		(net "MEMA_8")
	)
	(segment
		(start 10.619232 -136.716516)
		(end 11.646154 -136.716516)
		(width 0.127)
		(layer "B.Cu")
		(net "MEMA_8")
	)
	(segment
		(start 16.858234 -137.3378)
		(end 17.234408 -136.961626)
		(width 0.127)
		(layer "B.Cu")
		(net "MEMA_8")
	)
	(segment
		(start 14.244066 -137.29843)
		(end 14.244066 -136.56183)
		(width 0.127)
		(layer "B.Cu")
		(net "MEMA_8")
	)
	(segment
		(start 11.928348 -137.413746)
		(end 14.12875 -137.413746)
		(width 0.127)
		(layer "B.Cu")
		(net "MEMA_8")
	)
	(segment
		(start 14.86154 -137.664444)
		(end 15.11554 -137.664444)
		(width 0.127)
		(layer "B.Cu")
		(net "MEMA_8")
	)
	(segment
		(start 15.260066 -136.56183)
		(end 15.387066 -136.43483)
		(width 0.127)
		(layer "B.Cu")
		(net "MEMA_8")
	)
	(segment
		(start 32.172656 -133.950456)
		(end 29.34589 -133.950456)
		(width 0.127)
		(layer "In5.Cu")
		(net "MEMA_8")
	)
	(segment
		(start 41.7068 -140.4112)
		(end 41.7068 -140.0048)
		(width 0.1016)
		(layer "In5.Cu")
		(net "MEMA_8")
	)
	(segment
		(start 41.5036 -139.8016)
		(end 40.24884 -139.8016)
		(width 0.1016)
		(layer "In5.Cu")
		(net "MEMA_8")
	)
	(segment
		(start 32.9692 -134.747)
		(end 32.172656 -133.950456)
		(width 0.127)
		(layer "In5.Cu")
		(net "MEMA_8")
	)
	(segment
		(start 17.234408 -136.77265)
		(end 17.234408 -136.961626)
		(width 0.127)
		(layer "In5.Cu")
		(net "MEMA_8")
	)
	(segment
		(start 41.908984 -140.613384)
		(end 41.7068 -140.4112)
		(width 0.1016)
		(layer "In5.Cu")
		(net "MEMA_8")
	)
	(segment
		(start 41.7068 -140.0048)
		(end 41.5036 -139.8016)
		(width 0.1016)
		(layer "In5.Cu")
		(net "MEMA_8")
	)
	(segment
		(start 35.19424 -134.747)
		(end 32.9692 -134.747)
		(width 0.127)
		(layer "In5.Cu")
		(net "MEMA_8")
	)
	(segment
		(start 42.099992 -140.999972)
		(end 41.908984 -140.809218)
		(width 0.1016)
		(layer "In5.Cu")
		(net "MEMA_8")
	)
	(segment
		(start 29.34589 -133.950456)
		(end 28.61183 -133.216396)
		(width 0.127)
		(layer "In5.Cu")
		(net "MEMA_8")
	)
	(segment
		(start 40.24884 -139.8016)
		(end 39.457122 -139.009882)
		(width 0.1016)
		(layer "In5.Cu")
		(net "MEMA_8")
	)
	(segment
		(start 39.457122 -139.009882)
		(end 35.19424 -134.747)
		(width 0.127)
		(layer "In5.Cu")
		(net "MEMA_8")
	)
	(segment
		(start 20.790662 -133.216396)
		(end 17.234408 -136.77265)
		(width 0.127)
		(layer "In5.Cu")
		(net "MEMA_8")
	)
	(segment
		(start 41.908984 -140.809218)
		(end 41.908984 -140.613384)
		(width 0.1016)
		(layer "In5.Cu")
		(net "MEMA_8")
	)
	(segment
		(start 28.61183 -133.216396)
		(end 20.790662 -133.216396)
		(width 0.127)
		(layer "In5.Cu")
		(net "MEMA_8")
	)
	(segment
		(start 34.645854 -138.92022)
		(end 34.645854 -138.252962)
		(width 0.127)
		(layer "F.Cu")
		(net "MEMA_7")
	)
	(segment
		(start 28.95092 -138.6332)
		(end 29.07792 -138.7602)
		(width 0.127)
		(layer "F.Cu")
		(net "MEMA_7")
	)
	(segment
		(start 22.834346 -136.96188)
		(end 22.834346 -136.961372)
		(width 0.127)
		(layer "F.Cu")
		(net "MEMA_7")
	)
	(segment
		(start 28.95092 -136.4234)
		(end 28.95092 -137.59561)
		(width 0.127)
		(layer "F.Cu")
		(net "MEMA_7")
	)
	(segment
		(start 29.07792 -138.7602)
		(end 29.7688 -138.7602)
		(width 0.127)
		(layer "F.Cu")
		(net "MEMA_7")
	)
	(segment
		(start 28.31592 -135.9408)
		(end 28.06192 -135.9408)
		(width 0.127)
		(layer "F.Cu")
		(net "MEMA_7")
	)
	(segment
		(start 28.06192 -135.9408)
		(end 27.93492 -136.0678)
		(width 0.127)
		(layer "F.Cu")
		(net "MEMA_7")
	)
	(segment
		(start 28.82392 -138.23061)
		(end 28.95092 -138.35761)
		(width 0.127)
		(layer "F.Cu")
		(net "MEMA_7")
	)
	(segment
		(start 31.082234 -136.2964)
		(end 31.026354 -136.24052)
		(width 0.127)
		(layer "F.Cu")
		(net "MEMA_7")
	)
	(segment
		(start 28.95092 -137.59561)
		(end 28.82392 -137.72261)
		(width 0.127)
		(layer "F.Cu")
		(net "MEMA_7")
	)
	(segment
		(start 36.767262 -140.999464)
		(end 36.022788 -140.25499)
		(width 0.127)
		(layer "F.Cu")
		(net "MEMA_7")
	)
	(segment
		(start 27.93492 -138.10361)
		(end 28.06192 -138.23061)
		(width 0.127)
		(layer "F.Cu")
		(net "MEMA_7")
	)
	(segment
		(start 29.1338 -136.24052)
		(end 28.95092 -136.4234)
		(width 0.127)
		(layer "F.Cu")
		(net "MEMA_7")
	)
	(segment
		(start 28.82392 -137.72261)
		(end 28.56992 -137.72261)
		(width 0.127)
		(layer "F.Cu")
		(net "MEMA_7")
	)
	(segment
		(start 31.57728 -136.2964)
		(end 31.082234 -136.2964)
		(width 0.127)
		(layer "F.Cu")
		(net "MEMA_7")
	)
	(segment
		(start 31.82366 -136.54278)
		(end 31.57728 -136.2964)
		(width 0.127)
		(layer "F.Cu")
		(net "MEMA_7")
	)
	(segment
		(start 35.980624 -140.25499)
		(end 34.645854 -138.92022)
		(width 0.127)
		(layer "F.Cu")
		(net "MEMA_7")
	)
	(segment
		(start 28.44292 -137.59561)
		(end 28.44292 -136.0678)
		(width 0.127)
		(layer "F.Cu")
		(net "MEMA_7")
	)
	(segment
		(start 32.935672 -136.54278)
		(end 31.82366 -136.54278)
		(width 0.127)
		(layer "F.Cu")
		(net "MEMA_7")
	)
	(segment
		(start 31.026354 -136.24052)
		(end 29.1338 -136.24052)
		(width 0.127)
		(layer "F.Cu")
		(net "MEMA_7")
	)
	(segment
		(start 34.645854 -138.252962)
		(end 32.935672 -136.54278)
		(width 0.127)
		(layer "F.Cu")
		(net "MEMA_7")
	)
	(segment
		(start 28.56992 -137.72261)
		(end 28.44292 -137.59561)
		(width 0.127)
		(layer "F.Cu")
		(net "MEMA_7")
	)
	(segment
		(start 36.022788 -140.25499)
		(end 35.980624 -140.25499)
		(width 0.127)
		(layer "F.Cu")
		(net "MEMA_7")
	)
	(segment
		(start 28.95092 -138.35761)
		(end 28.95092 -138.6332)
		(width 0.127)
		(layer "F.Cu")
		(net "MEMA_7")
	)
	(segment
		(start 39.36873 -140.999464)
		(end 36.767262 -140.999464)
		(width 0.127)
		(layer "F.Cu")
		(net "MEMA_7")
	)
	(segment
		(start 28.44292 -136.0678)
		(end 28.31592 -135.9408)
		(width 0.127)
		(layer "F.Cu")
		(net "MEMA_7")
	)
	(segment
		(start 28.06192 -138.23061)
		(end 28.82392 -138.23061)
		(width 0.127)
		(layer "F.Cu")
		(net "MEMA_7")
	)
	(segment
		(start 22.43455 -137.361676)
		(end 22.834346 -136.96188)
		(width 0.127)
		(layer "F.Cu")
		(net "MEMA_7")
	)
	(segment
		(start 27.93492 -136.0678)
		(end 27.93492 -138.10361)
		(width 0.127)
		(layer "F.Cu")
		(net "MEMA_7")
	)
	(segment
		(start 40.099996 -141.400022)
		(end 39.933118 -141.233398)
		(width 0.127)
		(layer "F.Cu")
		(net "MEMA_7")
	)
	(via
		(at 22.834346 -136.961372)
		(size 0.508)
		(drill 0.254)
		(layers "F.Cu" "B.Cu")
		(net "MEMA_7")
	)
	(via
		(at 29.7688 -138.7602)
		(size 0.508)
		(drill 0.254)
		(layers "F.Cu" "B.Cu")
		(net "MEMA_7")
	)
	(arc
		(start 39.933118 -141.233398)
		(mid 39.674203 -141.06027)
		(end 39.36873 -140.999464)
		(width 0.127)
		(layer "F.Cu")
		(net "MEMA_7")
	)
	(segment
		(start 24.266144 -133.29158)
		(end 24.139144 -133.16458)
		(width 0.127)
		(layer "B.Cu")
		(net "MEMA_7")
	)
	(segment
		(start 22.310852 -136.058656)
		(end 22.437852 -135.931656)
		(width 0.127)
		(layer "B.Cu")
		(net "MEMA_7")
	)
	(segment
		(start 22.834346 -135.545068)
		(end 24.139144 -134.24027)
		(width 0.127)
		(layer "B.Cu")
		(net "MEMA_7")
	)
	(segment
		(start 25.206198 -133.29158)
		(end 24.266144 -133.29158)
		(width 0.127)
		(layer "B.Cu")
		(net "MEMA_7")
	)
	(segment
		(start 23.440644 -130.562858)
		(end 23.440644 -129.556002)
		(width 0.127)
		(layer "B.Cu")
		(net "MEMA_7")
	)
	(segment
		(start 23.440644 -129.556002)
		(end 23.437342 -129.5527)
		(width 0.127)
		(layer "B.Cu")
		(net "MEMA_7")
	)
	(segment
		(start 25.355042 -133.650736)
		(end 25.355042 -133.440424)
		(width 0.127)
		(layer "B.Cu")
		(net "MEMA_7")
	)
	(segment
		(start 22.834346 -135.804656)
		(end 22.834346 -135.545068)
		(width 0.127)
		(layer "B.Cu")
		(net "MEMA_7")
	)
	(segment
		(start 22.707346 -136.439656)
		(end 22.437852 -136.439656)
		(width 0.127)
		(layer "B.Cu")
		(net "MEMA_7")
	)
	(segment
		(start 22.437852 -135.931656)
		(end 22.707346 -135.931656)
		(width 0.127)
		(layer "B.Cu")
		(net "MEMA_7")
	)
	(segment
		(start 24.266144 -133.79958)
		(end 25.206198 -133.79958)
		(width 0.127)
		(layer "B.Cu")
		(net "MEMA_7")
	)
	(segment
		(start 22.834346 -136.566656)
		(end 22.707346 -136.439656)
		(width 0.127)
		(layer "B.Cu")
		(net "MEMA_7")
	)
	(segment
		(start 24.139144 -131.162298)
		(end 23.539704 -130.562858)
		(width 0.127)
		(layer "B.Cu")
		(net "MEMA_7")
	)
	(segment
		(start 22.834346 -136.961372)
		(end 22.834346 -136.566656)
		(width 0.127)
		(layer "B.Cu")
		(net "MEMA_7")
	)
	(segment
		(start 22.310852 -136.312656)
		(end 22.310852 -136.058656)
		(width 0.127)
		(layer "B.Cu")
		(net "MEMA_7")
	)
	(segment
		(start 24.139144 -134.24027)
		(end 24.139144 -133.92658)
		(width 0.127)
		(layer "B.Cu")
		(net "MEMA_7")
	)
	(segment
		(start 25.206198 -133.79958)
		(end 25.355042 -133.650736)
		(width 0.127)
		(layer "B.Cu")
		(net "MEMA_7")
	)
	(segment
		(start 22.437852 -136.439656)
		(end 22.310852 -136.312656)
		(width 0.127)
		(layer "B.Cu")
		(net "MEMA_7")
	)
	(segment
		(start 24.139144 -133.92658)
		(end 24.266144 -133.79958)
		(width 0.127)
		(layer "B.Cu")
		(net "MEMA_7")
	)
	(segment
		(start 25.355042 -133.440424)
		(end 25.206198 -133.29158)
		(width 0.127)
		(layer "B.Cu")
		(net "MEMA_7")
	)
	(segment
		(start 23.539704 -130.562858)
		(end 23.440644 -130.562858)
		(width 0.127)
		(layer "B.Cu")
		(net "MEMA_7")
	)
	(segment
		(start 22.707346 -135.931656)
		(end 22.834346 -135.804656)
		(width 0.127)
		(layer "B.Cu")
		(net "MEMA_7")
	)
	(segment
		(start 24.139144 -133.16458)
		(end 24.139144 -131.162298)
		(width 0.127)
		(layer "B.Cu")
		(net "MEMA_7")
	)
	(segment
		(start 29.7688 -138.7602)
		(end 27.918918 -136.910318)
		(width 0.127)
		(layer "In2.Cu")
		(net "MEMA_7")
	)
	(segment
		(start 27.918918 -136.910318)
		(end 22.8854 -136.910318)
		(width 0.127)
		(layer "In2.Cu")
		(net "MEMA_7")
	)
	(segment
		(start 22.8854 -136.910318)
		(end 22.834346 -136.961372)
		(width 0.127)
		(layer "In2.Cu")
		(net "MEMA_7")
	)
	(segment
		(start 34.137854 -138.463528)
		(end 32.808926 -137.1346)
		(width 0.127)
		(layer "F.Cu")
		(net "MEMA_6")
	)
	(segment
		(start 31.97352 -137.9728)
		(end 32.3342 -137.9728)
		(width 0.127)
		(layer "F.Cu")
		(net "MEMA_6")
	)
	(segment
		(start 31.805626 -137.261854)
		(end 31.805626 -137.804906)
		(width 0.127)
		(layer "F.Cu")
		(net "MEMA_6")
	)
	(segment
		(start 32.808926 -137.1346)
		(end 31.93288 -137.1346)
		(width 0.127)
		(layer "F.Cu")
		(net "MEMA_6")
	)
	(segment
		(start 36.449254 -141.400022)
		(end 35.812222 -140.76299)
		(width 0.127)
		(layer "F.Cu")
		(net "MEMA_6")
	)
	(segment
		(start 31.93288 -137.1346)
		(end 31.805626 -137.261854)
		(width 0.127)
		(layer "F.Cu")
		(net "MEMA_6")
	)
	(segment
		(start 34.137854 -139.130786)
		(end 34.137854 -138.463528)
		(width 0.127)
		(layer "F.Cu")
		(net "MEMA_6")
	)
	(segment
		(start 31.805626 -137.804906)
		(end 31.97352 -137.9728)
		(width 0.127)
		(layer "F.Cu")
		(net "MEMA_6")
	)
	(segment
		(start 18.034508 -137.761472)
		(end 17.634458 -138.161522)
		(width 0.127)
		(layer "F.Cu")
		(net "MEMA_6")
	)
	(segment
		(start 35.812222 -140.76299)
		(end 35.770058 -140.76299)
		(width 0.127)
		(layer "F.Cu")
		(net "MEMA_6")
	)
	(segment
		(start 35.770058 -140.76299)
		(end 34.137854 -139.130786)
		(width 0.127)
		(layer "F.Cu")
		(net "MEMA_6")
	)
	(segment
		(start 39.299896 -141.400022)
		(end 36.449254 -141.400022)
		(width 0.127)
		(layer "F.Cu")
		(net "MEMA_6")
	)
	(via
		(at 32.3342 -137.9728)
		(size 0.508)
		(drill 0.254)
		(layers "F.Cu" "B.Cu")
		(net "MEMA_6")
	)
	(via
		(at 18.034508 -137.761472)
		(size 0.508)
		(drill 0.254)
		(layers "F.Cu" "B.Cu")
		(net "MEMA_6")
	)
	(segment
		(start 17.60728 -138.1887)
		(end 14.806168 -138.1887)
		(width 0.127)
		(layer "B.Cu")
		(net "MEMA_6")
	)
	(segment
		(start 14.105382 -139.994132)
		(end 14.105382 -138.999722)
		(width 0.127)
		(layer "B.Cu")
		(net "MEMA_6")
	)
	(segment
		(start 14.244066 -140.132816)
		(end 14.105382 -139.994132)
		(width 0.127)
		(layer "B.Cu")
		(net "MEMA_6")
	)
	(segment
		(start 13.978382 -138.872722)
		(end 11.975846 -138.872722)
		(width 0.127)
		(layer "B.Cu")
		(net "MEMA_6")
	)
	(segment
		(start 14.806168 -138.1887)
		(end 14.613382 -138.381486)
		(width 0.127)
		(layer "B.Cu")
		(net "MEMA_6")
	)
	(segment
		(start 11.975846 -138.872722)
		(end 11.647424 -138.5443)
		(width 0.127)
		(layer "B.Cu")
		(net "MEMA_6")
	)
	(segment
		(start 14.613382 -138.381486)
		(end 14.613382 -140.0175)
		(width 0.127)
		(layer "B.Cu")
		(net "MEMA_6")
	)
	(segment
		(start 14.498066 -140.132816)
		(end 14.244066 -140.132816)
		(width 0.127)
		(layer "B.Cu")
		(net "MEMA_6")
	)
	(segment
		(start 11.647424 -138.5443)
		(end 11.647424 -138.144504)
		(width 0.127)
		(layer "B.Cu")
		(net "MEMA_6")
	)
	(segment
		(start 18.034508 -137.761472)
		(end 17.60728 -138.1887)
		(width 0.127)
		(layer "B.Cu")
		(net "MEMA_6")
	)
	(segment
		(start 10.644632 -138.145774)
		(end 11.646154 -138.145774)
		(width 0.127)
		(layer "B.Cu")
		(net "MEMA_6")
	)
	(segment
		(start 11.646154 -138.145774)
		(end 11.647424 -138.144504)
		(width 0.127)
		(layer "B.Cu")
		(net "MEMA_6")
	)
	(segment
		(start 14.105382 -138.999722)
		(end 13.978382 -138.872722)
		(width 0.127)
		(layer "B.Cu")
		(net "MEMA_6")
	)
	(segment
		(start 14.613382 -140.0175)
		(end 14.498066 -140.132816)
		(width 0.127)
		(layer "B.Cu")
		(net "MEMA_6")
	)
	(segment
		(start 26.853388 -135.375396)
		(end 26.853388 -135.85698)
		(width 0.127)
		(layer "In5.Cu")
		(net "MEMA_6")
	)
	(segment
		(start 25.837388 -135.375396)
		(end 25.837388 -135.85698)
		(width 0.127)
		(layer "In5.Cu")
		(net "MEMA_6")
	)
	(segment
		(start 26.853388 -135.85698)
		(end 26.726388 -135.98398)
		(width 0.127)
		(layer "In5.Cu")
		(net "MEMA_6")
	)
	(segment
		(start 30.199076 -136.817608)
		(end 29.338778 -136.817608)
		(width 0.127)
		(layer "In5.Cu")
		(net "MEMA_6")
	)
	(segment
		(start 32.2072 -137.61466)
		(end 30.996128 -137.61466)
		(width 0.127)
		(layer "In5.Cu")
		(net "MEMA_6")
	)
	(segment
		(start 25.329388 -135.85698)
		(end 25.329388 -135.375396)
		(width 0.127)
		(layer "In5.Cu")
		(net "MEMA_6")
	)
	(segment
		(start 21.013674 -135.248396)
		(end 18.996406 -137.265664)
		(width 0.127)
		(layer "In5.Cu")
		(net "MEMA_6")
	)
	(segment
		(start 27.769566 -135.248396)
		(end 26.980388 -135.248396)
		(width 0.127)
		(layer "In5.Cu")
		(net "MEMA_6")
	)
	(segment
		(start 25.456388 -135.98398)
		(end 25.329388 -135.85698)
		(width 0.127)
		(layer "In5.Cu")
		(net "MEMA_6")
	)
	(segment
		(start 29.338778 -136.817608)
		(end 27.769566 -135.248396)
		(width 0.127)
		(layer "In5.Cu")
		(net "MEMA_6")
	)
	(segment
		(start 18.996406 -137.265664)
		(end 18.530316 -137.265664)
		(width 0.127)
		(layer "In5.Cu")
		(net "MEMA_6")
	)
	(segment
		(start 26.726388 -135.98398)
		(end 26.472388 -135.98398)
		(width 0.127)
		(layer "In5.Cu")
		(net "MEMA_6")
	)
	(segment
		(start 32.3342 -137.74166)
		(end 32.2072 -137.61466)
		(width 0.127)
		(layer "In5.Cu")
		(net "MEMA_6")
	)
	(segment
		(start 26.218388 -135.248396)
		(end 25.964388 -135.248396)
		(width 0.127)
		(layer "In5.Cu")
		(net "MEMA_6")
	)
	(segment
		(start 25.202388 -135.248396)
		(end 21.013674 -135.248396)
		(width 0.127)
		(layer "In5.Cu")
		(net "MEMA_6")
	)
	(segment
		(start 25.710388 -135.98398)
		(end 25.456388 -135.98398)
		(width 0.127)
		(layer "In5.Cu")
		(net "MEMA_6")
	)
	(segment
		(start 25.837388 -135.85698)
		(end 25.710388 -135.98398)
		(width 0.127)
		(layer "In5.Cu")
		(net "MEMA_6")
	)
	(segment
		(start 30.996128 -137.61466)
		(end 30.199076 -136.817608)
		(width 0.127)
		(layer "In5.Cu")
		(net "MEMA_6")
	)
	(segment
		(start 26.345388 -135.375396)
		(end 26.218388 -135.248396)
		(width 0.127)
		(layer "In5.Cu")
		(net "MEMA_6")
	)
	(segment
		(start 18.530316 -137.265664)
		(end 18.034508 -137.761472)
		(width 0.127)
		(layer "In5.Cu")
		(net "MEMA_6")
	)
	(segment
		(start 26.345388 -135.85698)
		(end 26.345388 -135.375396)
		(width 0.127)
		(layer "In5.Cu")
		(net "MEMA_6")
	)
	(segment
		(start 26.472388 -135.98398)
		(end 26.345388 -135.85698)
		(width 0.127)
		(layer "In5.Cu")
		(net "MEMA_6")
	)
	(segment
		(start 25.329388 -135.375396)
		(end 25.202388 -135.248396)
		(width 0.127)
		(layer "In5.Cu")
		(net "MEMA_6")
	)
	(segment
		(start 32.3342 -137.9728)
		(end 32.3342 -137.74166)
		(width 0.127)
		(layer "In5.Cu")
		(net "MEMA_6")
	)
	(segment
		(start 26.980388 -135.248396)
		(end 26.853388 -135.375396)
		(width 0.127)
		(layer "In5.Cu")
		(net "MEMA_6")
	)
	(segment
		(start 25.964388 -135.248396)
		(end 25.837388 -135.375396)
		(width 0.127)
		(layer "In5.Cu")
		(net "MEMA_6")
	)
	(segment
		(start 42.900092 -141.800072)
		(end 42.500296 -142.199868)
		(width 0.127)
		(layer "F.Cu")
		(net "MEMA_5")
	)
	(segment
		(start 22.43455 -138.161776)
		(end 22.834346 -138.561572)
		(width 0.127)
		(layer "F.Cu")
		(net "MEMA_5")
	)
	(segment
		(start 22.43455 -138.161522)
		(end 22.43455 -138.161776)
		(width 0.127)
		(layer "F.Cu")
		(net "MEMA_5")
	)
	(segment
		(start 42.500296 -142.199868)
		(end 42.500042 -142.199868)
		(width 0.127)
		(layer "F.Cu")
		(net "MEMA_5")
	)
	(via
		(at 42.900092 -141.800072)
		(size 0.4572)
		(drill 0.2032)
		(layers "F.Cu" "B.Cu")
		(net "MEMA_5")
	)
	(via
		(at 22.834346 -138.561572)
		(size 0.508)
		(drill 0.254)
		(layers "F.Cu" "B.Cu")
		(net "MEMA_5")
	)
	(segment
		(start 25.159462 -130.753358)
		(end 25.88006 -131.473956)
		(width 0.127)
		(layer "B.Cu")
		(net "MEMA_5")
	)
	(segment
		(start 22.834346 -137.820654)
		(end 22.834346 -138.561572)
		(width 0.127)
		(layer "B.Cu")
		(net "MEMA_5")
	)
	(segment
		(start 24.869902 -130.562858)
		(end 25.060402 -130.753358)
		(width 0.127)
		(layer "B.Cu")
		(net "MEMA_5")
	)
	(segment
		(start 25.88006 -131.473956)
		(end 25.88006 -134.638288)
		(width 0.127)
		(layer "B.Cu")
		(net "MEMA_5")
	)
	(segment
		(start 23.9395 -135.466328)
		(end 23.9395 -136.7155)
		(width 0.127)
		(layer "B.Cu")
		(net "MEMA_5")
	)
	(segment
		(start 25.060402 -130.753358)
		(end 25.159462 -130.753358)
		(width 0.127)
		(layer "B.Cu")
		(net "MEMA_5")
	)
	(segment
		(start 24.869902 -130.562858)
		(end 24.869902 -129.556002)
		(width 0.127)
		(layer "B.Cu")
		(net "MEMA_5")
	)
	(segment
		(start 25.88006 -134.638288)
		(end 25.485598 -135.03275)
		(width 0.127)
		(layer "B.Cu")
		(net "MEMA_5")
	)
	(segment
		(start 25.485598 -135.03275)
		(end 24.373078 -135.03275)
		(width 0.127)
		(layer "B.Cu")
		(net "MEMA_5")
	)
	(segment
		(start 24.869902 -129.556002)
		(end 24.8666 -129.5527)
		(width 0.127)
		(layer "B.Cu")
		(net "MEMA_5")
	)
	(segment
		(start 24.373078 -135.03275)
		(end 23.9395 -135.466328)
		(width 0.127)
		(layer "B.Cu")
		(net "MEMA_5")
	)
	(segment
		(start 23.9395 -136.7155)
		(end 22.834346 -137.820654)
		(width 0.127)
		(layer "B.Cu")
		(net "MEMA_5")
	)
	(segment
		(start 27.070558 -138.434318)
		(end 29.18968 -140.55344)
		(width 0.127)
		(layer "In2.Cu")
		(net "MEMA_5")
	)
	(segment
		(start 22.834346 -138.561572)
		(end 23.081996 -138.313922)
		(width 0.127)
		(layer "In2.Cu")
		(net "MEMA_5")
	)
	(segment
		(start 34.989516 -140.14069)
		(end 35.116516 -140.26769)
		(width 0.127)
		(layer "In2.Cu")
		(net "MEMA_5")
	)
	(segment
		(start 36.005516 -140.14069)
		(end 36.132516 -140.26769)
		(width 0.127)
		(layer "In2.Cu")
		(net "MEMA_5")
	)
	(segment
		(start 34.481516 -140.14069)
		(end 34.481516 -139.56792)
		(width 0.127)
		(layer "In2.Cu")
		(net "MEMA_5")
	)
	(segment
		(start 37.148516 -140.26769)
		(end 38.725856 -140.26769)
		(width 0.127)
		(layer "In2.Cu")
		(net "MEMA_5")
	)
	(segment
		(start 32.449516 -139.74572)
		(end 32.576516 -139.61872)
		(width 0.127)
		(layer "In2.Cu")
		(net "MEMA_5")
	)
	(segment
		(start 35.497516 -139.44092)
		(end 35.624516 -139.31392)
		(width 0.127)
		(layer "In2.Cu")
		(net "MEMA_5")
	)
	(segment
		(start 38.725856 -140.26769)
		(end 40.249348 -141.791182)
		(width 0.127)
		(layer "In2.Cu")
		(net "MEMA_5")
	)
	(segment
		(start 24.456644 -138.434318)
		(end 27.070558 -138.434318)
		(width 0.127)
		(layer "In2.Cu")
		(net "MEMA_5")
	)
	(segment
		(start 32.576516 -139.61872)
		(end 32.830516 -139.61872)
		(width 0.127)
		(layer "In2.Cu")
		(net "MEMA_5")
	)
	(segment
		(start 34.354516 -140.26769)
		(end 34.481516 -140.14069)
		(width 0.127)
		(layer "In2.Cu")
		(net "MEMA_5")
	)
	(segment
		(start 24.336248 -138.313922)
		(end 24.456644 -138.434318)
		(width 0.127)
		(layer "In2.Cu")
		(net "MEMA_5")
	)
	(segment
		(start 40.249348 -141.791182)
		(end 40.706548 -141.791182)
		(width 0.127)
		(layer "In2.Cu")
		(net "MEMA_5")
	)
	(segment
		(start 29.18968 -140.55344)
		(end 31.60903 -140.55344)
		(width 0.127)
		(layer "In2.Cu")
		(net "MEMA_5")
	)
	(segment
		(start 32.322516 -140.26769)
		(end 32.449516 -140.14069)
		(width 0.127)
		(layer "In2.Cu")
		(net "MEMA_5")
	)
	(segment
		(start 35.624516 -139.31392)
		(end 35.878516 -139.31392)
		(width 0.127)
		(layer "In2.Cu")
		(net "MEMA_5")
	)
	(segment
		(start 36.513516 -140.14069)
		(end 36.513516 -139.39012)
		(width 0.127)
		(layer "In2.Cu")
		(net "MEMA_5")
	)
	(segment
		(start 33.973516 -140.14069)
		(end 34.100516 -140.26769)
		(width 0.127)
		(layer "In2.Cu")
		(net "MEMA_5")
	)
	(segment
		(start 31.60903 -140.55344)
		(end 31.89478 -140.26769)
		(width 0.127)
		(layer "In2.Cu")
		(net "MEMA_5")
	)
	(segment
		(start 33.084516 -140.26769)
		(end 33.338516 -140.26769)
		(width 0.127)
		(layer "In2.Cu")
		(net "MEMA_5")
	)
	(segment
		(start 32.830516 -139.61872)
		(end 32.957516 -139.74572)
		(width 0.127)
		(layer "In2.Cu")
		(net "MEMA_5")
	)
	(segment
		(start 31.89478 -140.26769)
		(end 32.322516 -140.26769)
		(width 0.127)
		(layer "In2.Cu")
		(net "MEMA_5")
	)
	(segment
		(start 34.100516 -140.26769)
		(end 34.354516 -140.26769)
		(width 0.127)
		(layer "In2.Cu")
		(net "MEMA_5")
	)
	(segment
		(start 41.109138 -142.193772)
		(end 42.506392 -142.193772)
		(width 0.127)
		(layer "In2.Cu")
		(net "MEMA_5")
	)
	(segment
		(start 32.449516 -140.14069)
		(end 32.449516 -139.74572)
		(width 0.127)
		(layer "In2.Cu")
		(net "MEMA_5")
	)
	(segment
		(start 34.481516 -139.56792)
		(end 34.608516 -139.44092)
		(width 0.127)
		(layer "In2.Cu")
		(net "MEMA_5")
	)
	(segment
		(start 36.386516 -140.26769)
		(end 36.513516 -140.14069)
		(width 0.127)
		(layer "In2.Cu")
		(net "MEMA_5")
	)
	(segment
		(start 35.116516 -140.26769)
		(end 35.370516 -140.26769)
		(width 0.127)
		(layer "In2.Cu")
		(net "MEMA_5")
	)
	(segment
		(start 36.005516 -139.44092)
		(end 36.005516 -140.14069)
		(width 0.127)
		(layer "In2.Cu")
		(net "MEMA_5")
	)
	(segment
		(start 35.878516 -139.31392)
		(end 36.005516 -139.44092)
		(width 0.127)
		(layer "In2.Cu")
		(net "MEMA_5")
	)
	(segment
		(start 34.989516 -139.56792)
		(end 34.989516 -140.14069)
		(width 0.127)
		(layer "In2.Cu")
		(net "MEMA_5")
	)
	(segment
		(start 33.338516 -140.26769)
		(end 33.465516 -140.14069)
		(width 0.127)
		(layer "In2.Cu")
		(net "MEMA_5")
	)
	(segment
		(start 33.592516 -139.61872)
		(end 33.846516 -139.61872)
		(width 0.127)
		(layer "In2.Cu")
		(net "MEMA_5")
	)
	(segment
		(start 42.506392 -142.193772)
		(end 42.900092 -141.800072)
		(width 0.127)
		(layer "In2.Cu")
		(net "MEMA_5")
	)
	(segment
		(start 32.957516 -139.74572)
		(end 32.957516 -140.14069)
		(width 0.127)
		(layer "In2.Cu")
		(net "MEMA_5")
	)
	(segment
		(start 36.132516 -140.26769)
		(end 36.386516 -140.26769)
		(width 0.127)
		(layer "In2.Cu")
		(net "MEMA_5")
	)
	(segment
		(start 33.973516 -139.74572)
		(end 33.973516 -140.14069)
		(width 0.127)
		(layer "In2.Cu")
		(net "MEMA_5")
	)
	(segment
		(start 35.370516 -140.26769)
		(end 35.497516 -140.14069)
		(width 0.127)
		(layer "In2.Cu")
		(net "MEMA_5")
	)
	(segment
		(start 37.021516 -139.39012)
		(end 37.021516 -140.14069)
		(width 0.127)
		(layer "In2.Cu")
		(net "MEMA_5")
	)
	(segment
		(start 40.706548 -141.791182)
		(end 41.109138 -142.193772)
		(width 0.127)
		(layer "In2.Cu")
		(net "MEMA_5")
	)
	(segment
		(start 33.465516 -139.74572)
		(end 33.592516 -139.61872)
		(width 0.127)
		(layer "In2.Cu")
		(net "MEMA_5")
	)
	(segment
		(start 34.862516 -139.44092)
		(end 34.989516 -139.56792)
		(width 0.127)
		(layer "In2.Cu")
		(net "MEMA_5")
	)
	(segment
		(start 32.957516 -140.14069)
		(end 33.084516 -140.26769)
		(width 0.127)
		(layer "In2.Cu")
		(net "MEMA_5")
	)
	(segment
		(start 35.497516 -140.14069)
		(end 35.497516 -139.44092)
		(width 0.127)
		(layer "In2.Cu")
		(net "MEMA_5")
	)
	(segment
		(start 23.081996 -138.313922)
		(end 24.336248 -138.313922)
		(width 0.127)
		(layer "In2.Cu")
		(net "MEMA_5")
	)
	(segment
		(start 37.021516 -140.14069)
		(end 37.148516 -140.26769)
		(width 0.127)
		(layer "In2.Cu")
		(net "MEMA_5")
	)
	(segment
		(start 33.846516 -139.61872)
		(end 33.973516 -139.74572)
		(width 0.127)
		(layer "In2.Cu")
		(net "MEMA_5")
	)
	(segment
		(start 36.640516 -139.26312)
		(end 36.894516 -139.26312)
		(width 0.127)
		(layer "In2.Cu")
		(net "MEMA_5")
	)
	(segment
		(start 36.513516 -139.39012)
		(end 36.640516 -139.26312)
		(width 0.127)
		(layer "In2.Cu")
		(net "MEMA_5")
	)
	(segment
		(start 33.465516 -140.14069)
		(end 33.465516 -139.74572)
		(width 0.127)
		(layer "In2.Cu")
		(net "MEMA_5")
	)
	(segment
		(start 36.894516 -139.26312)
		(end 37.021516 -139.39012)
		(width 0.127)
		(layer "In2.Cu")
		(net "MEMA_5")
	)
	(segment
		(start 34.608516 -139.44092)
		(end 34.862516 -139.44092)
		(width 0.127)
		(layer "In2.Cu")
		(net "MEMA_5")
	)
	(segment
		(start 18.473674 -139.000738)
		(end 19.07413 -139.000738)
		(width 0.127)
		(layer "F.Cu")
		(net "MEMA_4")
	)
	(segment
		(start 41.699688 -142.199868)
		(end 41.699942 -142.199868)
		(width 0.127)
		(layer "F.Cu")
		(net "MEMA_4")
	)
	(segment
		(start 41.299892 -141.800072)
		(end 41.699688 -142.199868)
		(width 0.127)
		(layer "F.Cu")
		(net "MEMA_4")
	)
	(segment
		(start 19.07413 -139.000738)
		(end 19.26844 -138.806428)
		(width 0.127)
		(layer "F.Cu")
		(net "MEMA_4")
	)
	(segment
		(start 19.26844 -137.8077)
		(end 19.179032 -137.718292)
		(width 0.127)
		(layer "F.Cu")
		(net "MEMA_4")
	)
	(segment
		(start 19.26844 -138.806428)
		(end 19.26844 -137.8077)
		(width 0.127)
		(layer "F.Cu")
		(net "MEMA_4")
	)
	(segment
		(start 18.434558 -138.961622)
		(end 18.473674 -139.000738)
		(width 0.127)
		(layer "F.Cu")
		(net "MEMA_4")
	)
	(via
		(at 41.299892 -141.800072)
		(size 0.4572)
		(drill 0.2032)
		(layers "F.Cu" "B.Cu")
		(net "MEMA_4")
	)
	(via
		(at 19.179032 -137.718292)
		(size 0.508)
		(drill 0.254)
		(layers "F.Cu" "B.Cu")
		(net "MEMA_4")
	)
	(segment
		(start 14.898624 -133.890512)
		(end 15.025624 -133.763512)
		(width 0.127)
		(layer "B.Cu")
		(net "MEMA_4")
	)
	(segment
		(start 11.647424 -134.075424)
		(end 12.12723 -134.55523)
		(width 0.127)
		(layer "B.Cu")
		(net "MEMA_4")
	)
	(segment
		(start 16.21663 -134.55523)
		(end 18.203926 -136.542526)
		(width 0.127)
		(layer "B.Cu")
		(net "MEMA_4")
	)
	(segment
		(start 10.64895 -133.85673)
		(end 11.647424 -133.85673)
		(width 0.127)
		(layer "B.Cu")
		(net "MEMA_4")
	)
	(segment
		(start 15.406624 -134.42823)
		(end 15.533624 -134.55523)
		(width 0.127)
		(layer "B.Cu")
		(net "MEMA_4")
	)
	(segment
		(start 18.453608 -136.792208)
		(end 19.179032 -137.517632)
		(width 0.127)
		(layer "B.Cu")
		(net "MEMA_4")
	)
	(segment
		(start 18.203926 -136.542526)
		(end 18.208244 -136.542526)
		(width 0.127)
		(layer "B.Cu")
		(net "MEMA_4")
	)
	(segment
		(start 11.647424 -133.85673)
		(end 11.647424 -134.075424)
		(width 0.127)
		(layer "B.Cu")
		(net "MEMA_4")
	)
	(segment
		(start 15.406624 -133.890512)
		(end 15.406624 -134.42823)
		(width 0.127)
		(layer "B.Cu")
		(net "MEMA_4")
	)
	(segment
		(start 15.533624 -134.55523)
		(end 16.21663 -134.55523)
		(width 0.127)
		(layer "B.Cu")
		(net "MEMA_4")
	)
	(segment
		(start 12.12723 -134.55523)
		(end 14.771624 -134.55523)
		(width 0.127)
		(layer "B.Cu")
		(net "MEMA_4")
	)
	(segment
		(start 19.179032 -137.517632)
		(end 19.179032 -137.718292)
		(width 0.127)
		(layer "B.Cu")
		(net "MEMA_4")
	)
	(segment
		(start 15.279624 -133.763512)
		(end 15.406624 -133.890512)
		(width 0.127)
		(layer "B.Cu")
		(net "MEMA_4")
	)
	(segment
		(start 18.453608 -136.78789)
		(end 18.453608 -136.792208)
		(width 0.127)
		(layer "B.Cu")
		(net "MEMA_4")
	)
	(segment
		(start 14.898624 -134.42823)
		(end 14.898624 -133.890512)
		(width 0.127)
		(layer "B.Cu")
		(net "MEMA_4")
	)
	(segment
		(start 15.025624 -133.763512)
		(end 15.279624 -133.763512)
		(width 0.127)
		(layer "B.Cu")
		(net "MEMA_4")
	)
	(segment
		(start 14.771624 -134.55523)
		(end 14.898624 -134.42823)
		(width 0.127)
		(layer "B.Cu")
		(net "MEMA_4")
	)
	(segment
		(start 18.208244 -136.542526)
		(end 18.453608 -136.78789)
		(width 0.127)
		(layer "B.Cu")
		(net "MEMA_4")
	)
	(segment
		(start 19.179032 -137.718292)
		(end 19.179032 -137.516108)
		(width 0.127)
		(layer "In5.Cu")
		(net "MEMA_4")
	)
	(segment
		(start 23.766018 -135.629142)
		(end 24.666956 -136.53008)
		(width 0.127)
		(layer "In5.Cu")
		(net "MEMA_4")
	)
	(segment
		(start 22.488398 -135.756142)
		(end 22.488398 -136.12368)
		(width 0.127)
		(layer "In5.Cu")
		(net "MEMA_4")
	)
	(segment
		(start 21.472398 -135.756142)
		(end 21.472398 -136.12368)
		(width 0.127)
		(layer "In5.Cu")
		(net "MEMA_4")
	)
	(segment
		(start 21.980398 -136.12368)
		(end 21.980398 -135.756142)
		(width 0.127)
		(layer "In5.Cu")
		(net "MEMA_4")
	)
	(segment
		(start 28.332684 -136.53008)
		(end 29.508704 -137.7061)
		(width 0.127)
		(layer "In5.Cu")
		(net "MEMA_4")
	)
	(segment
		(start 21.599398 -136.25068)
		(end 21.853398 -136.25068)
		(width 0.127)
		(layer "In5.Cu")
		(net "MEMA_4")
	)
	(segment
		(start 41.054782 -141.554962)
		(end 41.299892 -141.800072)
		(width 0.127)
		(layer "In5.Cu")
		(net "MEMA_4")
	)
	(segment
		(start 38.411658 -139.521692)
		(end 40.097202 -141.207236)
		(width 0.127)
		(layer "In5.Cu")
		(net "MEMA_4")
	)
	(segment
		(start 22.996398 -136.12368)
		(end 22.996398 -135.756142)
		(width 0.127)
		(layer "In5.Cu")
		(net "MEMA_4")
	)
	(segment
		(start 22.361398 -135.629142)
		(end 22.488398 -135.756142)
		(width 0.127)
		(layer "In5.Cu")
		(net "MEMA_4")
	)
	(segment
		(start 21.065998 -135.629142)
		(end 21.345398 -135.629142)
		(width 0.127)
		(layer "In5.Cu")
		(net "MEMA_4")
	)
	(segment
		(start 21.472398 -136.12368)
		(end 21.599398 -136.25068)
		(width 0.127)
		(layer "In5.Cu")
		(net "MEMA_4")
	)
	(segment
		(start 29.508704 -137.7061)
		(end 30.369002 -137.7061)
		(width 0.127)
		(layer "In5.Cu")
		(net "MEMA_4")
	)
	(segment
		(start 22.615398 -136.25068)
		(end 22.869398 -136.25068)
		(width 0.127)
		(layer "In5.Cu")
		(net "MEMA_4")
	)
	(segment
		(start 19.179032 -137.516108)
		(end 21.065998 -135.629142)
		(width 0.127)
		(layer "In5.Cu")
		(net "MEMA_4")
	)
	(segment
		(start 21.980398 -135.756142)
		(end 22.107398 -135.629142)
		(width 0.127)
		(layer "In5.Cu")
		(net "MEMA_4")
	)
	(segment
		(start 21.345398 -135.629142)
		(end 21.472398 -135.756142)
		(width 0.127)
		(layer "In5.Cu")
		(net "MEMA_4")
	)
	(segment
		(start 23.123398 -135.629142)
		(end 23.766018 -135.629142)
		(width 0.127)
		(layer "In5.Cu")
		(net "MEMA_4")
	)
	(segment
		(start 31.575502 -138.9126)
		(end 32.420306 -138.9126)
		(width 0.127)
		(layer "In5.Cu")
		(net "MEMA_4")
	)
	(segment
		(start 30.369002 -137.7061)
		(end 31.575502 -138.9126)
		(width 0.127)
		(layer "In5.Cu")
		(net "MEMA_4")
	)
	(segment
		(start 22.996398 -135.756142)
		(end 23.123398 -135.629142)
		(width 0.127)
		(layer "In5.Cu")
		(net "MEMA_4")
	)
	(segment
		(start 33.029398 -139.521692)
		(end 38.411658 -139.521692)
		(width 0.127)
		(layer "In5.Cu")
		(net "MEMA_4")
	)
	(segment
		(start 22.869398 -136.25068)
		(end 22.996398 -136.12368)
		(width 0.127)
		(layer "In5.Cu")
		(net "MEMA_4")
	)
	(segment
		(start 22.107398 -135.629142)
		(end 22.361398 -135.629142)
		(width 0.127)
		(layer "In5.Cu")
		(net "MEMA_4")
	)
	(segment
		(start 24.666956 -136.53008)
		(end 28.332684 -136.53008)
		(width 0.127)
		(layer "In5.Cu")
		(net "MEMA_4")
	)
	(segment
		(start 32.420306 -138.9126)
		(end 33.029398 -139.521692)
		(width 0.127)
		(layer "In5.Cu")
		(net "MEMA_4")
	)
	(segment
		(start 22.488398 -136.12368)
		(end 22.615398 -136.25068)
		(width 0.127)
		(layer "In5.Cu")
		(net "MEMA_4")
	)
	(segment
		(start 21.853398 -136.25068)
		(end 21.980398 -136.12368)
		(width 0.127)
		(layer "In5.Cu")
		(net "MEMA_4")
	)
	(arc
		(start 40.097202 -141.207236)
		(mid 40.339618 -141.385575)
		(end 40.63873 -141.418564)
		(width 0.127)
		(layer "In5.Cu")
		(net "MEMA_4")
	)
	(arc
		(start 40.63873 -141.418564)
		(mid 40.863055 -141.43707)
		(end 41.054782 -141.554962)
		(width 0.127)
		(layer "In5.Cu")
		(net "MEMA_4")
	)
	(segment
		(start 21.2344 -138.561572)
		(end 21.63445 -138.961622)
		(width 0.127)
		(layer "F.Cu")
		(net "MEMA_3")
	)
	(segment
		(start 43.299888 -142.999968)
		(end 43.699938 -142.599918)
		(width 0.127)
		(layer "F.Cu")
		(net "MEMA_3")
	)
	(via
		(at 21.2344 -138.561572)
		(size 0.508)
		(drill 0.254)
		(layers "F.Cu" "B.Cu")
		(net "MEMA_3")
	)
	(via
		(at 43.699938 -142.599918)
		(size 0.4572)
		(drill 0.2032)
		(layers "F.Cu" "B.Cu")
		(net "MEMA_3")
	)
	(segment
		(start 19.325844 -134.364984)
		(end 19.084036 -134.364984)
		(width 0.127)
		(layer "B.Cu")
		(net "MEMA_3")
	)
	(segment
		(start 19.685 -137.012172)
		(end 21.2344 -138.561572)
		(width 0.127)
		(layer "B.Cu")
		(net "MEMA_3")
	)
	(segment
		(start 17.723612 -130.562858)
		(end 17.914112 -130.753358)
		(width 0.127)
		(layer "B.Cu")
		(net "MEMA_3")
	)
	(segment
		(start 18.013172 -130.753358)
		(end 18.422112 -131.162298)
		(width 0.127)
		(layer "B.Cu")
		(net "MEMA_3")
	)
	(segment
		(start 19.325844 -134.872984)
		(end 19.452844 -134.999984)
		(width 0.127)
		(layer "B.Cu")
		(net "MEMA_3")
	)
	(segment
		(start 19.084036 -134.872984)
		(end 19.325844 -134.872984)
		(width 0.127)
		(layer "B.Cu")
		(net "MEMA_3")
	)
	(segment
		(start 17.723612 -129.521458)
		(end 17.749012 -129.496058)
		(width 0.127)
		(layer "B.Cu")
		(net "MEMA_3")
	)
	(segment
		(start 18.422112 -132.72516)
		(end 19.452844 -133.755892)
		(width 0.127)
		(layer "B.Cu")
		(net "MEMA_3")
	)
	(segment
		(start 19.452844 -134.999984)
		(end 19.452844 -135.30326)
		(width 0.127)
		(layer "B.Cu")
		(net "MEMA_3")
	)
	(segment
		(start 19.452844 -135.30326)
		(end 19.685 -135.535416)
		(width 0.127)
		(layer "B.Cu")
		(net "MEMA_3")
	)
	(segment
		(start 19.452844 -134.237984)
		(end 19.325844 -134.364984)
		(width 0.127)
		(layer "B.Cu")
		(net "MEMA_3")
	)
	(segment
		(start 18.422112 -131.162298)
		(end 18.422112 -132.72516)
		(width 0.127)
		(layer "B.Cu")
		(net "MEMA_3")
	)
	(segment
		(start 17.914112 -130.753358)
		(end 18.013172 -130.753358)
		(width 0.127)
		(layer "B.Cu")
		(net "MEMA_3")
	)
	(segment
		(start 17.723612 -130.562858)
		(end 17.723612 -129.521458)
		(width 0.127)
		(layer "B.Cu")
		(net "MEMA_3")
	)
	(segment
		(start 19.685 -135.535416)
		(end 19.685 -137.012172)
		(width 0.127)
		(layer "B.Cu")
		(net "MEMA_3")
	)
	(segment
		(start 19.084036 -134.364984)
		(end 18.957036 -134.491984)
		(width 0.127)
		(layer "B.Cu")
		(net "MEMA_3")
	)
	(segment
		(start 18.957036 -134.745984)
		(end 19.084036 -134.872984)
		(width 0.127)
		(layer "B.Cu")
		(net "MEMA_3")
	)
	(segment
		(start 18.957036 -134.491984)
		(end 18.957036 -134.745984)
		(width 0.127)
		(layer "B.Cu")
		(net "MEMA_3")
	)
	(segment
		(start 19.452844 -133.755892)
		(end 19.452844 -134.237984)
		(width 0.127)
		(layer "B.Cu")
		(net "MEMA_3")
	)
	(segment
		(start 32.554672 -142.091918)
		(end 32.427672 -141.964918)
		(width 0.127)
		(layer "In2.Cu")
		(net "MEMA_3")
	)
	(segment
		(start 43.699938 -142.599918)
		(end 43.306238 -142.993618)
		(width 0.127)
		(layer "In2.Cu")
		(net "MEMA_3")
	)
	(segment
		(start 40.906192 -142.449042)
		(end 40.650668 -142.193518)
		(width 0.127)
		(layer "In2.Cu")
		(net "MEMA_3")
	)
	(segment
		(start 39.09568 -141.992858)
		(end 39.09568 -141.41196)
		(width 0.127)
		(layer "In2.Cu")
		(net "MEMA_3")
	)
	(segment
		(start 32.427672 -141.964918)
		(end 32.427672 -141.4907)
		(width 0.127)
		(layer "In2.Cu")
		(net "MEMA_3")
	)
	(segment
		(start 33.443672 -140.95984)
		(end 33.316672 -140.83284)
		(width 0.127)
		(layer "In2.Cu")
		(net "MEMA_3")
	)
	(segment
		(start 39.09568 -141.41196)
		(end 38.48354 -140.79982)
		(width 0.127)
		(layer "In2.Cu")
		(net "MEMA_3")
	)
	(segment
		(start 43.306238 -142.993618)
		(end 41.13657 -142.993618)
		(width 0.127)
		(layer "In2.Cu")
		(net "MEMA_3")
	)
	(segment
		(start 40.906192 -142.76324)
		(end 40.906192 -142.449042)
		(width 0.127)
		(layer "In2.Cu")
		(net "MEMA_3")
	)
	(segment
		(start 29.899102 -141.822678)
		(end 28.848812 -141.822678)
		(width 0.127)
		(layer "In2.Cu")
		(net "MEMA_3")
	)
	(segment
		(start 34.13506 -140.92682)
		(end 34.13506 -141.95044)
		(width 0.127)
		(layer "In2.Cu")
		(net "MEMA_3")
	)
	(segment
		(start 24.356568 -139.380722)
		(end 22.05355 -139.380722)
		(width 0.127)
		(layer "In2.Cu")
		(net "MEMA_3")
	)
	(segment
		(start 31.919672 -141.4907)
		(end 31.919672 -141.964918)
		(width 0.127)
		(layer "In2.Cu")
		(net "MEMA_3")
	)
	(segment
		(start 26.471372 -140.04163)
		(end 25.88006 -139.450318)
		(width 0.127)
		(layer "In2.Cu")
		(net "MEMA_3")
	)
	(segment
		(start 31.792672 -142.091918)
		(end 30.168342 -142.091918)
		(width 0.127)
		(layer "In2.Cu")
		(net "MEMA_3")
	)
	(segment
		(start 32.427672 -141.4907)
		(end 32.300672 -141.3637)
		(width 0.127)
		(layer "In2.Cu")
		(net "MEMA_3")
	)
	(segment
		(start 33.316672 -140.83284)
		(end 33.062672 -140.83284)
		(width 0.127)
		(layer "In2.Cu")
		(net "MEMA_3")
	)
	(segment
		(start 32.935672 -141.964918)
		(end 32.808672 -142.091918)
		(width 0.127)
		(layer "In2.Cu")
		(net "MEMA_3")
	)
	(segment
		(start 38.48354 -140.79982)
		(end 34.26206 -140.79982)
		(width 0.127)
		(layer "In2.Cu")
		(net "MEMA_3")
	)
	(segment
		(start 32.046672 -141.3637)
		(end 31.919672 -141.4907)
		(width 0.127)
		(layer "In2.Cu")
		(net "MEMA_3")
	)
	(segment
		(start 31.919672 -141.964918)
		(end 31.792672 -142.091918)
		(width 0.127)
		(layer "In2.Cu")
		(net "MEMA_3")
	)
	(segment
		(start 32.300672 -141.3637)
		(end 32.046672 -141.3637)
		(width 0.127)
		(layer "In2.Cu")
		(net "MEMA_3")
	)
	(segment
		(start 41.13657 -142.993618)
		(end 40.906192 -142.76324)
		(width 0.127)
		(layer "In2.Cu")
		(net "MEMA_3")
	)
	(segment
		(start 33.443672 -141.964918)
		(end 33.443672 -140.95984)
		(width 0.127)
		(layer "In2.Cu")
		(net "MEMA_3")
	)
	(segment
		(start 33.062672 -140.83284)
		(end 32.935672 -140.95984)
		(width 0.127)
		(layer "In2.Cu")
		(net "MEMA_3")
	)
	(segment
		(start 33.570672 -142.091918)
		(end 33.443672 -141.964918)
		(width 0.127)
		(layer "In2.Cu")
		(net "MEMA_3")
	)
	(segment
		(start 22.05355 -139.380722)
		(end 21.2344 -138.561572)
		(width 0.127)
		(layer "In2.Cu")
		(net "MEMA_3")
	)
	(segment
		(start 30.168342 -142.091918)
		(end 29.899102 -141.822678)
		(width 0.127)
		(layer "In2.Cu")
		(net "MEMA_3")
	)
	(segment
		(start 34.26206 -140.79982)
		(end 34.13506 -140.92682)
		(width 0.127)
		(layer "In2.Cu")
		(net "MEMA_3")
	)
	(segment
		(start 24.426164 -139.450318)
		(end 24.356568 -139.380722)
		(width 0.127)
		(layer "In2.Cu")
		(net "MEMA_3")
	)
	(segment
		(start 32.935672 -140.95984)
		(end 32.935672 -141.964918)
		(width 0.127)
		(layer "In2.Cu")
		(net "MEMA_3")
	)
	(segment
		(start 39.29634 -142.193518)
		(end 39.09568 -141.992858)
		(width 0.127)
		(layer "In2.Cu")
		(net "MEMA_3")
	)
	(segment
		(start 27.067764 -140.04163)
		(end 26.471372 -140.04163)
		(width 0.127)
		(layer "In2.Cu")
		(net "MEMA_3")
	)
	(segment
		(start 32.808672 -142.091918)
		(end 32.554672 -142.091918)
		(width 0.127)
		(layer "In2.Cu")
		(net "MEMA_3")
	)
	(segment
		(start 40.650668 -142.193518)
		(end 39.29634 -142.193518)
		(width 0.127)
		(layer "In2.Cu")
		(net "MEMA_3")
	)
	(segment
		(start 33.993582 -142.091918)
		(end 33.570672 -142.091918)
		(width 0.127)
		(layer "In2.Cu")
		(net "MEMA_3")
	)
	(segment
		(start 28.848812 -141.822678)
		(end 27.067764 -140.04163)
		(width 0.127)
		(layer "In2.Cu")
		(net "MEMA_3")
	)
	(segment
		(start 25.88006 -139.450318)
		(end 24.426164 -139.450318)
		(width 0.127)
		(layer "In2.Cu")
		(net "MEMA_3")
	)
	(segment
		(start 34.13506 -141.95044)
		(end 33.993582 -142.091918)
		(width 0.127)
		(layer "In2.Cu")
		(net "MEMA_3")
	)
	(segment
		(start 41.699942 -142.999968)
		(end 42.099992 -142.599918)
		(width 0.127)
		(layer "F.Cu")
		(net "MEMA_2")
	)
	(segment
		(start 18.815304 -136.98093)
		(end 18.815304 -136.135364)
		(width 0.127)
		(layer "F.Cu")
		(net "MEMA_2")
	)
	(segment
		(start 18.434558 -137.361676)
		(end 18.815304 -136.98093)
		(width 0.127)
		(layer "F.Cu")
		(net "MEMA_2")
	)
	(via
		(at 18.815304 -136.135364)
		(size 0.508)
		(drill 0.254)
		(layers "F.Cu" "B.Cu")
		(net "MEMA_2")
	)
	(via
		(at 42.099992 -142.599918)
		(size 0.4572)
		(drill 0.2032)
		(layers "F.Cu" "B.Cu")
		(net "MEMA_2")
	)
	(segment
		(start 12.304268 -133.15823)
		(end 14.538198 -133.15823)
		(width 0.127)
		(layer "B.Cu")
		(net "MEMA_2")
	)
	(segment
		(start 15.173198 -132.525516)
		(end 15.173198 -133.03123)
		(width 0.127)
		(layer "B.Cu")
		(net "MEMA_2")
	)
	(segment
		(start 14.665198 -132.525516)
		(end 14.792198 -132.398516)
		(width 0.127)
		(layer "B.Cu")
		(net "MEMA_2")
	)
	(segment
		(start 15.173198 -133.03123)
		(end 15.300198 -133.15823)
		(width 0.127)
		(layer "B.Cu")
		(net "MEMA_2")
	)
	(segment
		(start 11.647424 -132.402326)
		(end 11.647424 -132.501386)
		(width 0.127)
		(layer "B.Cu")
		(net "MEMA_2")
	)
	(segment
		(start 15.83817 -133.15823)
		(end 18.815304 -136.135364)
		(width 0.127)
		(layer "B.Cu")
		(net "MEMA_2")
	)
	(segment
		(start 10.638028 -132.402834)
		(end 11.646916 -132.402834)
		(width 0.127)
		(layer "B.Cu")
		(net "MEMA_2")
	)
	(segment
		(start 15.300198 -133.15823)
		(end 15.83817 -133.15823)
		(width 0.127)
		(layer "B.Cu")
		(net "MEMA_2")
	)
	(segment
		(start 11.647424 -132.501386)
		(end 12.304268 -133.15823)
		(width 0.127)
		(layer "B.Cu")
		(net "MEMA_2")
	)
	(segment
		(start 14.538198 -133.15823)
		(end 14.665198 -133.03123)
		(width 0.127)
		(layer "B.Cu")
		(net "MEMA_2")
	)
	(segment
		(start 14.665198 -133.03123)
		(end 14.665198 -132.525516)
		(width 0.127)
		(layer "B.Cu")
		(net "MEMA_2")
	)
	(segment
		(start 14.792198 -132.398516)
		(end 15.046198 -132.398516)
		(width 0.127)
		(layer "B.Cu")
		(net "MEMA_2")
	)
	(segment
		(start 15.046198 -132.398516)
		(end 15.173198 -132.525516)
		(width 0.127)
		(layer "B.Cu")
		(net "MEMA_2")
	)
	(segment
		(start 11.646916 -132.402834)
		(end 11.647424 -132.402326)
		(width 0.127)
		(layer "B.Cu")
		(net "MEMA_2")
	)
	(segment
		(start 41.680892 -141.629892)
		(end 41.680892 -142.010638)
		(width 0.1016)
		(layer "In5.Cu")
		(net "MEMA_2")
	)
	(segment
		(start 34.983674 -135.255)
		(end 35.980624 -136.25195)
		(width 0.127)
		(layer "In5.Cu")
		(net "MEMA_2")
	)
	(segment
		(start 35.985704 -136.25195)
		(end 40.10025 -140.366496)
		(width 0.127)
		(layer "In5.Cu")
		(net "MEMA_2")
	)
	(segment
		(start 35.980624 -136.25195)
		(end 35.985704 -136.25195)
		(width 0.127)
		(layer "In5.Cu")
		(net "MEMA_2")
	)
	(segment
		(start 18.815304 -136.135364)
		(end 18.815304 -136.009634)
		(width 0.127)
		(layer "In5.Cu")
		(net "MEMA_2")
	)
	(segment
		(start 21.100542 -133.724396)
		(end 28.401264 -133.724396)
		(width 0.127)
		(layer "In5.Cu")
		(net "MEMA_2")
	)
	(segment
		(start 41.680892 -142.010638)
		(end 42.099992 -142.429738)
		(width 0.1016)
		(layer "In5.Cu")
		(net "MEMA_2")
	)
	(segment
		(start 42.099992 -142.429738)
		(end 42.099992 -142.599918)
		(width 0.1016)
		(layer "In5.Cu")
		(net "MEMA_2")
	)
	(segment
		(start 41.681146 -141.629638)
		(end 41.680892 -141.629892)
		(width 0.1016)
		(layer "In5.Cu")
		(net "MEMA_2")
	)
	(segment
		(start 40.10025 -140.366496)
		(end 40.352726 -140.618972)
		(width 0.1016)
		(layer "In5.Cu")
		(net "MEMA_2")
	)
	(segment
		(start 18.815304 -136.009634)
		(end 21.100542 -133.724396)
		(width 0.127)
		(layer "In5.Cu")
		(net "MEMA_2")
	)
	(segment
		(start 28.401264 -133.724396)
		(end 29.931868 -135.255)
		(width 0.127)
		(layer "In5.Cu")
		(net "MEMA_2")
	)
	(segment
		(start 41.680638 -140.842238)
		(end 41.681146 -140.842746)
		(width 0.1016)
		(layer "In5.Cu")
		(net "MEMA_2")
	)
	(segment
		(start 41.680638 -140.841984)
		(end 41.680638 -140.842238)
		(width 0.1016)
		(layer "In5.Cu")
		(net "MEMA_2")
	)
	(segment
		(start 41.457626 -140.618972)
		(end 41.680638 -140.841984)
		(width 0.1016)
		(layer "In5.Cu")
		(net "MEMA_2")
	)
	(segment
		(start 41.681146 -140.842746)
		(end 41.681146 -141.629638)
		(width 0.1016)
		(layer "In5.Cu")
		(net "MEMA_2")
	)
	(segment
		(start 40.352726 -140.618972)
		(end 41.457626 -140.618972)
		(width 0.1016)
		(layer "In5.Cu")
		(net "MEMA_2")
	)
	(segment
		(start 29.931868 -135.255)
		(end 34.983674 -135.255)
		(width 0.127)
		(layer "In5.Cu")
		(net "MEMA_2")
	)
	(segment
		(start 29.44876 -137.974832)
		(end 29.44876 -137.720832)
		(width 0.127)
		(layer "F.Cu")
		(net "MEMA_13")
	)
	(segment
		(start 31.946088 -138.52144)
		(end 32.073088 -138.64844)
		(width 0.127)
		(layer "F.Cu")
		(net "MEMA_13")
	)
	(segment
		(start 33.606994 -139.318492)
		(end 36.053522 -141.76502)
		(width 0.127)
		(layer "F.Cu")
		(net "MEMA_13")
	)
	(segment
		(start 29.57576 -137.593832)
		(end 30.25267 -137.593832)
		(width 0.127)
		(layer "F.Cu")
		(net "MEMA_13")
	)
	(segment
		(start 31.438088 -139.4587)
		(end 31.565088 -139.3317)
		(width 0.127)
		(layer "F.Cu")
		(net "MEMA_13")
	)
	(segment
		(start 32.803846 -138.22172)
		(end 33.17748 -138.22172)
		(width 0.127)
		(layer "F.Cu")
		(net "MEMA_13")
	)
	(segment
		(start 30.37967 -137.466832)
		(end 30.37967 -136.962896)
		(width 0.127)
		(layer "F.Cu")
		(net "MEMA_13")
	)
	(segment
		(start 30.37967 -138.228832)
		(end 30.25267 -138.101832)
		(width 0.127)
		(layer "F.Cu")
		(net "MEMA_13")
	)
	(segment
		(start 29.44876 -137.720832)
		(end 29.57576 -137.593832)
		(width 0.127)
		(layer "F.Cu")
		(net "MEMA_13")
	)
	(segment
		(start 33.606994 -138.651234)
		(end 33.606994 -139.318492)
		(width 0.127)
		(layer "F.Cu")
		(net "MEMA_13")
	)
	(segment
		(start 32.200088 -139.41552)
		(end 32.454088 -139.41552)
		(width 0.127)
		(layer "F.Cu")
		(net "MEMA_13")
	)
	(segment
		(start 31.057088 -136.92886)
		(end 31.057088 -139.3317)
		(width 0.127)
		(layer "F.Cu")
		(net "MEMA_13")
	)
	(segment
		(start 30.540706 -136.80186)
		(end 30.930088 -136.80186)
		(width 0.127)
		(layer "F.Cu")
		(net "MEMA_13")
	)
	(segment
		(start 39.299896 -141.969236)
		(end 39.299896 -142.199868)
		(width 0.127)
		(layer "F.Cu")
		(net "MEMA_13")
	)
	(segment
		(start 39.09568 -141.76502)
		(end 39.299896 -141.969236)
		(width 0.127)
		(layer "F.Cu")
		(net "MEMA_13")
	)
	(segment
		(start 36.053522 -141.76502)
		(end 39.09568 -141.76502)
		(width 0.127)
		(layer "F.Cu")
		(net "MEMA_13")
	)
	(segment
		(start 22.43455 -136.561576)
		(end 22.034754 -136.961372)
		(width 0.127)
		(layer "F.Cu")
		(net "MEMA_13")
	)
	(segment
		(start 31.692088 -138.52144)
		(end 31.946088 -138.52144)
		(width 0.127)
		(layer "F.Cu")
		(net "MEMA_13")
	)
	(segment
		(start 30.37967 -139.37107)
		(end 30.37967 -138.228832)
		(width 0.127)
		(layer "F.Cu")
		(net "MEMA_13")
	)
	(segment
		(start 30.37967 -136.962896)
		(end 30.540706 -136.80186)
		(width 0.127)
		(layer "F.Cu")
		(net "MEMA_13")
	)
	(segment
		(start 32.581088 -139.28852)
		(end 32.581088 -138.444478)
		(width 0.127)
		(layer "F.Cu")
		(net "MEMA_13")
	)
	(segment
		(start 31.565088 -139.3317)
		(end 31.565088 -138.64844)
		(width 0.127)
		(layer "F.Cu")
		(net "MEMA_13")
	)
	(segment
		(start 32.073088 -139.28852)
		(end 32.200088 -139.41552)
		(width 0.127)
		(layer "F.Cu")
		(net "MEMA_13")
	)
	(segment
		(start 22.034754 -136.961372)
		(end 22.0345 -136.961372)
		(width 0.127)
		(layer "F.Cu")
		(net "MEMA_13")
	)
	(segment
		(start 30.25267 -138.101832)
		(end 29.57576 -138.101832)
		(width 0.127)
		(layer "F.Cu")
		(net "MEMA_13")
	)
	(segment
		(start 31.057088 -139.3317)
		(end 31.184088 -139.4587)
		(width 0.127)
		(layer "F.Cu")
		(net "MEMA_13")
	)
	(segment
		(start 29.57576 -138.101832)
		(end 29.44876 -137.974832)
		(width 0.127)
		(layer "F.Cu")
		(net "MEMA_13")
	)
	(segment
		(start 30.25267 -137.593832)
		(end 30.37967 -137.466832)
		(width 0.127)
		(layer "F.Cu")
		(net "MEMA_13")
	)
	(segment
		(start 31.565088 -138.64844)
		(end 31.692088 -138.52144)
		(width 0.127)
		(layer "F.Cu")
		(net "MEMA_13")
	)
	(segment
		(start 32.073088 -138.64844)
		(end 32.073088 -139.28852)
		(width 0.127)
		(layer "F.Cu")
		(net "MEMA_13")
	)
	(segment
		(start 30.930088 -136.80186)
		(end 31.057088 -136.92886)
		(width 0.127)
		(layer "F.Cu")
		(net "MEMA_13")
	)
	(segment
		(start 31.184088 -139.4587)
		(end 31.438088 -139.4587)
		(width 0.127)
		(layer "F.Cu")
		(net "MEMA_13")
	)
	(segment
		(start 32.581088 -138.444478)
		(end 32.803846 -138.22172)
		(width 0.127)
		(layer "F.Cu")
		(net "MEMA_13")
	)
	(segment
		(start 32.454088 -139.41552)
		(end 32.581088 -139.28852)
		(width 0.127)
		(layer "F.Cu")
		(net "MEMA_13")
	)
	(segment
		(start 33.17748 -138.22172)
		(end 33.606994 -138.651234)
		(width 0.127)
		(layer "F.Cu")
		(net "MEMA_13")
	)
	(via
		(at 30.37967 -139.37107)
		(size 0.508)
		(drill 0.254)
		(layers "F.Cu" "B.Cu")
		(net "MEMA_13")
	)
	(via
		(at 22.0345 -136.961372)
		(size 0.508)
		(drill 0.254)
		(layers "F.Cu" "B.Cu")
		(net "MEMA_13")
	)
	(segment
		(start 22.215348 -133.19379)
		(end 22.709886 -132.699252)
		(width 0.127)
		(layer "B.Cu")
		(net "MEMA_13")
	)
	(segment
		(start 22.0345 -134.395718)
		(end 22.1615 -134.268718)
		(width 0.127)
		(layer "B.Cu")
		(net "MEMA_13")
	)
	(segment
		(start 22.634448 -134.903718)
		(end 22.507448 -134.776718)
		(width 0.127)
		(layer "B.Cu")
		(net "MEMA_13")
	)
	(segment
		(start 23.532592 -134.119874)
		(end 23.532592 -133.909562)
		(width 0.127)
		(layer "B.Cu")
		(net "MEMA_13")
	)
	(segment
		(start 22.1615 -135.284718)
		(end 22.507448 -135.284718)
		(width 0.127)
		(layer "B.Cu")
		(net "MEMA_13")
	)
	(segment
		(start 22.507448 -134.776718)
		(end 22.1615 -134.776718)
		(width 0.127)
		(layer "B.Cu")
		(net "MEMA_13")
	)
	(segment
		(start 22.300946 -130.753358)
		(end 22.201886 -130.753358)
		(width 0.127)
		(layer "B.Cu")
		(net "MEMA_13")
	)
	(segment
		(start 22.1615 -134.268718)
		(end 23.383748 -134.268718)
		(width 0.127)
		(layer "B.Cu")
		(net "MEMA_13")
	)
	(segment
		(start 22.634448 -135.157718)
		(end 22.634448 -134.903718)
		(width 0.127)
		(layer "B.Cu")
		(net "MEMA_13")
	)
	(segment
		(start 22.0345 -136.961372)
		(end 22.0345 -135.411718)
		(width 0.127)
		(layer "B.Cu")
		(net "MEMA_13")
	)
	(segment
		(start 22.380194 -133.760718)
		(end 22.215348 -133.595872)
		(width 0.127)
		(layer "B.Cu")
		(net "MEMA_13")
	)
	(segment
		(start 22.215348 -133.595872)
		(end 22.215348 -133.19379)
		(width 0.127)
		(layer "B.Cu")
		(net "MEMA_13")
	)
	(segment
		(start 22.1615 -134.776718)
		(end 22.0345 -134.649718)
		(width 0.127)
		(layer "B.Cu")
		(net "MEMA_13")
	)
	(segment
		(start 22.011386 -129.556256)
		(end 22.014942 -129.5527)
		(width 0.127)
		(layer "B.Cu")
		(net "MEMA_13")
	)
	(segment
		(start 22.011386 -130.562858)
		(end 22.011386 -129.556256)
		(width 0.127)
		(layer "B.Cu")
		(net "MEMA_13")
	)
	(segment
		(start 23.383748 -134.268718)
		(end 23.532592 -134.119874)
		(width 0.127)
		(layer "B.Cu")
		(net "MEMA_13")
	)
	(segment
		(start 22.507448 -135.284718)
		(end 22.634448 -135.157718)
		(width 0.127)
		(layer "B.Cu")
		(net "MEMA_13")
	)
	(segment
		(start 22.0345 -134.649718)
		(end 22.0345 -134.395718)
		(width 0.127)
		(layer "B.Cu")
		(net "MEMA_13")
	)
	(segment
		(start 22.709886 -132.699252)
		(end 22.709886 -131.162298)
		(width 0.127)
		(layer "B.Cu")
		(net "MEMA_13")
	)
	(segment
		(start 23.383748 -133.760718)
		(end 22.380194 -133.760718)
		(width 0.127)
		(layer "B.Cu")
		(net "MEMA_13")
	)
	(segment
		(start 23.532592 -133.909562)
		(end 23.383748 -133.760718)
		(width 0.127)
		(layer "B.Cu")
		(net "MEMA_13")
	)
	(segment
		(start 22.0345 -135.411718)
		(end 22.1615 -135.284718)
		(width 0.127)
		(layer "B.Cu")
		(net "MEMA_13")
	)
	(segment
		(start 22.201886 -130.753358)
		(end 22.011386 -130.562858)
		(width 0.127)
		(layer "B.Cu")
		(net "MEMA_13")
	)
	(segment
		(start 22.709886 -131.162298)
		(end 22.300946 -130.753358)
		(width 0.127)
		(layer "B.Cu")
		(net "MEMA_13")
	)
	(segment
		(start 30.338776 -139.411964)
		(end 30.37967 -139.37107)
		(width 0.127)
		(layer "In2.Cu")
		(net "MEMA_13")
	)
	(segment
		(start 23.231094 -137.361422)
		(end 23.33879 -137.253726)
		(width 0.127)
		(layer "In2.Cu")
		(net "MEMA_13")
	)
	(segment
		(start 29.485336 -139.411964)
		(end 30.338776 -139.411964)
		(width 0.127)
		(layer "In2.Cu")
		(net "MEMA_13")
	)
	(segment
		(start 24.261572 -137.253726)
		(end 24.426164 -137.418318)
		(width 0.127)
		(layer "In2.Cu")
		(net "MEMA_13")
	)
	(segment
		(start 22.0345 -136.961372)
		(end 22.43455 -137.361422)
		(width 0.0889)
		(layer "In2.Cu")
		(net "MEMA_13")
	)
	(segment
		(start 23.33879 -137.253726)
		(end 24.261572 -137.253726)
		(width 0.127)
		(layer "In2.Cu")
		(net "MEMA_13")
	)
	(segment
		(start 24.426164 -137.418318)
		(end 27.49169 -137.418318)
		(width 0.127)
		(layer "In2.Cu")
		(net "MEMA_13")
	)
	(segment
		(start 27.49169 -137.418318)
		(end 29.485336 -139.411964)
		(width 0.127)
		(layer "In2.Cu")
		(net "MEMA_13")
	)
	(segment
		(start 22.43455 -137.361422)
		(end 23.231094 -137.361422)
		(width 0.0889)
		(layer "In2.Cu")
		(net "MEMA_13")
	)
	(segment
		(start 21.63445 -139.761468)
		(end 21.548852 -139.67587)
		(width 0.127)
		(layer "F.Cu")
		(net "MEMA_12")
	)
	(segment
		(start 20.93341 -139.67587)
		(end 20.644104 -139.386564)
		(width 0.127)
		(layer "F.Cu")
		(net "MEMA_12")
	)
	(segment
		(start 40.899842 -142.999714)
		(end 40.899842 -142.999968)
		(width 0.127)
		(layer "F.Cu")
		(net "MEMA_12")
	)
	(segment
		(start 40.500046 -142.599918)
		(end 40.899842 -142.999714)
		(width 0.127)
		(layer "F.Cu")
		(net "MEMA_12")
	)
	(segment
		(start 21.548852 -139.67587)
		(end 20.93341 -139.67587)
		(width 0.127)
		(layer "F.Cu")
		(net "MEMA_12")
	)
	(via
		(at 40.500046 -142.599918)
		(size 0.4572)
		(drill 0.2032)
		(layers "F.Cu" "B.Cu")
		(net "MEMA_12")
	)
	(via
		(at 20.644104 -139.386564)
		(size 0.508)
		(drill 0.254)
		(layers "F.Cu" "B.Cu")
		(net "MEMA_12")
	)
	(segment
		(start 19.304 -137.1854)
		(end 19.304 -135.905494)
		(width 0.127)
		(layer "B.Cu")
		(net "MEMA_12")
	)
	(segment
		(start 18.373598 -134.36981)
		(end 16.992854 -132.989066)
		(width 0.127)
		(layer "B.Cu")
		(net "MEMA_12")
	)
	(segment
		(start 16.294354 -130.562858)
		(end 16.294354 -129.546858)
		(width 0.127)
		(layer "B.Cu")
		(net "MEMA_12")
	)
	(segment
		(start 16.992854 -131.162298)
		(end 16.393414 -130.562858)
		(width 0.127)
		(layer "B.Cu")
		(net "MEMA_12")
	)
	(segment
		(start 20.644104 -138.525504)
		(end 19.304 -137.1854)
		(width 0.127)
		(layer "B.Cu")
		(net "MEMA_12")
	)
	(segment
		(start 20.644104 -139.386564)
		(end 20.644104 -138.525504)
		(width 0.127)
		(layer "B.Cu")
		(net "MEMA_12")
	)
	(segment
		(start 16.294354 -129.546858)
		(end 16.319754 -129.521458)
		(width 0.127)
		(layer "B.Cu")
		(net "MEMA_12")
	)
	(segment
		(start 18.373598 -134.975092)
		(end 18.373598 -134.36981)
		(width 0.127)
		(layer "B.Cu")
		(net "MEMA_12")
	)
	(segment
		(start 16.393414 -130.562858)
		(end 16.294354 -130.562858)
		(width 0.127)
		(layer "B.Cu")
		(net "MEMA_12")
	)
	(segment
		(start 19.304 -135.905494)
		(end 18.373598 -134.975092)
		(width 0.127)
		(layer "B.Cu")
		(net "MEMA_12")
	)
	(segment
		(start 16.992854 -132.989066)
		(end 16.992854 -131.162298)
		(width 0.127)
		(layer "B.Cu")
		(net "MEMA_12")
	)
	(segment
		(start 40.500046 -142.599918)
		(end 39.2684 -142.599918)
		(width 0.127)
		(layer "In2.Cu")
		(net "MEMA_12")
	)
	(segment
		(start 34.64306 -141.710918)
		(end 34.64306 -141.964918)
		(width 0.127)
		(layer "In2.Cu")
		(net "MEMA_12")
	)
	(segment
		(start 29.688536 -142.330678)
		(end 28.638246 -142.330678)
		(width 0.127)
		(layer "In2.Cu")
		(net "MEMA_12")
	)
	(segment
		(start 26.857198 -140.54963)
		(end 26.260806 -140.54963)
		(width 0.127)
		(layer "In2.Cu")
		(net "MEMA_12")
	)
	(segment
		(start 29.957776 -142.599918)
		(end 29.688536 -142.330678)
		(width 0.127)
		(layer "In2.Cu")
		(net "MEMA_12")
	)
	(segment
		(start 39.2684 -142.599918)
		(end 38.2524 -141.583918)
		(width 0.127)
		(layer "In2.Cu")
		(net "MEMA_12")
	)
	(segment
		(start 28.638246 -142.330678)
		(end 26.857198 -140.54963)
		(width 0.127)
		(layer "In2.Cu")
		(net "MEMA_12")
	)
	(segment
		(start 37.81806 -142.599918)
		(end 29.957776 -142.599918)
		(width 0.127)
		(layer "In2.Cu")
		(net "MEMA_12")
	)
	(segment
		(start 34.64306 -141.964918)
		(end 34.77006 -142.091918)
		(width 0.127)
		(layer "In2.Cu")
		(net "MEMA_12")
	)
	(segment
		(start 24.495506 -139.976098)
		(end 24.12873 -139.609322)
		(width 0.127)
		(layer "In2.Cu")
		(net "MEMA_12")
	)
	(segment
		(start 34.77006 -142.091918)
		(end 37.81806 -142.091918)
		(width 0.127)
		(layer "In2.Cu")
		(net "MEMA_12")
	)
	(segment
		(start 38.2524 -141.583918)
		(end 34.77006 -141.583918)
		(width 0.127)
		(layer "In2.Cu")
		(net "MEMA_12")
	)
	(segment
		(start 37.81806 -142.091918)
		(end 37.94506 -142.218918)
		(width 0.127)
		(layer "In2.Cu")
		(net "MEMA_12")
	)
	(segment
		(start 34.77006 -141.583918)
		(end 34.64306 -141.710918)
		(width 0.127)
		(layer "In2.Cu")
		(net "MEMA_12")
	)
	(segment
		(start 26.260806 -140.54963)
		(end 25.687274 -139.976098)
		(width 0.127)
		(layer "In2.Cu")
		(net "MEMA_12")
	)
	(segment
		(start 20.866862 -139.609322)
		(end 20.644104 -139.386564)
		(width 0.127)
		(layer "In2.Cu")
		(net "MEMA_12")
	)
	(segment
		(start 25.687274 -139.976098)
		(end 24.495506 -139.976098)
		(width 0.127)
		(layer "In2.Cu")
		(net "MEMA_12")
	)
	(segment
		(start 37.94506 -142.218918)
		(end 37.94506 -142.472918)
		(width 0.127)
		(layer "In2.Cu")
		(net "MEMA_12")
	)
	(segment
		(start 24.12873 -139.609322)
		(end 20.866862 -139.609322)
		(width 0.127)
		(layer "In2.Cu")
		(net "MEMA_12")
	)
	(segment
		(start 37.94506 -142.472918)
		(end 37.81806 -142.599918)
		(width 0.127)
		(layer "In2.Cu")
		(net "MEMA_12")
	)
	(segment
		(start 33.40862 -140.45946)
		(end 33.229042 -140.279882)
		(width 0.127)
		(layer "F.Cu")
		(net "MEMA_11")
	)
	(segment
		(start 34.84626 -141.8971)
		(end 34.666682 -141.717522)
		(width 0.127)
		(layer "F.Cu")
		(net "MEMA_11")
	)
	(segment
		(start 33.098994 -139.529058)
		(end 33.098994 -138.8618)
		(width 0.127)
		(layer "F.Cu")
		(net "MEMA_11")
	)
	(segment
		(start 35.33648 -141.766544)
		(end 35.156648 -141.766544)
		(width 0.127)
		(layer "F.Cu")
		(net "MEMA_11")
	)
	(segment
		(start 33.719008 -140.328904)
		(end 33.588452 -140.45946)
		(width 0.127)
		(layer "F.Cu")
		(net "MEMA_11")
	)
	(segment
		(start 40.099996 -142.999968)
		(end 40.099234 -142.999968)
		(width 0.1016)
		(layer "F.Cu")
		(net "MEMA_11")
	)
	(segment
		(start 33.947862 -140.81887)
		(end 34.078418 -140.688314)
		(width 0.127)
		(layer "F.Cu")
		(net "MEMA_11")
	)
	(segment
		(start 34.12744 -141.17828)
		(end 33.947862 -140.998702)
		(width 0.127)
		(layer "F.Cu")
		(net "MEMA_11")
	)
	(segment
		(start 37.996114 -142.56004)
		(end 37.932614 -142.49654)
		(width 0.127)
		(layer "F.Cu")
		(net "MEMA_11")
	)
	(segment
		(start 34.078418 -140.688314)
		(end 34.078418 -140.508482)
		(width 0.127)
		(layer "F.Cu")
		(net "MEMA_11")
	)
	(segment
		(start 33.359598 -139.969494)
		(end 33.359598 -139.789662)
		(width 0.127)
		(layer "F.Cu")
		(net "MEMA_11")
	)
	(segment
		(start 34.307272 -141.17828)
		(end 34.12744 -141.17828)
		(width 0.127)
		(layer "F.Cu")
		(net "MEMA_11")
	)
	(segment
		(start 33.229042 -140.10005)
		(end 33.359598 -139.969494)
		(width 0.127)
		(layer "F.Cu")
		(net "MEMA_11")
	)
	(segment
		(start 34.797238 -141.407134)
		(end 34.797238 -141.227302)
		(width 0.127)
		(layer "F.Cu")
		(net "MEMA_11")
	)
	(segment
		(start 33.947862 -140.998702)
		(end 33.947862 -140.81887)
		(width 0.127)
		(layer "F.Cu")
		(net "MEMA_11")
	)
	(segment
		(start 34.666682 -141.53769)
		(end 34.797238 -141.407134)
		(width 0.127)
		(layer "F.Cu")
		(net "MEMA_11")
	)
	(segment
		(start 34.797238 -141.227302)
		(end 34.61766 -141.047724)
		(width 0.127)
		(layer "F.Cu")
		(net "MEMA_11")
	)
	(segment
		(start 34.437828 -141.047724)
		(end 34.307272 -141.17828)
		(width 0.127)
		(layer "F.Cu")
		(net "MEMA_11")
	)
	(segment
		(start 35.156648 -141.766544)
		(end 35.026092 -141.8971)
		(width 0.127)
		(layer "F.Cu")
		(net "MEMA_11")
	)
	(segment
		(start 34.666682 -141.717522)
		(end 34.666682 -141.53769)
		(width 0.127)
		(layer "F.Cu")
		(net "MEMA_11")
	)
	(segment
		(start 33.588452 -140.45946)
		(end 33.40862 -140.45946)
		(width 0.127)
		(layer "F.Cu")
		(net "MEMA_11")
	)
	(segment
		(start 40.099234 -142.999968)
		(end 39.83228 -142.733014)
		(width 0.1016)
		(layer "F.Cu")
		(net "MEMA_11")
	)
	(segment
		(start 33.229042 -140.279882)
		(end 33.229042 -140.10005)
		(width 0.127)
		(layer "F.Cu")
		(net "MEMA_11")
	)
	(segment
		(start 33.359598 -139.789662)
		(end 33.098994 -139.529058)
		(width 0.127)
		(layer "F.Cu")
		(net "MEMA_11")
	)
	(segment
		(start 33.89884 -140.328904)
		(end 33.719008 -140.328904)
		(width 0.127)
		(layer "F.Cu")
		(net "MEMA_11")
	)
	(segment
		(start 18.034508 -136.961626)
		(end 17.634458 -136.561576)
		(width 0.127)
		(layer "F.Cu")
		(net "MEMA_11")
	)
	(segment
		(start 34.61766 -141.047724)
		(end 34.437828 -141.047724)
		(width 0.127)
		(layer "F.Cu")
		(net "MEMA_11")
	)
	(segment
		(start 34.078418 -140.508482)
		(end 33.89884 -140.328904)
		(width 0.127)
		(layer "F.Cu")
		(net "MEMA_11")
	)
	(segment
		(start 39.414704 -142.56004)
		(end 37.996114 -142.56004)
		(width 0.127)
		(layer "F.Cu")
		(net "MEMA_11")
	)
	(segment
		(start 35.026092 -141.8971)
		(end 34.84626 -141.8971)
		(width 0.127)
		(layer "F.Cu")
		(net "MEMA_11")
	)
	(segment
		(start 37.932614 -142.49654)
		(end 36.066476 -142.49654)
		(width 0.127)
		(layer "F.Cu")
		(net "MEMA_11")
	)
	(segment
		(start 36.066476 -142.49654)
		(end 35.33648 -141.766544)
		(width 0.127)
		(layer "F.Cu")
		(net "MEMA_11")
	)
	(via
		(at 18.034508 -136.961626)
		(size 0.508)
		(drill 0.254)
		(layers "F.Cu" "B.Cu")
		(net "MEMA_11")
	)
	(via
		(at 33.098994 -138.8618)
		(size 0.508)
		(drill 0.254)
		(layers "F.Cu" "B.Cu")
		(net "MEMA_11")
	)
	(arc
		(start 39.83228 -142.733014)
		(mid 39.640709 -142.604947)
		(end 39.414704 -142.56004)
		(width 0.1016)
		(layer "F.Cu")
		(net "MEMA_11")
	)
	(segment
		(start 14.423898 -135.701278)
		(end 14.296898 -135.828278)
		(width 0.127)
		(layer "B.Cu")
		(net "MEMA_11")
	)
	(segment
		(start 16.074898 -135.828278)
		(end 15.947898 -135.701278)
		(width 0.127)
		(layer "B.Cu")
		(net "MEMA_11")
	)
	(segment
		(start 15.439898 -135.701278)
		(end 15.312898 -135.828278)
		(width 0.127)
		(layer "B.Cu")
		(net "MEMA_11")
	)
	(segment
		(start 15.947898 -135.701278)
		(end 15.947898 -135.208518)
		(width 0.127)
		(layer "B.Cu")
		(net "MEMA_11")
	)
	(segment
		(start 13.892784 -136.016746)
		(end 12.039346 -136.016746)
		(width 0.127)
		(layer "B.Cu")
		(net "MEMA_11")
	)
	(segment
		(start 12.039346 -136.016746)
		(end 11.647424 -135.624824)
		(width 0.127)
		(layer "B.Cu")
		(net "MEMA_11")
	)
	(segment
		(start 11.64336 -135.290052)
		(end 11.647424 -135.285988)
		(width 0.127)
		(layer "B.Cu")
		(net "MEMA_11")
	)
	(segment
		(start 15.312898 -135.828278)
		(end 15.058898 -135.828278)
		(width 0.127)
		(layer "B.Cu")
		(net "MEMA_11")
	)
	(segment
		(start 14.423898 -135.208518)
		(end 14.423898 -135.701278)
		(width 0.127)
		(layer "B.Cu")
		(net "MEMA_11")
	)
	(segment
		(start 14.550898 -135.081518)
		(end 14.423898 -135.208518)
		(width 0.127)
		(layer "B.Cu")
		(net "MEMA_11")
	)
	(segment
		(start 11.647424 -135.624824)
		(end 11.647424 -135.285988)
		(width 0.127)
		(layer "B.Cu")
		(net "MEMA_11")
	)
	(segment
		(start 15.947898 -135.208518)
		(end 15.820898 -135.081518)
		(width 0.127)
		(layer "B.Cu")
		(net "MEMA_11")
	)
	(segment
		(start 15.820898 -135.081518)
		(end 15.566898 -135.081518)
		(width 0.127)
		(layer "B.Cu")
		(net "MEMA_11")
	)
	(segment
		(start 14.296898 -135.828278)
		(end 14.081252 -135.828278)
		(width 0.127)
		(layer "B.Cu")
		(net "MEMA_11")
	)
	(segment
		(start 10.64641 -135.290052)
		(end 11.64336 -135.290052)
		(width 0.127)
		(layer "B.Cu")
		(net "MEMA_11")
	)
	(segment
		(start 15.566898 -135.081518)
		(end 15.439898 -135.208518)
		(width 0.127)
		(layer "B.Cu")
		(net "MEMA_11")
	)
	(segment
		(start 15.439898 -135.208518)
		(end 15.439898 -135.701278)
		(width 0.127)
		(layer "B.Cu")
		(net "MEMA_11")
	)
	(segment
		(start 15.058898 -135.828278)
		(end 14.931898 -135.701278)
		(width 0.127)
		(layer "B.Cu")
		(net "MEMA_11")
	)
	(segment
		(start 14.804898 -135.081518)
		(end 14.550898 -135.081518)
		(width 0.127)
		(layer "B.Cu")
		(net "MEMA_11")
	)
	(segment
		(start 16.90116 -135.828278)
		(end 16.074898 -135.828278)
		(width 0.127)
		(layer "B.Cu")
		(net "MEMA_11")
	)
	(segment
		(start 14.081252 -135.828278)
		(end 13.892784 -136.016746)
		(width 0.127)
		(layer "B.Cu")
		(net "MEMA_11")
	)
	(segment
		(start 14.931898 -135.701278)
		(end 14.931898 -135.208518)
		(width 0.127)
		(layer "B.Cu")
		(net "MEMA_11")
	)
	(segment
		(start 14.931898 -135.208518)
		(end 14.804898 -135.081518)
		(width 0.127)
		(layer "B.Cu")
		(net "MEMA_11")
	)
	(segment
		(start 18.034508 -136.961626)
		(end 16.90116 -135.828278)
		(width 0.127)
		(layer "B.Cu")
		(net "MEMA_11")
	)
	(segment
		(start 18.034508 -136.961626)
		(end 18.977102 -136.961626)
		(width 0.127)
		(layer "In5.Cu")
		(net "MEMA_11")
	)
	(segment
		(start 21.198332 -134.740396)
		(end 27.980132 -134.740396)
		(width 0.127)
		(layer "In5.Cu")
		(net "MEMA_11")
	)
	(segment
		(start 33.63722 -137.23366)
		(end 33.63722 -137.71626)
		(width 0.127)
		(layer "In5.Cu")
		(net "MEMA_11")
	)
	(segment
		(start 33.51022 -137.10666)
		(end 33.63722 -137.23366)
		(width 0.127)
		(layer "In5.Cu")
		(net "MEMA_11")
	)
	(segment
		(start 33.098994 -137.97026)
		(end 33.098994 -138.8618)
		(width 0.127)
		(layer "In5.Cu")
		(net "MEMA_11")
	)
	(segment
		(start 31.206694 -137.10666)
		(end 33.51022 -137.10666)
		(width 0.127)
		(layer "In5.Cu")
		(net "MEMA_11")
	)
	(segment
		(start 33.51022 -137.84326)
		(end 33.225994 -137.84326)
		(width 0.127)
		(layer "In5.Cu")
		(net "MEMA_11")
	)
	(segment
		(start 29.510736 -136.271)
		(end 30.371034 -136.271)
		(width 0.127)
		(layer "In5.Cu")
		(net "MEMA_11")
	)
	(segment
		(start 27.980132 -134.740396)
		(end 29.510736 -136.271)
		(width 0.127)
		(layer "In5.Cu")
		(net "MEMA_11")
	)
	(segment
		(start 33.225994 -137.84326)
		(end 33.098994 -137.97026)
		(width 0.127)
		(layer "In5.Cu")
		(net "MEMA_11")
	)
	(segment
		(start 33.63722 -137.71626)
		(end 33.51022 -137.84326)
		(width 0.127)
		(layer "In5.Cu")
		(net "MEMA_11")
	)
	(segment
		(start 30.371034 -136.271)
		(end 31.206694 -137.10666)
		(width 0.127)
		(layer "In5.Cu")
		(net "MEMA_11")
	)
	(segment
		(start 18.977102 -136.961626)
		(end 21.198332 -134.740396)
		(width 0.127)
		(layer "In5.Cu")
		(net "MEMA_11")
	)
	(segment
		(start 42.89933 -143.400018)
		(end 43.29938 -143.800068)
		(width 0.127)
		(layer "F.Cu")
		(net "MEMA_10")
	)
	(segment
		(start 18.819368 -140.146278)
		(end 18.922492 -140.146278)
		(width 0.127)
		(layer "F.Cu")
		(net "MEMA_10")
	)
	(segment
		(start 43.29938 -143.800068)
		(end 43.299888 -143.800068)
		(width 0.127)
		(layer "F.Cu")
		(net "MEMA_10")
	)
	(segment
		(start 18.434558 -139.761468)
		(end 18.819368 -140.146278)
		(width 0.127)
		(layer "F.Cu")
		(net "MEMA_10")
	)
	(via
		(at 42.89933 -143.400018)
		(size 0.4572)
		(drill 0.2032)
		(layers "F.Cu" "B.Cu")
		(net "MEMA_10")
	)
	(via
		(at 18.922492 -140.146278)
		(size 0.508)
		(drill 0.254)
		(layers "F.Cu" "B.Cu")
		(net "MEMA_10")
	)
	(segment
		(start 14.940026 -142.37335)
		(end 14.813026 -142.50035)
		(width 0.127)
		(layer "B.Cu")
		(net "MEMA_10")
	)
	(segment
		(start 11.880342 -141.707362)
		(end 11.66749 -141.49451)
		(width 0.127)
		(layer "B.Cu")
		(net "MEMA_10")
	)
	(segment
		(start 18.922492 -140.146278)
		(end 18.75917 -140.3096)
		(width 0.127)
		(layer "B.Cu")
		(net "MEMA_10")
	)
	(segment
		(start 14.813026 -142.50035)
		(end 14.559026 -142.50035)
		(width 0.127)
		(layer "B.Cu")
		(net "MEMA_10")
	)
	(segment
		(start 14.432026 -142.37335)
		(end 14.432026 -141.67104)
		(width 0.127)
		(layer "B.Cu")
		(net "MEMA_10")
	)
	(segment
		(start 15.36446 -141.135608)
		(end 15.195296 -141.135608)
		(width 0.127)
		(layer "B.Cu")
		(net "MEMA_10")
	)
	(segment
		(start 11.66749 -141.49451)
		(end 11.66749 -141.008862)
		(width 0.127)
		(layer "B.Cu")
		(net "MEMA_10")
	)
	(segment
		(start 15.195296 -141.135608)
		(end 14.940026 -141.390878)
		(width 0.127)
		(layer "B.Cu")
		(net "MEMA_10")
	)
	(segment
		(start 13.865098 -141.450822)
		(end 13.608558 -141.707362)
		(width 0.127)
		(layer "B.Cu")
		(net "MEMA_10")
	)
	(segment
		(start 14.940026 -141.390878)
		(end 14.940026 -142.37335)
		(width 0.127)
		(layer "B.Cu")
		(net "MEMA_10")
	)
	(segment
		(start 15.993364 -140.506704)
		(end 15.36446 -141.135608)
		(width 0.127)
		(layer "B.Cu")
		(net "MEMA_10")
	)
	(segment
		(start 16.439896 -140.506704)
		(end 15.993364 -140.506704)
		(width 0.127)
		(layer "B.Cu")
		(net "MEMA_10")
	)
	(segment
		(start 16.637 -140.3096)
		(end 16.439896 -140.506704)
		(width 0.127)
		(layer "B.Cu")
		(net "MEMA_10")
	)
	(segment
		(start 13.608558 -141.707362)
		(end 11.880342 -141.707362)
		(width 0.127)
		(layer "B.Cu")
		(net "MEMA_10")
	)
	(segment
		(start 11.66749 -141.008862)
		(end 10.65149 -141.008862)
		(width 0.127)
		(layer "B.Cu")
		(net "MEMA_10")
	)
	(segment
		(start 14.211808 -141.450822)
		(end 13.865098 -141.450822)
		(width 0.127)
		(layer "B.Cu")
		(net "MEMA_10")
	)
	(segment
		(start 14.559026 -142.50035)
		(end 14.432026 -142.37335)
		(width 0.127)
		(layer "B.Cu")
		(net "MEMA_10")
	)
	(segment
		(start 18.75917 -140.3096)
		(end 16.637 -140.3096)
		(width 0.127)
		(layer "B.Cu")
		(net "MEMA_10")
	)
	(segment
		(start 14.432026 -141.67104)
		(end 14.211808 -141.450822)
		(width 0.127)
		(layer "B.Cu")
		(net "MEMA_10")
	)
	(segment
		(start 32.143954 -142.377414)
		(end 31.943548 -142.57782)
		(width 0.127)
		(layer "In5.Cu")
		(net "MEMA_10")
	)
	(segment
		(start 33.53435 -142.377414)
		(end 32.143954 -142.377414)
		(width 0.127)
		(layer "In5.Cu")
		(net "MEMA_10")
	)
	(segment
		(start 43.30573 -143.581628)
		(end 43.30573 -144.351248)
		(width 0.127)
		(layer "In5.Cu")
		(net "MEMA_10")
	)
	(segment
		(start 22.42439 -139.691364)
		(end 21.839936 -139.691364)
		(width 0.127)
		(layer "In5.Cu")
		(net "MEMA_10")
	)
	(segment
		(start 38.80993 -143.348964)
		(end 37.838634 -142.377668)
		(width 0.127)
		(layer "In5.Cu")
		(net "MEMA_10")
	)
	(segment
		(start 37.838634 -142.377668)
		(end 36.190936 -142.377668)
		(width 0.127)
		(layer "In5.Cu")
		(net "MEMA_10")
	)
	(segment
		(start 31.943548 -142.57782)
		(end 29.766514 -142.57782)
		(width 0.127)
		(layer "In5.Cu")
		(net "MEMA_10")
	)
	(segment
		(start 19.337782 -140.561568)
		(end 18.922492 -140.146278)
		(width 0.0889)
		(layer "In5.Cu")
		(net "MEMA_10")
	)
	(segment
		(start 21.63445 -140.32738)
		(end 21.400262 -140.561568)
		(width 0.0889)
		(layer "In5.Cu")
		(net "MEMA_10")
	)
	(segment
		(start 22.829266 -140.09624)
		(end 22.42439 -139.691364)
		(width 0.127)
		(layer "In5.Cu")
		(net "MEMA_10")
	)
	(segment
		(start 43.02633 -144.593818)
		(end 41.93667 -144.593818)
		(width 0.127)
		(layer "In5.Cu")
		(net "MEMA_10")
	)
	(segment
		(start 36.190936 -142.377668)
		(end 33.53435 -142.377414)
		(width 0.127)
		(layer "In5.Cu")
		(net "MEMA_10")
	)
	(segment
		(start 40.734234 -143.552164)
		(end 39.300404 -143.552164)
		(width 0.127)
		(layer "In5.Cu")
		(net "MEMA_10")
	)
	(segment
		(start 40.96893 -143.679164)
		(end 40.91813 -143.628364)
		(width 0.127)
		(layer "In5.Cu")
		(net "MEMA_10")
	)
	(segment
		(start 21.839936 -139.691364)
		(end 21.63445 -139.89685)
		(width 0.0889)
		(layer "In5.Cu")
		(net "MEMA_10")
	)
	(segment
		(start 21.400262 -140.561568)
		(end 19.337782 -140.561568)
		(width 0.0889)
		(layer "In5.Cu")
		(net "MEMA_10")
	)
	(segment
		(start 21.63445 -139.89685)
		(end 21.63445 -140.32738)
		(width 0.0889)
		(layer "In5.Cu")
		(net "MEMA_10")
	)
	(segment
		(start 43.106848 -143.399764)
		(end 43.123866 -143.399764)
		(width 0.127)
		(layer "In5.Cu")
		(net "MEMA_10")
	)
	(segment
		(start 29.766514 -142.57782)
		(end 27.284934 -140.09624)
		(width 0.127)
		(layer "In5.Cu")
		(net "MEMA_10")
	)
	(segment
		(start 27.284934 -140.09624)
		(end 22.829266 -140.09624)
		(width 0.127)
		(layer "In5.Cu")
		(net "MEMA_10")
	)
	(segment
		(start 41.474644 -143.806164)
		(end 41.275508 -143.806164)
		(width 0.127)
		(layer "In5.Cu")
		(net "MEMA_10")
	)
	(segment
		(start 41.706292 -144.36344)
		(end 41.706292 -144.037812)
		(width 0.127)
		(layer "In5.Cu")
		(net "MEMA_10")
	)
	(arc
		(start 42.89933 -143.400018)
		(mid 43.003089 -143.399828)
		(end 43.106848 -143.399764)
		(width 0.127)
		(layer "In5.Cu")
		(net "MEMA_10")
	)
	(arc
		(start 40.91813 -143.628364)
		(mid 40.833758 -143.571988)
		(end 40.734234 -143.552164)
		(width 0.127)
		(layer "In5.Cu")
		(net "MEMA_10")
	)
	(arc
		(start 39.300404 -143.552164)
		(mid 39.034946 -143.499361)
		(end 38.80993 -143.348964)
		(width 0.127)
		(layer "In5.Cu")
		(net "MEMA_10")
	)
	(arc
		(start 43.123866 -143.399764)
		(mid 43.252463 -143.453031)
		(end 43.30573 -143.581628)
		(width 0.127)
		(layer "In5.Cu")
		(net "MEMA_10")
	)
	(arc
		(start 41.93667 -144.593818)
		(mid 41.773768 -144.526342)
		(end 41.706292 -144.36344)
		(width 0.127)
		(layer "In5.Cu")
		(net "MEMA_10")
	)
	(arc
		(start 43.30573 -144.351248)
		(mid 43.211334 -144.524716)
		(end 43.02633 -144.593818)
		(width 0.127)
		(layer "In5.Cu")
		(net "MEMA_10")
	)
	(arc
		(start 41.275508 -143.806164)
		(mid 41.109585 -143.77316)
		(end 40.96893 -143.679164)
		(width 0.127)
		(layer "In5.Cu")
		(net "MEMA_10")
	)
	(arc
		(start 41.706292 -144.037812)
		(mid 41.638444 -143.874012)
		(end 41.474644 -143.806164)
		(width 0.127)
		(layer "In5.Cu")
		(net "MEMA_10")
	)
	(segment
		(start 28.400756 -140.75918)
		(end 28.400756 -140.10894)
		(width 0.127)
		(layer "F.Cu")
		(net "MEMA_1")
	)
	(segment
		(start 32.856932 -141.52626)
		(end 32.856932 -141.705584)
		(width 0.127)
		(layer "F.Cu")
		(net "MEMA_1")
	)
	(segment
		(start 33.73501 -141.546072)
		(end 35.193478 -143.00454)
		(width 0.127)
		(layer "F.Cu")
		(net "MEMA_1")
	)
	(segment
		(start 33.555686 -141.546072)
		(end 33.73501 -141.546072)
		(width 0.127)
		(layer "F.Cu")
		(net "MEMA_1")
	)
	(segment
		(start 33.037018 -141.88567)
		(end 33.216342 -141.88567)
		(width 0.127)
		(layer "F.Cu")
		(net "MEMA_1")
	)
	(segment
		(start 35.193478 -143.00454)
		(end 36.504626 -143.00454)
		(width 0.127)
		(layer "F.Cu")
		(net "MEMA_1")
	)
	(segment
		(start 33.216342 -141.88567)
		(end 33.555686 -141.546072)
		(width 0.127)
		(layer "F.Cu")
		(net "MEMA_1")
	)
	(segment
		(start 28.527756 -140.88618)
		(end 28.400756 -140.75918)
		(width 0.127)
		(layer "F.Cu")
		(net "MEMA_1")
	)
	(segment
		(start 32.089598 -140.73759)
		(end 31.941008 -140.88618)
		(width 0.127)
		(layer "F.Cu")
		(net "MEMA_1")
	)
	(segment
		(start 36.509198 -142.999968)
		(end 39.299896 -142.999968)
		(width 0.127)
		(layer "F.Cu")
		(net "MEMA_1")
	)
	(segment
		(start 31.941008 -140.88618)
		(end 28.527756 -140.88618)
		(width 0.127)
		(layer "F.Cu")
		(net "MEMA_1")
	)
	(segment
		(start 32.856932 -141.705584)
		(end 33.037018 -141.88567)
		(width 0.127)
		(layer "F.Cu")
		(net "MEMA_1")
	)
	(segment
		(start 36.504626 -143.00454)
		(end 36.509198 -142.999968)
		(width 0.127)
		(layer "F.Cu")
		(net "MEMA_1")
	)
	(segment
		(start 32.721042 -140.10894)
		(end 32.721042 -140.532104)
		(width 0.127)
		(layer "F.Cu")
		(net "MEMA_1")
	)
	(segment
		(start 33.196276 -141.186662)
		(end 32.856932 -141.52626)
		(width 0.127)
		(layer "F.Cu")
		(net "MEMA_1")
	)
	(segment
		(start 32.721042 -140.532104)
		(end 33.196276 -141.007338)
		(width 0.127)
		(layer "F.Cu")
		(net "MEMA_1")
	)
	(segment
		(start 32.594042 -139.98194)
		(end 32.721042 -140.10894)
		(width 0.127)
		(layer "F.Cu")
		(net "MEMA_1")
	)
	(segment
		(start 28.527756 -139.98194)
		(end 32.594042 -139.98194)
		(width 0.127)
		(layer "F.Cu")
		(net "MEMA_1")
	)
	(segment
		(start 33.196276 -141.007338)
		(end 33.196276 -141.186662)
		(width 0.127)
		(layer "F.Cu")
		(net "MEMA_1")
	)
	(segment
		(start 22.0345 -137.761472)
		(end 21.63445 -138.161522)
		(width 0.127)
		(layer "F.Cu")
		(net "MEMA_1")
	)
	(segment
		(start 28.400756 -140.10894)
		(end 28.527756 -139.98194)
		(width 0.127)
		(layer "F.Cu")
		(net "MEMA_1")
	)
	(via
		(at 22.0345 -137.761472)
		(size 0.508)
		(drill 0.254)
		(layers "F.Cu" "B.Cu")
		(net "MEMA_1")
	)
	(via
		(at 32.089598 -140.73759)
		(size 0.508)
		(drill 0.254)
		(layers "F.Cu" "B.Cu")
		(net "MEMA_1")
	)
	(segment
		(start 20.818856 -133.46684)
		(end 20.2438 -133.46684)
		(width 0.127)
		(layer "B.Cu")
		(net "MEMA_1")
	)
	(segment
		(start 20.1168 -133.179312)
		(end 19.85137 -132.913882)
		(width 0.127)
		(layer "B.Cu")
		(net "MEMA_1")
	)
	(segment
		(start 19.25193 -130.562858)
		(end 19.15287 -130.562858)
		(width 0.127)
		(layer "B.Cu")
		(net "MEMA_1")
	)
	(segment
		(start 22.0345 -137.761472)
		(end 21.22297 -137.761472)
		(width 0.127)
		(layer "B.Cu")
		(net "MEMA_1")
	)
	(segment
		(start 20.2438 -133.97484)
		(end 20.818856 -133.97484)
		(width 0.127)
		(layer "B.Cu")
		(net "MEMA_1")
	)
	(segment
		(start 20.945856 -133.84784)
		(end 20.945856 -133.59384)
		(width 0.127)
		(layer "B.Cu")
		(net "MEMA_1")
	)
	(segment
		(start 19.15287 -129.530094)
		(end 19.144742 -129.521966)
		(width 0.127)
		(layer "B.Cu")
		(net "MEMA_1")
	)
	(segment
		(start 20.1168 -134.10184)
		(end 20.2438 -133.97484)
		(width 0.127)
		(layer "B.Cu")
		(net "MEMA_1")
	)
	(segment
		(start 20.2438 -133.46684)
		(end 20.1168 -133.33984)
		(width 0.127)
		(layer "B.Cu")
		(net "MEMA_1")
	)
	(segment
		(start 19.85137 -132.913882)
		(end 19.85137 -131.162298)
		(width 0.127)
		(layer "B.Cu")
		(net "MEMA_1")
	)
	(segment
		(start 19.85137 -131.162298)
		(end 19.25193 -130.562858)
		(width 0.127)
		(layer "B.Cu")
		(net "MEMA_1")
	)
	(segment
		(start 20.818856 -133.97484)
		(end 20.945856 -133.84784)
		(width 0.127)
		(layer "B.Cu")
		(net "MEMA_1")
	)
	(segment
		(start 20.1168 -136.655302)
		(end 20.1168 -134.10184)
		(width 0.127)
		(layer "B.Cu")
		(net "MEMA_1")
	)
	(segment
		(start 20.1168 -133.33984)
		(end 20.1168 -133.179312)
		(width 0.127)
		(layer "B.Cu")
		(net "MEMA_1")
	)
	(segment
		(start 19.15287 -130.562858)
		(end 19.15287 -129.530094)
		(width 0.127)
		(layer "B.Cu")
		(net "MEMA_1")
	)
	(segment
		(start 21.22297 -137.761472)
		(end 20.1168 -136.655302)
		(width 0.127)
		(layer "B.Cu")
		(net "MEMA_1")
	)
	(segment
		(start 20.945856 -133.59384)
		(end 20.818856 -133.46684)
		(width 0.127)
		(layer "B.Cu")
		(net "MEMA_1")
	)
	(segment
		(start 31.788608 -140.4366)
		(end 29.780992 -140.4366)
		(width 0.127)
		(layer "In5.Cu")
		(net "MEMA_1")
	)
	(segment
		(start 27.398472 -138.05408)
		(end 24.022558 -138.05408)
		(width 0.127)
		(layer "In5.Cu")
		(net "MEMA_1")
	)
	(segment
		(start 23.471632 -138.161522)
		(end 22.43455 -138.161522)
		(width 0.0889)
		(layer "In5.Cu")
		(net "MEMA_1")
	)
	(segment
		(start 29.780992 -140.4366)
		(end 27.398472 -138.05408)
		(width 0.127)
		(layer "In5.Cu")
		(net "MEMA_1")
	)
	(segment
		(start 23.915116 -138.161522)
		(end 23.471632 -138.161522)
		(width 0.127)
		(layer "In5.Cu")
		(net "MEMA_1")
	)
	(segment
		(start 24.022558 -138.05408)
		(end 23.915116 -138.161522)
		(width 0.127)
		(layer "In5.Cu")
		(net "MEMA_1")
	)
	(segment
		(start 22.43455 -138.161522)
		(end 22.0345 -137.761472)
		(width 0.0889)
		(layer "In5.Cu")
		(net "MEMA_1")
	)
	(segment
		(start 32.089598 -140.73759)
		(end 31.788608 -140.4366)
		(width 0.127)
		(layer "In5.Cu")
		(net "MEMA_1")
	)
	(segment
		(start 18.434812 -138.161522)
		(end 18.834354 -138.561064)
		(width 0.127)
		(layer "F.Cu")
		(net "MEMA_0")
	)
	(segment
		(start 42.09923 -143.400018)
		(end 42.49928 -143.800068)
		(width 0.127)
		(layer "F.Cu")
		(net "MEMA_0")
	)
	(segment
		(start 42.49928 -143.800068)
		(end 42.500042 -143.800068)
		(width 0.127)
		(layer "F.Cu")
		(net "MEMA_0")
	)
	(segment
		(start 18.434558 -138.161522)
		(end 18.434812 -138.161522)
		(width 0.127)
		(layer "F.Cu")
		(net "MEMA_0")
	)
	(via
		(at 42.09923 -143.400018)
		(size 0.4572)
		(drill 0.2032)
		(layers "F.Cu" "B.Cu")
		(net "MEMA_0")
	)
	(via
		(at 18.834354 -138.561064)
		(size 0.508)
		(drill 0.254)
		(layers "F.Cu" "B.Cu")
		(net "MEMA_0")
	)
	(segment
		(start 11.66749 -139.579604)
		(end 10.660634 -139.579604)
		(width 0.127)
		(layer "B.Cu")
		(net "MEMA_0")
	)
	(segment
		(start 19.551904 -139.147042)
		(end 19.65706 -139.252198)
		(width 0.127)
		(layer "B.Cu")
		(net "MEMA_0")
	)
	(segment
		(start 11.66749 -139.678664)
		(end 11.66749 -139.579604)
		(width 0.127)
		(layer "B.Cu")
		(net "MEMA_0")
	)
	(segment
		(start 16.236696 -140.278104)
		(end 15.743428 -140.278104)
		(width 0.127)
		(layer "B.Cu")
		(net "MEMA_0")
	)
	(segment
		(start 19.65706 -139.252198)
		(end 19.65706 -139.566904)
		(width 0.127)
		(layer "B.Cu")
		(net "MEMA_0")
	)
	(segment
		(start 13.94714 -140.65758)
		(end 13.567664 -140.278104)
		(width 0.127)
		(layer "B.Cu")
		(net "MEMA_0")
	)
	(segment
		(start 19.523202 -139.700762)
		(end 18.414238 -139.700762)
		(width 0.127)
		(layer "B.Cu")
		(net "MEMA_0")
	)
	(segment
		(start 12.26693 -140.278104)
		(end 11.66749 -139.678664)
		(width 0.127)
		(layer "B.Cu")
		(net "MEMA_0")
	)
	(segment
		(start 18.834354 -138.954256)
		(end 19.02714 -139.147042)
		(width 0.127)
		(layer "B.Cu")
		(net "MEMA_0")
	)
	(segment
		(start 15.743428 -140.278104)
		(end 15.363952 -140.65758)
		(width 0.127)
		(layer "B.Cu")
		(net "MEMA_0")
	)
	(segment
		(start 15.363952 -140.65758)
		(end 13.94714 -140.65758)
		(width 0.127)
		(layer "B.Cu")
		(net "MEMA_0")
	)
	(segment
		(start 13.567664 -140.278104)
		(end 12.26693 -140.278104)
		(width 0.127)
		(layer "B.Cu")
		(net "MEMA_0")
	)
	(segment
		(start 18.834354 -138.561064)
		(end 18.834354 -138.954256)
		(width 0.127)
		(layer "B.Cu")
		(net "MEMA_0")
	)
	(segment
		(start 19.65706 -139.566904)
		(end 19.523202 -139.700762)
		(width 0.127)
		(layer "B.Cu")
		(net "MEMA_0")
	)
	(segment
		(start 16.4465 -140.0683)
		(end 16.236696 -140.278104)
		(width 0.127)
		(layer "B.Cu")
		(net "MEMA_0")
	)
	(segment
		(start 10.660634 -139.579604)
		(end 10.656062 -139.575032)
		(width 0.127)
		(layer "B.Cu")
		(net "MEMA_0")
	)
	(segment
		(start 19.02714 -139.147042)
		(end 19.551904 -139.147042)
		(width 0.127)
		(layer "B.Cu")
		(net "MEMA_0")
	)
	(segment
		(start 18.0467 -140.0683)
		(end 16.4465 -140.0683)
		(width 0.127)
		(layer "B.Cu")
		(net "MEMA_0")
	)
	(segment
		(start 18.414238 -139.700762)
		(end 18.0467 -140.0683)
		(width 0.127)
		(layer "B.Cu")
		(net "MEMA_0")
	)
	(segment
		(start 41.57853 -143.120364)
		(end 41.70553 -143.247364)
		(width 0.127)
		(layer "In5.Cu")
		(net "MEMA_0")
	)
	(segment
		(start 30.066996 -141.42466)
		(end 30.320996 -141.42466)
		(width 0.127)
		(layer "In5.Cu")
		(net "MEMA_0")
	)
	(segment
		(start 23.518114 -138.542522)
		(end 24.406606 -138.542522)
		(width 0.127)
		(layer "In5.Cu")
		(net "MEMA_0")
	)
	(segment
		(start 34.099246 -141.234414)
		(end 34.099246 -141.19352)
		(width 0.127)
		(layer "In5.Cu")
		(net "MEMA_0")
	)
	(segment
		(start 25.508458 -138.56208)
		(end 25.762458 -138.56208)
		(width 0.127)
		(layer "In5.Cu")
		(net "MEMA_0")
	)
	(segment
		(start 36.766246 -141.361414)
		(end 37.020246 -141.361414)
		(width 0.127)
		(layer "In5.Cu")
		(net "MEMA_0")
	)
	(segment
		(start 25.762458 -138.56208)
		(end 25.889458 -138.68908)
		(width 0.127)
		(layer "In5.Cu")
		(net "MEMA_0")
	)
	(segment
		(start 30.447996 -141.0716)
		(end 30.574996 -140.9446)
		(width 0.127)
		(layer "In5.Cu")
		(net "MEMA_0")
	)
	(segment
		(start 34.988246 -141.361414)
		(end 35.115246 -141.234414)
		(width 0.127)
		(layer "In5.Cu")
		(net "MEMA_0")
	)
	(segment
		(start 30.447996 -141.29766)
		(end 30.447996 -141.0716)
		(width 0.127)
		(layer "In5.Cu")
		(net "MEMA_0")
	)
	(segment
		(start 33.591246 -141.234414)
		(end 33.718246 -141.361414)
		(width 0.127)
		(layer "In5.Cu")
		(net "MEMA_0")
	)
	(segment
		(start 37.274246 -141.06652)
		(end 37.528246 -141.06652)
		(width 0.127)
		(layer "In5.Cu")
		(net "MEMA_0")
	)
	(segment
		(start 37.528246 -141.06652)
		(end 37.655246 -141.19352)
		(width 0.127)
		(layer "In5.Cu")
		(net "MEMA_0")
	)
	(segment
		(start 33.083246 -141.234414)
		(end 33.083246 -141.19352)
		(width 0.127)
		(layer "In5.Cu")
		(net "MEMA_0")
	)
	(segment
		(start 25.889458 -138.93546)
		(end 26.016458 -139.06246)
		(width 0.127)
		(layer "In5.Cu")
		(net "MEMA_0")
	)
	(segment
		(start 37.147246 -141.19352)
		(end 37.274246 -141.06652)
		(width 0.127)
		(layer "In5.Cu")
		(net "MEMA_0")
	)
	(segment
		(start 35.496246 -141.06652)
		(end 35.623246 -141.19352)
		(width 0.127)
		(layer "In5.Cu")
		(net "MEMA_0")
	)
	(segment
		(start 25.254458 -139.06246)
		(end 25.381458 -138.93546)
		(width 0.127)
		(layer "In5.Cu")
		(net "MEMA_0")
	)
	(segment
		(start 24.746458 -138.56208)
		(end 24.873458 -138.68908)
		(width 0.127)
		(layer "In5.Cu")
		(net "MEMA_0")
	)
	(segment
		(start 35.242246 -141.06652)
		(end 35.496246 -141.06652)
		(width 0.127)
		(layer "In5.Cu")
		(net "MEMA_0")
	)
	(segment
		(start 31.149798 -140.9446)
		(end 31.566612 -141.361414)
		(width 0.127)
		(layer "In5.Cu")
		(net "MEMA_0")
	)
	(segment
		(start 37.020246 -141.361414)
		(end 37.147246 -141.234414)
		(width 0.127)
		(layer "In5.Cu")
		(net "MEMA_0")
	)
	(segment
		(start 20.503134 -138.78814)
		(end 20.710398 -138.78814)
		(width 0.127)
		(layer "In5.Cu")
		(net "MEMA_0")
	)
	(segment
		(start 37.147246 -141.234414)
		(end 37.147246 -141.19352)
		(width 0.127)
		(layer "In5.Cu")
		(net "MEMA_0")
	)
	(segment
		(start 24.406606 -138.542522)
		(end 24.426164 -138.56208)
		(width 0.127)
		(layer "In5.Cu")
		(net "MEMA_0")
	)
	(segment
		(start 19.982434 -139.30884)
		(end 20.503134 -138.78814)
		(width 0.127)
		(layer "In5.Cu")
		(net "MEMA_0")
	)
	(segment
		(start 30.574996 -140.9446)
		(end 31.149798 -140.9446)
		(width 0.127)
		(layer "In5.Cu")
		(net "MEMA_0")
	)
	(segment
		(start 35.115246 -141.234414)
		(end 35.115246 -141.19352)
		(width 0.127)
		(layer "In5.Cu")
		(net "MEMA_0")
	)
	(segment
		(start 36.639246 -141.234414)
		(end 36.766246 -141.361414)
		(width 0.127)
		(layer "In5.Cu")
		(net "MEMA_0")
	)
	(segment
		(start 33.591246 -141.19352)
		(end 33.591246 -141.234414)
		(width 0.127)
		(layer "In5.Cu")
		(net "MEMA_0")
	)
	(segment
		(start 37.655246 -141.234414)
		(end 37.782246 -141.361414)
		(width 0.127)
		(layer "In5.Cu")
		(net "MEMA_0")
	)
	(segment
		(start 33.718246 -141.361414)
		(end 33.972246 -141.361414)
		(width 0.127)
		(layer "In5.Cu")
		(net "MEMA_0")
	)
	(segment
		(start 40.736266 -142.993364)
		(end 41.271952 -142.993364)
		(width 0.127)
		(layer "In5.Cu")
		(net "MEMA_0")
	)
	(segment
		(start 36.639246 -141.19352)
		(end 36.639246 -141.234414)
		(width 0.127)
		(layer "In5.Cu")
		(net "MEMA_0")
	)
	(segment
		(start 32.956246 -141.361414)
		(end 33.083246 -141.234414)
		(width 0.127)
		(layer "In5.Cu")
		(net "MEMA_0")
	)
	(segment
		(start 20.90293 -138.980672)
		(end 23.079964 -138.980672)
		(width 0.127)
		(layer "In5.Cu")
		(net "MEMA_0")
	)
	(segment
		(start 25.381458 -138.93546)
		(end 25.381458 -138.68908)
		(width 0.127)
		(layer "In5.Cu")
		(net "MEMA_0")
	)
	(segment
		(start 35.623246 -141.19352)
		(end 35.623246 -141.234414)
		(width 0.127)
		(layer "In5.Cu")
		(net "MEMA_0")
	)
	(segment
		(start 35.115246 -141.19352)
		(end 35.242246 -141.06652)
		(width 0.127)
		(layer "In5.Cu")
		(net "MEMA_0")
	)
	(segment
		(start 29.570426 -140.9446)
		(end 29.812996 -140.9446)
		(width 0.127)
		(layer "In5.Cu")
		(net "MEMA_0")
	)
	(segment
		(start 33.464246 -141.06652)
		(end 33.591246 -141.19352)
		(width 0.127)
		(layer "In5.Cu")
		(net "MEMA_0")
	)
	(segment
		(start 33.972246 -141.361414)
		(end 34.099246 -141.234414)
		(width 0.127)
		(layer "In5.Cu")
		(net "MEMA_0")
	)
	(segment
		(start 33.210246 -141.06652)
		(end 33.464246 -141.06652)
		(width 0.127)
		(layer "In5.Cu")
		(net "MEMA_0")
	)
	(segment
		(start 36.512246 -141.06652)
		(end 36.639246 -141.19352)
		(width 0.127)
		(layer "In5.Cu")
		(net "MEMA_0")
	)
	(segment
		(start 20.710398 -138.78814)
		(end 20.90293 -138.980672)
		(width 0.127)
		(layer "In5.Cu")
		(net "MEMA_0")
	)
	(segment
		(start 34.099246 -141.19352)
		(end 34.226246 -141.06652)
		(width 0.127)
		(layer "In5.Cu")
		(net "MEMA_0")
	)
	(segment
		(start 36.258246 -141.06652)
		(end 36.512246 -141.06652)
		(width 0.127)
		(layer "In5.Cu")
		(net "MEMA_0")
	)
	(segment
		(start 25.381458 -138.68908)
		(end 25.508458 -138.56208)
		(width 0.127)
		(layer "In5.Cu")
		(net "MEMA_0")
	)
	(segment
		(start 25.000458 -139.06246)
		(end 25.254458 -139.06246)
		(width 0.127)
		(layer "In5.Cu")
		(net "MEMA_0")
	)
	(segment
		(start 35.750246 -141.361414)
		(end 36.004246 -141.361414)
		(width 0.127)
		(layer "In5.Cu")
		(net "MEMA_0")
	)
	(segment
		(start 36.131246 -141.19352)
		(end 36.258246 -141.06652)
		(width 0.127)
		(layer "In5.Cu")
		(net "MEMA_0")
	)
	(segment
		(start 33.083246 -141.19352)
		(end 33.210246 -141.06652)
		(width 0.127)
		(layer "In5.Cu")
		(net "MEMA_0")
	)
	(segment
		(start 25.889458 -138.68908)
		(end 25.889458 -138.93546)
		(width 0.127)
		(layer "In5.Cu")
		(net "MEMA_0")
	)
	(segment
		(start 37.782246 -141.361414)
		(end 37.99078 -141.361414)
		(width 0.127)
		(layer "In5.Cu")
		(net "MEMA_0")
	)
	(segment
		(start 26.397458 -138.68908)
		(end 26.524458 -138.56208)
		(width 0.127)
		(layer "In5.Cu")
		(net "MEMA_0")
	)
	(segment
		(start 26.397458 -138.93546)
		(end 26.397458 -138.68908)
		(width 0.127)
		(layer "In5.Cu")
		(net "MEMA_0")
	)
	(segment
		(start 34.480246 -141.06652)
		(end 34.607246 -141.19352)
		(width 0.127)
		(layer "In5.Cu")
		(net "MEMA_0")
	)
	(segment
		(start 30.320996 -141.42466)
		(end 30.447996 -141.29766)
		(width 0.127)
		(layer "In5.Cu")
		(net "MEMA_0")
	)
	(segment
		(start 23.079964 -138.980672)
		(end 23.518114 -138.542522)
		(width 0.127)
		(layer "In5.Cu")
		(net "MEMA_0")
	)
	(segment
		(start 34.607246 -141.234414)
		(end 34.734246 -141.361414)
		(width 0.127)
		(layer "In5.Cu")
		(net "MEMA_0")
	)
	(segment
		(start 29.939996 -141.29766)
		(end 30.066996 -141.42466)
		(width 0.127)
		(layer "In5.Cu")
		(net "MEMA_0")
	)
	(segment
		(start 34.226246 -141.06652)
		(end 34.480246 -141.06652)
		(width 0.127)
		(layer "In5.Cu")
		(net "MEMA_0")
	)
	(segment
		(start 29.939996 -141.0716)
		(end 29.939996 -141.29766)
		(width 0.127)
		(layer "In5.Cu")
		(net "MEMA_0")
	)
	(segment
		(start 24.873458 -138.93546)
		(end 25.000458 -139.06246)
		(width 0.127)
		(layer "In5.Cu")
		(net "MEMA_0")
	)
	(segment
		(start 36.131246 -141.234414)
		(end 36.131246 -141.19352)
		(width 0.127)
		(layer "In5.Cu")
		(net "MEMA_0")
	)
	(segment
		(start 26.524458 -138.56208)
		(end 27.187906 -138.56208)
		(width 0.127)
		(layer "In5.Cu")
		(net "MEMA_0")
	)
	(segment
		(start 37.99078 -141.361414)
		(end 38.83533 -142.205964)
		(width 0.127)
		(layer "In5.Cu")
		(net "MEMA_0")
	)
	(segment
		(start 18.834354 -138.561064)
		(end 19.58213 -139.30884)
		(width 0.127)
		(layer "In5.Cu")
		(net "MEMA_0")
	)
	(segment
		(start 31.566612 -141.361414)
		(end 32.956246 -141.361414)
		(width 0.127)
		(layer "In5.Cu")
		(net "MEMA_0")
	)
	(segment
		(start 35.623246 -141.234414)
		(end 35.750246 -141.361414)
		(width 0.127)
		(layer "In5.Cu")
		(net "MEMA_0")
	)
	(segment
		(start 26.016458 -139.06246)
		(end 26.270458 -139.06246)
		(width 0.127)
		(layer "In5.Cu")
		(net "MEMA_0")
	)
	(segment
		(start 24.426164 -138.56208)
		(end 24.746458 -138.56208)
		(width 0.127)
		(layer "In5.Cu")
		(net "MEMA_0")
	)
	(segment
		(start 34.607246 -141.19352)
		(end 34.607246 -141.234414)
		(width 0.127)
		(layer "In5.Cu")
		(net "MEMA_0")
	)
	(segment
		(start 29.812996 -140.9446)
		(end 29.939996 -141.0716)
		(width 0.127)
		(layer "In5.Cu")
		(net "MEMA_0")
	)
	(segment
		(start 36.004246 -141.361414)
		(end 36.131246 -141.234414)
		(width 0.127)
		(layer "In5.Cu")
		(net "MEMA_0")
	)
	(segment
		(start 19.58213 -139.30884)
		(end 19.982434 -139.30884)
		(width 0.127)
		(layer "In5.Cu")
		(net "MEMA_0")
	)
	(segment
		(start 26.270458 -139.06246)
		(end 26.397458 -138.93546)
		(width 0.127)
		(layer "In5.Cu")
		(net "MEMA_0")
	)
	(segment
		(start 27.187906 -138.56208)
		(end 29.570426 -140.9446)
		(width 0.127)
		(layer "In5.Cu")
		(net "MEMA_0")
	)
	(segment
		(start 34.734246 -141.361414)
		(end 34.988246 -141.361414)
		(width 0.127)
		(layer "In5.Cu")
		(net "MEMA_0")
	)
	(segment
		(start 37.655246 -141.19352)
		(end 37.655246 -141.234414)
		(width 0.127)
		(layer "In5.Cu")
		(net "MEMA_0")
	)
	(segment
		(start 24.873458 -138.68908)
		(end 24.873458 -138.93546)
		(width 0.127)
		(layer "In5.Cu")
		(net "MEMA_0")
	)
	(arc
		(start 40.61333 -143.018764)
		(mid 40.673499 -142.999776)
		(end 40.736266 -142.993364)
		(width 0.127)
		(layer "In5.Cu")
		(net "MEMA_0")
	)
	(arc
		(start 38.83533 -142.205964)
		(mid 39.523311 -142.751097)
		(end 40.34917 -143.048482)
		(width 0.127)
		(layer "In5.Cu")
		(net "MEMA_0")
	)
	(arc
		(start 41.70553 -143.247364)
		(mid 41.886291 -143.365182)
		(end 42.09923 -143.400018)
		(width 0.127)
		(layer "In5.Cu")
		(net "MEMA_0")
	)
	(arc
		(start 40.34917 -143.048482)
		(mid 40.483466 -143.05329)
		(end 40.61333 -143.018764)
		(width 0.127)
		(layer "In5.Cu")
		(net "MEMA_0")
	)
	(arc
		(start 41.271952 -142.993364)
		(mid 41.437875 -143.026368)
		(end 41.57853 -143.120364)
		(width 0.127)
		(layer "In5.Cu")
		(net "MEMA_0")
	)
	(segment
		(start 50.4698 -132.588)
		(end 49.8094 -133.2484)
		(width 0.127)
		(layer "F.Cu")
		(net "LPCRST0_N")
	)
	(segment
		(start 49.8094 -135.109458)
		(end 51.299872 -136.59993)
		(width 0.127)
		(layer "F.Cu")
		(net "LPCRST0_N")
	)
	(segment
		(start 50.4698 -132.1689)
		(end 50.4698 -132.588)
		(width 0.127)
		(layer "F.Cu")
		(net "LPCRST0_N")
	)
	(segment
		(start 49.8094 -133.2484)
		(end 49.8094 -135.109458)
		(width 0.127)
		(layer "F.Cu")
		(net "LPCRST0_N")
	)
	(via
		(at 49.8094 -133.2484)
		(size 0.6604)
		(drill 0.3302)
		(layers "F.Cu" "B.Cu")
		(net "LPCRST0_N")
	)
	(segment
		(start 52.899818 -145.400014)
		(end 52.499768 -145.800064)
		(width 0.127)
		(layer "F.Cu")
		(net "JTAG_BMC_TRST_N")
	)
	(via
		(at 52.499768 -145.800064)
		(size 0.4572)
		(drill 0.2032)
		(layers "F.Cu" "B.Cu")
		(net "JTAG_BMC_TRST_N")
	)
	(via
		(at 72.601582 -141.637766)
		(size 0.508)
		(drill 0.254)
		(layers "F.Cu" "B.Cu")
		(net "JTAG_BMC_TRST_N")
	)
	(segment
		(start 51.746404 -144.606264)
		(end 51.40452 -144.26438)
		(width 0.127)
		(layer "B.Cu")
		(net "JTAG_BMC_TRST_N")
	)
	(segment
		(start 51.2445 -143.27632)
		(end 51.03114 -143.06296)
		(width 0.127)
		(layer "B.Cu")
		(net "JTAG_BMC_TRST_N")
	)
	(segment
		(start 52.093368 -144.836642)
		(end 51.86299 -144.606264)
		(width 0.127)
		(layer "B.Cu")
		(net "JTAG_BMC_TRST_N")
	)
	(segment
		(start 50.01006 -143.2179)
		(end 50.165 -143.06296)
		(width 0.127)
		(layer "B.Cu")
		(net "JTAG_BMC_TRST_N")
	)
	(segment
		(start 51.86299 -144.606264)
		(end 51.746404 -144.606264)
		(width 0.127)
		(layer "B.Cu")
		(net "JTAG_BMC_TRST_N")
	)
	(segment
		(start 52.093368 -145.393664)
		(end 52.093368 -144.836642)
		(width 0.127)
		(layer "B.Cu")
		(net "JTAG_BMC_TRST_N")
	)
	(segment
		(start 51.2445 -144.10436)
		(end 51.2445 -143.27632)
		(width 0.127)
		(layer "B.Cu")
		(net "JTAG_BMC_TRST_N")
	)
	(segment
		(start 72.646794 -140.527024)
		(end 72.646794 -141.592554)
		(width 0.127)
		(layer "B.Cu")
		(net "JTAG_BMC_TRST_N")
	)
	(segment
		(start 51.40452 -144.26438)
		(end 51.2445 -144.10436)
		(width 0.127)
		(layer "B.Cu")
		(net "JTAG_BMC_TRST_N")
	)
	(segment
		(start 50.165 -143.06296)
		(end 51.03114 -143.06296)
		(width 0.127)
		(layer "B.Cu")
		(net "JTAG_BMC_TRST_N")
	)
	(segment
		(start 72.646794 -141.592554)
		(end 72.601582 -141.637766)
		(width 0.127)
		(layer "B.Cu")
		(net "JTAG_BMC_TRST_N")
	)
	(segment
		(start 52.499768 -145.800064)
		(end 52.093368 -145.393664)
		(width 0.127)
		(layer "B.Cu")
		(net "JTAG_BMC_TRST_N")
	)
	(segment
		(start 67.124834 -143.3322)
		(end 67.0306 -143.3322)
		(width 0.127)
		(layer "In5.Cu")
		(net "JTAG_BMC_TRST_N")
	)
	(segment
		(start 60.234322 -143.141446)
		(end 59.448954 -143.141446)
		(width 0.127)
		(layer "In5.Cu")
		(net "JTAG_BMC_TRST_N")
	)
	(segment
		(start 62.496954 -143.141446)
		(end 61.546486 -143.141446)
		(width 0.127)
		(layer "In5.Cu")
		(net "JTAG_BMC_TRST_N")
	)
	(segment
		(start 67.545712 -143.332454)
		(end 67.125088 -143.332454)
		(width 0.127)
		(layer "In5.Cu")
		(net "JTAG_BMC_TRST_N")
	)
	(segment
		(start 67.0306 -143.3322)
		(end 66.04 -142.3416)
		(width 0.127)
		(layer "In5.Cu")
		(net "JTAG_BMC_TRST_N")
	)
	(segment
		(start 61.488574 -143.199358)
		(end 60.292234 -143.199358)
		(width 0.127)
		(layer "In5.Cu")
		(net "JTAG_BMC_TRST_N")
	)
	(segment
		(start 60.292234 -143.199358)
		(end 60.234322 -143.141446)
		(width 0.127)
		(layer "In5.Cu")
		(net "JTAG_BMC_TRST_N")
	)
	(segment
		(start 69.492622 -141.675866)
		(end 67.836288 -143.3322)
		(width 0.127)
		(layer "In5.Cu")
		(net "JTAG_BMC_TRST_N")
	)
	(segment
		(start 72.601582 -141.637766)
		(end 72.563482 -141.675866)
		(width 0.127)
		(layer "In5.Cu")
		(net "JTAG_BMC_TRST_N")
	)
	(segment
		(start 67.125088 -143.332454)
		(end 67.124834 -143.3322)
		(width 0.127)
		(layer "In5.Cu")
		(net "JTAG_BMC_TRST_N")
	)
	(segment
		(start 59.448954 -143.141446)
		(end 59.0296 -143.5608)
		(width 0.127)
		(layer "In5.Cu")
		(net "JTAG_BMC_TRST_N")
	)
	(segment
		(start 72.563482 -141.675866)
		(end 69.492622 -141.675866)
		(width 0.127)
		(layer "In5.Cu")
		(net "JTAG_BMC_TRST_N")
	)
	(segment
		(start 67.836288 -143.3322)
		(end 67.545966 -143.3322)
		(width 0.127)
		(layer "In5.Cu")
		(net "JTAG_BMC_TRST_N")
	)
	(segment
		(start 61.546486 -143.141446)
		(end 61.488574 -143.199358)
		(width 0.127)
		(layer "In5.Cu")
		(net "JTAG_BMC_TRST_N")
	)
	(segment
		(start 57.997344 -143.5608)
		(end 56.164226 -145.393918)
		(width 0.127)
		(layer "In5.Cu")
		(net "JTAG_BMC_TRST_N")
	)
	(segment
		(start 63.2968 -142.3416)
		(end 62.496954 -143.141446)
		(width 0.127)
		(layer "In5.Cu")
		(net "JTAG_BMC_TRST_N")
	)
	(segment
		(start 66.04 -142.3416)
		(end 63.2968 -142.3416)
		(width 0.127)
		(layer "In5.Cu")
		(net "JTAG_BMC_TRST_N")
	)
	(segment
		(start 67.545966 -143.3322)
		(end 67.545712 -143.332454)
		(width 0.127)
		(layer "In5.Cu")
		(net "JTAG_BMC_TRST_N")
	)
	(segment
		(start 59.0296 -143.5608)
		(end 57.997344 -143.5608)
		(width 0.127)
		(layer "In5.Cu")
		(net "JTAG_BMC_TRST_N")
	)
	(segment
		(start 52.905914 -145.393918)
		(end 52.499768 -145.800064)
		(width 0.127)
		(layer "In5.Cu")
		(net "JTAG_BMC_TRST_N")
	)
	(segment
		(start 56.164226 -145.393918)
		(end 52.905914 -145.393918)
		(width 0.127)
		(layer "In5.Cu")
		(net "JTAG_BMC_TRST_N")
	)
	(segment
		(start 54.899814 -148.20011)
		(end 54.500018 -147.800314)
		(width 0.127)
		(layer "F.Cu")
		(net "JTAG_BMC_TMS")
	)
	(segment
		(start 54.500018 -147.800314)
		(end 54.500018 -147.80006)
		(width 0.127)
		(layer "F.Cu")
		(net "JTAG_BMC_TMS")
	)
	(via
		(at 54.899814 -148.20011)
		(size 0.4572)
		(drill 0.2032)
		(layers "F.Cu" "B.Cu")
		(net "JTAG_BMC_TMS")
	)
	(segment
		(start 55.800752 -149.122384)
		(end 55.521352 -148.842984)
		(width 0.127)
		(layer "B.Cu")
		(net "JTAG_BMC_TMS")
	)
	(segment
		(start 55.800752 -149.122384)
		(end 56.160416 -149.122384)
		(width 0.127)
		(layer "B.Cu")
		(net "JTAG_BMC_TMS")
	)
	(segment
		(start 56.160416 -149.122384)
		(end 56.4642 -148.8186)
		(width 0.127)
		(layer "B.Cu")
		(net "JTAG_BMC_TMS")
	)
	(segment
		(start 56.4642 -148.8186)
		(end 56.9595 -148.8186)
		(width 0.127)
		(layer "B.Cu")
		(net "JTAG_BMC_TMS")
	)
	(segment
		(start 55.521352 -148.842984)
		(end 55.521352 -148.821648)
		(width 0.127)
		(layer "B.Cu")
		(net "JTAG_BMC_TMS")
	)
	(segment
		(start 55.521352 -148.821648)
		(end 54.899814 -148.20011)
		(width 0.127)
		(layer "B.Cu")
		(net "JTAG_BMC_TMS")
	)
	(segment
		(start 53.699918 -145.400014)
		(end 53.699664 -145.400014)
		(width 0.127)
		(layer "F.Cu")
		(net "JTAG_BMC_TDO")
	)
	(segment
		(start 53.699664 -145.400014)
		(end 53.299614 -145.800064)
		(width 0.127)
		(layer "F.Cu")
		(net "JTAG_BMC_TDO")
	)
	(via
		(at 53.299614 -145.800064)
		(size 0.4572)
		(drill 0.2032)
		(layers "F.Cu" "B.Cu")
		(net "JTAG_BMC_TDO")
	)
	(segment
		(start 53.299614 -145.353786)
		(end 53.299614 -145.800064)
		(width 0.127)
		(layer "B.Cu")
		(net "JTAG_BMC_TDO")
	)
	(segment
		(start 56.3626 -145.2626)
		(end 56.8833 -145.2626)
		(width 0.127)
		(layer "B.Cu")
		(net "JTAG_BMC_TDO")
	)
	(segment
		(start 53.659278 -144.994122)
		(end 53.299614 -145.353786)
		(width 0.127)
		(layer "B.Cu")
		(net "JTAG_BMC_TDO")
	)
	(segment
		(start 54.153054 -144.994122)
		(end 53.659278 -144.994122)
		(width 0.127)
		(layer "B.Cu")
		(net "JTAG_BMC_TDO")
	)
	(segment
		(start 56.094122 -144.994122)
		(end 56.3626 -145.2626)
		(width 0.127)
		(layer "B.Cu")
		(net "JTAG_BMC_TDO")
	)
	(segment
		(start 54.153054 -144.994122)
		(end 56.094122 -144.994122)
		(width 0.127)
		(layer "B.Cu")
		(net "JTAG_BMC_TDO")
	)
	(segment
		(start 54.099714 -144.200372)
		(end 54.09946 -144.200372)
		(width 0.127)
		(layer "F.Cu")
		(net "JTAG_BMC_TDI")
	)
	(segment
		(start 54.09946 -144.200372)
		(end 53.699918 -144.599914)
		(width 0.127)
		(layer "F.Cu")
		(net "JTAG_BMC_TDI")
	)
	(via
		(at 54.099714 -144.200372)
		(size 0.4572)
		(drill 0.2032)
		(layers "F.Cu" "B.Cu")
		(net "JTAG_BMC_TDI")
	)
	(segment
		(start 57.8993 -144.018)
		(end 56.716168 -144.018)
		(width 0.127)
		(layer "B.Cu")
		(net "JTAG_BMC_TDI")
	)
	(segment
		(start 55.933086 -143.806418)
		(end 55.5371 -143.806418)
		(width 0.127)
		(layer "B.Cu")
		(net "JTAG_BMC_TDI")
	)
	(segment
		(start 56.144668 -144.018)
		(end 55.933086 -143.806418)
		(width 0.127)
		(layer "B.Cu")
		(net "JTAG_BMC_TDI")
	)
	(segment
		(start 56.716168 -144.018)
		(end 56.144668 -144.018)
		(width 0.127)
		(layer "B.Cu")
		(net "JTAG_BMC_TDI")
	)
	(segment
		(start 55.5371 -143.806418)
		(end 55.306722 -144.036796)
		(width 0.127)
		(layer "B.Cu")
		(net "JTAG_BMC_TDI")
	)
	(segment
		(start 54.6862 -144.594072)
		(end 54.2925 -144.200372)
		(width 0.127)
		(layer "B.Cu")
		(net "JTAG_BMC_TDI")
	)
	(segment
		(start 55.306722 -144.036796)
		(end 55.306722 -144.350486)
		(width 0.127)
		(layer "B.Cu")
		(net "JTAG_BMC_TDI")
	)
	(segment
		(start 55.306722 -144.350486)
		(end 55.063136 -144.594072)
		(width 0.127)
		(layer "B.Cu")
		(net "JTAG_BMC_TDI")
	)
	(segment
		(start 55.063136 -144.594072)
		(end 54.6862 -144.594072)
		(width 0.127)
		(layer "B.Cu")
		(net "JTAG_BMC_TDI")
	)
	(segment
		(start 54.2925 -144.200372)
		(end 54.099714 -144.200372)
		(width 0.127)
		(layer "B.Cu")
		(net "JTAG_BMC_TDI")
	)
	(segment
		(start 54.899814 -146.59991)
		(end 54.899814 -146.599656)
		(width 0.127)
		(layer "F.Cu")
		(net "JTAG_BMC_TCK")
	)
	(segment
		(start 54.899814 -146.599656)
		(end 54.500018 -146.19986)
		(width 0.127)
		(layer "F.Cu")
		(net "JTAG_BMC_TCK")
	)
	(via
		(at 54.899814 -146.59991)
		(size 0.4572)
		(drill 0.2032)
		(layers "F.Cu" "B.Cu")
		(net "JTAG_BMC_TCK")
	)
	(segment
		(start 55.90413 -146.511264)
		(end 55.788052 -146.395186)
		(width 0.127)
		(layer "B.Cu")
		(net "JTAG_BMC_TCK")
	)
	(segment
		(start 55.185056 -146.395186)
		(end 55.788052 -146.395186)
		(width 0.127)
		(layer "B.Cu")
		(net "JTAG_BMC_TCK")
	)
	(segment
		(start 54.899814 -146.59991)
		(end 54.980332 -146.59991)
		(width 0.127)
		(layer "B.Cu")
		(net "JTAG_BMC_TCK")
	)
	(segment
		(start 56.97855 -146.511264)
		(end 55.90413 -146.511264)
		(width 0.127)
		(layer "B.Cu")
		(net "JTAG_BMC_TCK")
	)
	(segment
		(start 54.980332 -146.59991)
		(end 55.185056 -146.395186)
		(width 0.127)
		(layer "B.Cu")
		(net "JTAG_BMC_TCK")
	)
	(segment
		(start 89.292938 -164.661596)
		(end 90.1954 -165.564058)
		(width 0.508)
		(layer "F.Cu")
		(net "GND")
	)
	(segment
		(start 47.115476 -142.815564)
		(end 46.684438 -142.815564)
		(width 0.3556)
		(layer "F.Cu")
		(net "GND")
	)
	(segment
		(start 50.4698 -131.2799)
		(end 50.4698 -130.429)
		(width 0.508)
		(layer "F.Cu")
		(net "GND")
	)
	(segment
		(start 91.096084 -151.7904)
		(end 91.251532 -151.945848)
		(width 0.254)
		(layer "F.Cu")
		(net "GND")
	)
	(segment
		(start 43.700192 -149.800056)
		(end 43.700192 -149.799802)
		(width 0.3556)
		(layer "F.Cu")
		(net "GND")
	)
	(segment
		(start 93.795342 -164.051234)
		(end 95.0468 -164.051234)
		(width 0.508)
		(layer "F.Cu")
		(net "GND")
	)
	(segment
		(start 47.71263 -145.81251)
		(end 48.09998 -146.19986)
		(width 0.3556)
		(layer "F.Cu")
		(net "GND")
	)
	(segment
		(start 77.516228 -57.778396)
		(end 77.567028 -57.778396)
		(width 0.508)
		(layer "F.Cu")
		(net "GND")
	)
	(segment
		(start 77.490828 -62.959996)
		(end 77.837284 -62.959996)
		(width 0.254)
		(layer "F.Cu")
		(net "GND")
	)
	(segment
		(start 16.458184 -165.327584)
		(end 16.480536 -165.349936)
		(width 0.508)
		(layer "F.Cu")
		(net "GND")
	)
	(segment
		(start 96.7232 -21.9202)
		(end 97.155 -22.352)
		(width 0.508)
		(layer "F.Cu")
		(net "GND")
	)
	(segment
		(start 125.2855 -7.62)
		(end 126.084076 -7.62)
		(width 0.254)
		(layer "F.Cu")
		(net "GND")
	)
	(segment
		(start 100.2792 -155.3718)
		(end 99.7204 -155.9306)
		(width 0.508)
		(layer "F.Cu")
		(net "GND")
	)
	(segment
		(start 77.026516 -72.95007)
		(end 77.283818 -72.692768)
		(width 0.508)
		(layer "F.Cu")
		(net "GND")
	)
	(segment
		(start 75.475084 -85.750146)
		(end 77.02804 -85.750146)
		(width 0.508)
		(layer "F.Cu")
		(net "GND")
	)
	(segment
		(start 90.3478 -129.54)
		(end 90.3478 -129.61112)
		(width 0.254)
		(layer "F.Cu")
		(net "GND")
	)
	(segment
		(start 8.636 -13.843)
		(end 8.636 -15.0876)
		(width 0.508)
		(layer "F.Cu")
		(net "GND")
	)
	(segment
		(start 71.890128 -187.054744)
		(end 71.890128 -187.792614)
		(width 0.508)
		(layer "F.Cu")
		(net "GND")
	)
	(segment
		(start 23.055072 -15.11427)
		(end 24.134572 -14.03477)
		(width 0.508)
		(layer "F.Cu")
		(net "GND")
	)
	(segment
		(start 98.8187 -137.4394)
		(end 98.8695 -137.3886)
		(width 0.508)
		(layer "F.Cu")
		(net "GND")
	)
	(segment
		(start 87.638636 -32.667448)
		(end 86.539324 -32.667448)
		(width 0.508)
		(layer "F.Cu")
		(net "GND")
	)
	(segment
		(start 75.475084 -82.55)
		(end 76.748386 -82.55)
		(width 0.508)
		(layer "F.Cu")
		(net "GND")
	)
	(segment
		(start 44.499784 -149.800056)
		(end 44.499784 -149.799802)
		(width 0.3556)
		(layer "F.Cu")
		(net "GND")
	)
	(segment
		(start 52.8828 -163.0045)
		(end 52.8828 -163.957)
		(width 0.508)
		(layer "F.Cu")
		(net "GND")
	)
	(segment
		(start 42.500042 -141.400022)
		(end 42.099992 -141.800072)
		(width 0.3556)
		(layer "F.Cu")
		(net "GND")
	)
	(segment
		(start 123.661424 -12.052046)
		(end 123.663456 -12.054078)
		(width 0.508)
		(layer "F.Cu")
		(net "GND")
	)
	(segment
		(start 79.925164 -96.149922)
		(end 81.143602 -96.149922)
		(width 0.254)
		(layer "F.Cu")
		(net "GND")
	)
	(segment
		(start 208.3181 -108.1532)
		(end 208.3181 -106.9467)
		(width 0.508)
		(layer "F.Cu")
		(net "GND")
	)
	(segment
		(start 74.718418 -148.810472)
		(end 75.632818 -148.810472)
		(width 0.508)
		(layer "F.Cu")
		(net "GND")
	)
	(segment
		(start 68.6562 -157.158944)
		(end 68.712334 -157.10281)
		(width 0.254)
		(layer "F.Cu")
		(net "GND")
	)
	(segment
		(start 47.69993 -150.600156)
		(end 47.699676 -150.600156)
		(width 0.3556)
		(layer "F.Cu")
		(net "GND")
	)
	(segment
		(start 57.9628 -163.2331)
		(end 58.928 -163.2331)
		(width 0.508)
		(layer "F.Cu")
		(net "GND")
	)
	(segment
		(start 215.32088 -93.695266)
		(end 215.32088 -94.252288)
		(width 0.508)
		(layer "F.Cu")
		(net "GND")
	)
	(segment
		(start 87.638636 -28.476448)
		(end 87.638636 -27.576272)
		(width 0.508)
		(layer "F.Cu")
		(net "GND")
	)
	(segment
		(start 166.073582 -134.66953)
		(end 166.928546 -134.66953)
		(width 0.508)
		(layer "F.Cu")
		(net "GND")
	)
	(segment
		(start 94.1451 -49.165256)
		(end 94.1832 -49.203356)
		(width 0.508)
		(layer "F.Cu")
		(net "GND")
	)
	(segment
		(start 79.925164 -64.950086)
		(end 81.259934 -64.950086)
		(width 0.508)
		(layer "F.Cu")
		(net "GND")
	)
	(segment
		(start 22.834346 -145.761456)
		(end 22.43455 -145.36166)
		(width 0.3048)
		(layer "F.Cu")
		(net "GND")
	)
	(segment
		(start 79.925164 -90.549984)
		(end 81.182718 -90.549984)
		(width 0.508)
		(layer "F.Cu")
		(net "GND")
	)
	(segment
		(start 47.29988 -149.400006)
		(end 47.29988 -149.399752)
		(width 0.3556)
		(layer "F.Cu")
		(net "GND")
	)
	(segment
		(start 51.699668 -149.799802)
		(end 51.299872 -149.400006)
		(width 0.3556)
		(layer "F.Cu")
		(net "GND")
	)
	(segment
		(start 89.289128 -45.384212)
		(end 89.447116 -45.5422)
		(width 0.254)
		(layer "F.Cu")
		(net "GND")
	)
	(segment
		(start 175.150018 -134.875016)
		(end 175.150018 -133.225794)
		(width 0.254)
		(layer "F.Cu")
		(net "GND")
	)
	(segment
		(start 62.476634 -175.964596)
		(end 62.476634 -177.3936)
		(width 0.254)
		(layer "F.Cu")
		(net "GND")
	)
	(segment
		(start 86.66734 -152.40508)
		(end 85.7885 -151.52624)
		(width 0.381)
		(layer "F.Cu")
		(net "GND")
	)
	(segment
		(start 76.749148 -88.950038)
		(end 77.283818 -88.415368)
		(width 0.508)
		(layer "F.Cu")
		(net "GND")
	)
	(segment
		(start 91.9861 -54.400196)
		(end 92.44965 -53.936646)
		(width 0.381)
		(layer "F.Cu")
		(net "GND")
	)
	(segment
		(start 14.0335 -6.466332)
		(end 14.249908 -6.249924)
		(width 0.508)
		(layer "F.Cu")
		(net "GND")
	)
	(segment
		(start 71.53783 -139.546076)
		(end 72.5932 -139.546076)
		(width 0.3556)
		(layer "F.Cu")
		(net "GND")
	)
	(segment
		(start 81.577688 -55.698136)
		(end 82.255868 -55.698136)
		(width 0.254)
		(layer "F.Cu")
		(net "GND")
	)
	(segment
		(start 40.099996 -142.199868)
		(end 40.099488 -142.199868)
		(width 0.3556)
		(layer "F.Cu")
		(net "GND")
	)
	(segment
		(start 66.8147 -168.274492)
		(end 66.757804 -168.217596)
		(width 0.508)
		(layer "F.Cu")
		(net "GND")
	)
	(segment
		(start 100.042726 -146.565874)
		(end 100.1522 -146.4564)
		(width 0.381)
		(layer "F.Cu")
		(net "GND")
	)
	(segment
		(start 48.122332 -143.800068)
		(end 48.09998 -143.800068)
		(width 0.3556)
		(layer "F.Cu")
		(net "GND")
	)
	(segment
		(start 49.299622 -144.200372)
		(end 49.299368 -144.200372)
		(width 0.3556)
		(layer "F.Cu")
		(net "GND")
	)
	(segment
		(start 89.123266 -132.1816)
		(end 89.250266 -132.3086)
		(width 0.508)
		(layer "F.Cu")
		(net "GND")
	)
	(segment
		(start 46.900084 -141.00048)
		(end 47.29988 -140.600684)
		(width 0.3048)
		(layer "F.Cu")
		(net "GND")
	)
	(segment
		(start 23.233888 -141.361668)
		(end 22.834346 -141.76121)
		(width 0.254)
		(layer "F.Cu")
		(net "GND")
	)
	(segment
		(start 198.649844 -134.875016)
		(end 198.649844 -136.25449)
		(width 0.254)
		(layer "F.Cu")
		(net "GND")
	)
	(segment
		(start 16.04137 -166.651178)
		(end 16.04137 -165.789102)
		(width 0.254)
		(layer "F.Cu")
		(net "GND")
	)
	(segment
		(start 25.007316 -162.3441)
		(end 26.6319 -162.3441)
		(width 0.508)
		(layer "F.Cu")
		(net "GND")
	)
	(segment
		(start 79.057246 -135.419846)
		(end 78.084426 -135.419846)
		(width 0.3048)
		(layer "F.Cu")
		(net "GND")
	)
	(segment
		(start 67.146932 -154.470608)
		(end 67.146932 -157.290008)
		(width 0.508)
		(layer "F.Cu")
		(net "GND")
	)
	(segment
		(start 43.299888 -145.39976)
		(end 43.299888 -145.400014)
		(width 0.3556)
		(layer "F.Cu")
		(net "GND")
	)
	(segment
		(start 48.499776 -143.422624)
		(end 48.122332 -143.800068)
		(width 0.3556)
		(layer "F.Cu")
		(net "GND")
	)
	(segment
		(start 16.834612 -144.56156)
		(end 16.834358 -144.56156)
		(width 0.3048)
		(layer "F.Cu")
		(net "GND")
	)
	(segment
		(start 47.687484 -144.187926)
		(end 47.687484 -144.187672)
		(width 0.3556)
		(layer "F.Cu")
		(net "GND")
	)
	(segment
		(start 39.114984 -153.585164)
		(end 38.899846 -153.800302)
		(width 0.254)
		(layer "F.Cu")
		(net "GND")
	)
	(segment
		(start 47.29988 -140.600684)
		(end 47.29988 -140.599922)
		(width 0.3048)
		(layer "F.Cu")
		(net "GND")
	)
	(segment
		(start 81.182464 -80.950054)
		(end 81.643728 -80.48879)
		(width 0.508)
		(layer "F.Cu")
		(net "GND")
	)
	(segment
		(start 89.916 -29.464)
		(end 88.773 -29.464)
		(width 0.254)
		(layer "F.Cu")
		(net "GND")
	)
	(segment
		(start 79.925164 -68.149978)
		(end 81.14284 -68.149978)
		(width 0.508)
		(layer "F.Cu")
		(net "GND")
	)
	(segment
		(start 75.475084 -76.149962)
		(end 76.747624 -76.149962)
		(width 0.508)
		(layer "F.Cu")
		(net "GND")
	)
	(segment
		(start 81.371948 -73.749916)
		(end 81.758028 -74.135996)
		(width 0.508)
		(layer "F.Cu")
		(net "GND")
	)
	(segment
		(start 51.689 -131.2799)
		(end 51.689 -130.429)
		(width 0.3048)
		(layer "F.Cu")
		(net "GND")
	)
	(segment
		(start 79.925164 -80.950054)
		(end 81.182464 -80.950054)
		(width 0.508)
		(layer "F.Cu")
		(net "GND")
	)
	(segment
		(start 75.475084 -78.550008)
		(end 76.740258 -78.550008)
		(width 0.508)
		(layer "F.Cu")
		(net "GND")
	)
	(segment
		(start 16.834104 -142.961614)
		(end 16.434054 -143.361664)
		(width 0.3048)
		(layer "F.Cu")
		(net "GND")
	)
	(segment
		(start 49.299622 -143.400526)
		(end 49.299622 -143.400272)
		(width 0.3556)
		(layer "F.Cu")
		(net "GND")
	)
	(segment
		(start 14.0335 -11.43)
		(end 14.0335 -6.466332)
		(width 0.508)
		(layer "F.Cu")
		(net "GND")
	)
	(segment
		(start 51.699668 -149.800056)
		(end 51.699668 -149.799802)
		(width 0.3556)
		(layer "F.Cu")
		(net "GND")
	)
	(segment
		(start 48.09998 -145.400014)
		(end 48.499776 -145.79981)
		(width 0.3556)
		(layer "F.Cu")
		(net "GND")
	)
	(segment
		(start 206.149956 -134.875016)
		(end 206.149956 -136.25449)
		(width 0.254)
		(layer "F.Cu")
		(net "GND")
	)
	(segment
		(start 125.2855 -8.5344)
		(end 125.3871 -8.636)
		(width 0.254)
		(layer "F.Cu")
		(net "GND")
	)
	(segment
		(start 178.8541 -107.6452)
		(end 178.0286 -107.6452)
		(width 0.508)
		(layer "F.Cu")
		(net "GND")
	)
	(segment
		(start 153.351738 -17.248378)
		(end 153.351738 -18.137378)
		(width 0.508)
		(layer "F.Cu")
		(net "GND")
	)
	(segment
		(start 209.14995 -134.875016)
		(end 209.14995 -135.79475)
		(width 0.254)
		(layer "F.Cu")
		(net "GND")
	)
	(segment
		(start 81.108042 -64.149986)
		(end 81.584038 -64.625982)
		(width 0.508)
		(layer "F.Cu")
		(net "GND")
	)
	(segment
		(start 81.304892 -86.549992)
		(end 81.643728 -86.888828)
		(width 0.508)
		(layer "F.Cu")
		(net "GND")
	)
	(segment
		(start 47.29988 -148.60016)
		(end 47.29988 -148.599906)
		(width 0.3556)
		(layer "F.Cu")
		(net "GND")
	)
	(segment
		(start 212.649816 -134.875016)
		(end 212.649816 -136.25449)
		(width 0.254)
		(layer "F.Cu")
		(net "GND")
	)
	(segment
		(start 56.28005 -174.994824)
		(end 56.28005 -176.6316)
		(width 0.254)
		(layer "F.Cu")
		(net "GND")
	)
	(segment
		(start 49.299368 -144.200372)
		(end 48.899826 -144.599914)
		(width 0.3556)
		(layer "F.Cu")
		(net "GND")
	)
	(segment
		(start 25.007316 -164.3507)
		(end 26.5557 -164.3507)
		(width 0.508)
		(layer "F.Cu")
		(net "GND")
	)
	(segment
		(start 49.699926 -137.40003)
		(end 50.099722 -137.000234)
		(width 0.3556)
		(layer "F.Cu")
		(net "GND")
	)
	(segment
		(start 12.954 -13.208)
		(end 12.954 -15.113)
		(width 0.508)
		(layer "F.Cu")
		(net "GND")
	)
	(segment
		(start 215.026494 -43.047412)
		(end 215.0237 -43.044618)
		(width 0.508)
		(layer "F.Cu")
		(net "GND")
	)
	(segment
		(start 172.150024 -134.875016)
		(end 172.150024 -133.225794)
		(width 0.254)
		(layer "F.Cu")
		(net "GND")
	)
	(segment
		(start 59.436 -158.8135)
		(end 59.436 -159.6136)
		(width 0.508)
		(layer "F.Cu")
		(net "GND")
	)
	(segment
		(start 70.6501 -161.8615)
		(end 70.6501 -162.756088)
		(width 0.508)
		(layer "F.Cu")
		(net "GND")
	)
	(segment
		(start 24.134572 -14.03477)
		(end 24.147272 -14.02207)
		(width 0.508)
		(layer "F.Cu")
		(net "GND")
	)
	(segment
		(start 51.679602 -153.7843)
		(end 51.299872 -153.40457)
		(width 0.3556)
		(layer "F.Cu")
		(net "GND")
	)
	(segment
		(start 86.66734 -153.01468)
		(end 86.66734 -152.40508)
		(width 0.381)
		(layer "F.Cu")
		(net "GND")
	)
	(segment
		(start 204.478636 -103.06939)
		(end 205.067662 -103.06939)
		(width 0.254)
		(layer "F.Cu")
		(net "GND")
	)
	(segment
		(start 48.899826 -137.40003)
		(end 49.299876 -136.99998)
		(width 0.254)
		(layer "F.Cu")
		(net "GND")
	)
	(segment
		(start 93.0656 -50.546)
		(end 93.68663 -50.546)
		(width 0.508)
		(layer "F.Cu")
		(net "GND")
	)
	(segment
		(start 56.515 -160.0708)
		(end 56.3626 -159.9184)
		(width 0.508)
		(layer "F.Cu")
		(net "GND")
	)
	(segment
		(start 46.900084 -145.000218)
		(end 46.500034 -144.600168)
		(width 0.3556)
		(layer "F.Cu")
		(net "GND")
	)
	(segment
		(start 72.5678 -153.6192)
		(end 70.485 -153.6192)
		(width 0.508)
		(layer "F.Cu")
		(net "GND")
	)
	(segment
		(start 91.195144 -161.451544)
		(end 91.186 -161.4424)
		(width 0.254)
		(layer "F.Cu")
		(net "GND")
	)
	(segment
		(start 43.700446 -141.00048)
		(end 44.099988 -141.400022)
		(width 0.3556)
		(layer "F.Cu")
		(net "GND")
	)
	(segment
		(start 79.925164 -71.350124)
		(end 81.182464 -71.350124)
		(width 0.508)
		(layer "F.Cu")
		(net "GND")
	)
	(segment
		(start 34.802318 -136.59993)
		(end 34.791396 -136.589008)
		(width 0.508)
		(layer "F.Cu")
		(net "GND")
	)
	(segment
		(start 81.1657 -133.1595)
		(end 80.8228 -132.8166)
		(width 0.508)
		(layer "F.Cu")
		(net "GND")
	)
	(segment
		(start 48.708818 -172.699934)
		(end 48.708564 -172.69968)
		(width 0.508)
		(layer "F.Cu")
		(net "GND")
	)
	(segment
		(start 91.195144 -162.52952)
		(end 91.195144 -161.451544)
		(width 0.254)
		(layer "F.Cu")
		(net "GND")
	)
	(segment
		(start 178.150012 -134.875016)
		(end 178.150012 -133.225794)
		(width 0.254)
		(layer "F.Cu")
		(net "GND")
	)
	(segment
		(start 51.71567 -153.878534)
		(end 51.71567 -153.820368)
		(width 0.254)
		(layer "F.Cu")
		(net "GND")
	)
	(segment
		(start 16.834612 -138.961622)
		(end 15.619222 -138.961622)
		(width 0.254)
		(layer "F.Cu")
		(net "GND")
	)
	(segment
		(start 76.747624 -76.149962)
		(end 77.283818 -75.613768)
		(width 0.508)
		(layer "F.Cu")
		(net "GND")
	)
	(segment
		(start 181.150006 -134.875016)
		(end 181.150006 -133.225794)
		(width 0.254)
		(layer "F.Cu")
		(net "GND")
	)
	(segment
		(start 48.899826 -143.000476)
		(end 48.899826 -142.999968)
		(width 0.3556)
		(layer "F.Cu")
		(net "GND")
	)
	(segment
		(start 47.335948 -150.199852)
		(end 47.29988 -150.199852)
		(width 0.3556)
		(layer "F.Cu")
		(net "GND")
	)
	(segment
		(start 98.5012 -134.4676)
		(end 98.8695 -134.8359)
		(width 0.508)
		(layer "F.Cu")
		(net "GND")
	)
	(segment
		(start 49.699418 -144.599914)
		(end 49.299876 -144.200372)
		(width 0.3556)
		(layer "F.Cu")
		(net "GND")
	)
	(segment
		(start 64.724534 -159.258)
		(end 64.92494 -159.057594)
		(width 0.254)
		(layer "F.Cu")
		(net "GND")
	)
	(segment
		(start 48.50003 -145.800064)
		(end 48.899826 -146.19986)
		(width 0.3556)
		(layer "F.Cu")
		(net "GND")
	)
	(segment
		(start 77.150214 -159.729678)
		(end 77.150214 -158.867602)
		(width 0.254)
		(layer "F.Cu")
		(net "GND")
	)
	(segment
		(start 79.925164 -93.75013)
		(end 81.080864 -93.75013)
		(width 0.508)
		(layer "F.Cu")
		(net "GND")
	)
	(segment
		(start 62.0649 -152.908)
		(end 61.8109 -152.654)
		(width 0.508)
		(layer "F.Cu")
		(net "GND")
	)
	(segment
		(start 47.73295 -143.331184)
		(end 47.401734 -142.999968)
		(width 0.3556)
		(layer "F.Cu")
		(net "GND")
	)
	(segment
		(start 77.088238 -68.950078)
		(end 77.355192 -69.217032)
		(width 0.508)
		(layer "F.Cu")
		(net "GND")
	)
	(segment
		(start 46.96333 -145.838164)
		(end 46.52518 -145.400014)
		(width 0.3556)
		(layer "F.Cu")
		(net "GND")
	)
	(segment
		(start 99.0219 -143.3576)
		(end 99.8474 -143.3576)
		(width 0.508)
		(layer "F.Cu")
		(net "GND")
	)
	(segment
		(start 75.475084 -52.15001)
		(end 77.63891 -52.15001)
		(width 0.508)
		(layer "F.Cu")
		(net "GND")
	)
	(segment
		(start 30.3022 -129.9464)
		(end 30.3276 -129.921)
		(width 0.508)
		(layer "F.Cu")
		(net "GND")
	)
	(segment
		(start 24.147272 -10.852658)
		(end 26.249884 -8.750046)
		(width 0.508)
		(layer "F.Cu")
		(net "GND")
	)
	(segment
		(start 72.37603 -146.421602)
		(end 71.363078 -146.421602)
		(width 0.508)
		(layer "F.Cu")
		(net "GND")
	)
	(segment
		(start 44.499784 -149.799802)
		(end 44.099988 -149.400006)
		(width 0.3556)
		(layer "F.Cu")
		(net "GND")
	)
	(segment
		(start 24.147272 -14.02207)
		(end 24.147272 -10.852658)
		(width 0.508)
		(layer "F.Cu")
		(net "GND")
	)
	(segment
		(start 23.234396 -146.961352)
		(end 23.634192 -146.561556)
		(width 0.254)
		(layer "F.Cu")
		(net "GND")
	)
	(segment
		(start 62.760352 -154.999944)
		(end 62.760352 -155.584652)
		(width 0.508)
		(layer "F.Cu")
		(net "GND")
	)
	(segment
		(start 208.3181 -106.9467)
		(end 208.8642 -106.4006)
		(width 0.508)
		(layer "F.Cu")
		(net "GND")
	)
	(segment
		(start 27.50947 -146.606768)
		(end 27.526234 -146.623532)
		(width 0.508)
		(layer "F.Cu")
		(net "GND")
	)
	(segment
		(start 89.8652 -132.3086)
		(end 90.368374 -132.811774)
		(width 0.508)
		(layer "F.Cu")
		(net "GND")
	)
	(segment
		(start 71.48068 -161.8615)
		(end 70.6501 -161.8615)
		(width 0.508)
		(layer "F.Cu")
		(net "GND")
	)
	(segment
		(start 49.13503 -147.235164)
		(end 48.899826 -146.99996)
		(width 0.3556)
		(layer "F.Cu")
		(net "GND")
	)
	(segment
		(start 50.899822 -149.799802)
		(end 50.500026 -149.400006)
		(width 0.3556)
		(layer "F.Cu")
		(net "GND")
	)
	(segment
		(start 52.499514 -141.00048)
		(end 52.099972 -141.400022)
		(width 0.3556)
		(layer "F.Cu")
		(net "GND")
	)
	(segment
		(start 48.50003 -146.600164)
		(end 48.899826 -146.99996)
		(width 0.3556)
		(layer "F.Cu")
		(net "GND")
	)
	(segment
		(start 76.8223 -69.749924)
		(end 77.355192 -69.217032)
		(width 0.508)
		(layer "F.Cu")
		(net "GND")
	)
	(segment
		(start 16.834612 -142.961614)
		(end 16.834104 -142.961614)
		(width 0.3048)
		(layer "F.Cu")
		(net "GND")
	)
	(segment
		(start 80.6704 -153.238708)
		(end 80.663288 -153.231596)
		(width 0.508)
		(layer "F.Cu")
		(net "GND")
	)
	(segment
		(start 92.012262 -139.077446)
		(end 90.357706 -139.077446)
		(width 0.254)
		(layer "F.Cu")
		(net "GND")
	)
	(segment
		(start 47.29988 -141.400022)
		(end 46.900338 -141.00048)
		(width 0.3556)
		(layer "F.Cu")
		(net "GND")
	)
	(segment
		(start 46.89983 -146.600164)
		(end 46.500034 -146.99996)
		(width 0.3556)
		(layer "F.Cu")
		(net "GND")
	)
	(segment
		(start 78.43901 -52.95011)
		(end 77.827378 -52.338478)
		(width 0.508)
		(layer "F.Cu")
		(net "GND")
	)
	(segment
		(start 61.9633 -149.7584)
		(end 62.6872 -149.7584)
		(width 0.254)
		(layer "F.Cu")
		(net "GND")
	)
	(segment
		(start 89.45372 -163.122356)
		(end 89.45372 -163.90747)
		(width 0.508)
		(layer "F.Cu")
		(net "GND")
	)
	(segment
		(start 49.299622 -145.79981)
		(end 48.899826 -145.400014)
		(width 0.3556)
		(layer "F.Cu")
		(net "GND")
	)
	(segment
		(start 51.71567 -153.820368)
		(end 51.679602 -153.7843)
		(width 0.254)
		(layer "F.Cu")
		(net "GND")
	)
	(segment
		(start 74.718418 -148.810472)
		(end 74.176128 -148.810472)
		(width 0.508)
		(layer "F.Cu")
		(net "GND")
	)
	(segment
		(start 74.58583 -136.980676)
		(end 74.58583 -137.421112)
		(width 0.508)
		(layer "F.Cu")
		(net "GND")
	)
	(segment
		(start 47.879 -175.2727)
		(end 47.879 -174.4472)
		(width 0.254)
		(layer "F.Cu")
		(net "GND")
	)
	(segment
		(start 48.6156 -129.286)
		(end 48.615092 -129.286)
		(width 0.508)
		(layer "F.Cu")
		(net "GND")
	)
	(segment
		(start 75.103228 -169.896028)
		(end 75.467972 -169.896028)
		(width 0.508)
		(layer "F.Cu")
		(net "GND")
	)
	(segment
		(start 180.4797 -5.84835)
		(end 180.4797 -4.7117)
		(width 0.508)
		(layer "F.Cu")
		(net "GND")
	)
	(segment
		(start 42.900092 -149.799802)
		(end 43.299888 -149.400006)
		(width 0.3556)
		(layer "F.Cu")
		(net "GND")
	)
	(segment
		(start 93.8276 -29.4513)
		(end 92.3036 -29.4513)
		(width 0.508)
		(layer "F.Cu")
		(net "GND")
	)
	(segment
		(start 94.1832 -49.203356)
		(end 94.1832 -50.04943)
		(width 0.508)
		(layer "F.Cu")
		(net "GND")
	)
	(segment
		(start 47.699676 -150.600156)
		(end 47.29988 -150.999952)
		(width 0.3556)
		(layer "F.Cu")
		(net "GND")
	)
	(segment
		(start 64.92494 -159.057594)
		(end 64.92494 -158.905194)
		(width 0.254)
		(layer "F.Cu")
		(net "GND")
	)
	(segment
		(start 82.255868 -55.543196)
		(end 82.255868 -55.698136)
		(width 0.254)
		(layer "F.Cu")
		(net "GND")
	)
	(segment
		(start 50.500026 -150.999952)
		(end 50.899822 -151.399748)
		(width 0.3556)
		(layer "F.Cu")
		(net "GND")
	)
	(segment
		(start 81.080864 -93.75013)
		(end 81.491328 -93.339666)
		(width 0.508)
		(layer "F.Cu")
		(net "GND")
	)
	(segment
		(start 95.43288 -19.98472)
		(end 95.504 -19.9136)
		(width 0.3048)
		(layer "F.Cu")
		(net "GND")
	)
	(segment
		(start 202.946 -111.2139)
		(end 202.946 -112.0394)
		(width 0.508)
		(layer "F.Cu")
		(net "GND")
	)
	(segment
		(start 207.649826 -134.875016)
		(end 207.649826 -136.25449)
		(width 0.254)
		(layer "F.Cu")
		(net "GND")
	)
	(segment
		(start 19.0627 -145.36166)
		(end 19.100038 -145.398998)
		(width 0.254)
		(layer "F.Cu")
		(net "GND")
	)
	(segment
		(start 90.8812 -178.55184)
		(end 89.6112 -178.55184)
		(width 0.4572)
		(layer "F.Cu")
		(net "GND")
	)
	(segment
		(start 16.834612 -136.561576)
		(end 16.833342 -136.561576)
		(width 0.3048)
		(layer "F.Cu")
		(net "GND")
	)
	(segment
		(start 10.922 -13.843)
		(end 10.922 -15.113)
		(width 0.508)
		(layer "F.Cu")
		(net "GND")
	)
	(segment
		(start 81.14284 -68.149978)
		(end 81.605374 -67.687444)
		(width 0.508)
		(layer "F.Cu")
		(net "GND")
	)
	(segment
		(start 49.699926 -143.000222)
		(end 49.299622 -143.400526)
		(width 0.3556)
		(layer "F.Cu")
		(net "GND")
	)
	(segment
		(start 53.299868 -148.199856)
		(end 52.900072 -147.80006)
		(width 0.3556)
		(layer "F.Cu")
		(net "GND")
	)
	(segment
		(start 77.02804 -85.750146)
		(end 77.283818 -85.494368)
		(width 0.508)
		(layer "F.Cu")
		(net "GND")
	)
	(segment
		(start 66.71183 -179.90439)
		(end 66.71183 -180.88737)
		(width 0.508)
		(layer "F.Cu")
		(net "GND")
	)
	(segment
		(start 47.700184 -146.600164)
		(end 47.69993 -146.600164)
		(width 0.3556)
		(layer "F.Cu")
		(net "GND")
	)
	(segment
		(start 29.367226 -179.57673)
		(end 28.64993 -179.57673)
		(width 0.508)
		(layer "F.Cu")
		(net "GND")
	)
	(segment
		(start 79.925164 -52.95011)
		(end 78.43901 -52.95011)
		(width 0.508)
		(layer "F.Cu")
		(net "GND")
	)
	(segment
		(start 86.1949 -167.29075)
		(end 84.5185 -167.29075)
		(width 0.508)
		(layer "F.Cu")
		(net "GND")
	)
	(segment
		(start 27.50947 -146.308572)
		(end 27.50947 -146.606768)
		(width 0.508)
		(layer "F.Cu")
		(net "GND")
	)
	(segment
		(start 99.304094 -146.565874)
		(end 100.042726 -146.565874)
		(width 0.381)
		(layer "F.Cu")
		(net "GND")
	)
	(segment
		(start 50.899822 -149.800056)
		(end 50.899822 -149.799802)
		(width 0.3556)
		(layer "F.Cu")
		(net "GND")
	)
	(segment
		(start 84.2645 -147.674076)
		(end 84.63153 -147.307046)
		(width 0.508)
		(layer "F.Cu")
		(net "GND")
	)
	(segment
		(start 53.773324 -162.926268)
		(end 53.773324 -163.918646)
		(width 0.508)
		(layer "F.Cu")
		(net "GND")
	)
	(segment
		(start 92.6084 -125.8443)
		(end 92.6084 -126.401068)
		(width 0.254)
		(layer "F.Cu")
		(net "GND")
	)
	(segment
		(start 38.38702 -178.68011)
		(end 38.38702 -178.67376)
		(width 0.508)
		(layer "F.Cu")
		(net "GND")
	)
	(segment
		(start 147.141438 -9.450578)
		(end 146.537426 -10.05459)
		(width 0.508)
		(layer "F.Cu")
		(net "GND")
	)
	(segment
		(start 66.808604 -169.170096)
		(end 66.8147 -169.164)
		(width 0.508)
		(layer "F.Cu")
		(net "GND")
	)
	(segment
		(start 88.23706 -134.2263)
		(end 87.99576 -133.985)
		(width 0.508)
		(layer "F.Cu")
		(net "GND")
	)
	(segment
		(start 62.760352 -155.584652)
		(end 62.9666 -155.7909)
		(width 0.508)
		(layer "F.Cu")
		(net "GND")
	)
	(segment
		(start 63.62065 -160.979104)
		(end 64.140842 -160.979104)
		(width 0.508)
		(layer "F.Cu")
		(net "GND")
	)
	(segment
		(start 209.14995 -135.79475)
		(end 209.55 -136.1948)
		(width 0.254)
		(layer "F.Cu")
		(net "GND")
	)
	(segment
		(start 49.299876 -144.200372)
		(end 49.299622 -144.200372)
		(width 0.3556)
		(layer "F.Cu")
		(net "GND")
	)
	(segment
		(start 73.787 -154.8384)
		(end 72.5678 -153.6192)
		(width 0.508)
		(layer "F.Cu")
		(net "GND")
	)
	(segment
		(start 90.548206 -129.811526)
		(end 91.805506 -129.811526)
		(width 0.254)
		(layer "F.Cu")
		(net "GND")
	)
	(segment
		(start 56.099964 -153.400252)
		(end 56.099964 -153.399998)
		(width 0.254)
		(layer "F.Cu")
		(net "GND")
	)
	(segment
		(start 60.404502 -136.942068)
		(end 59.933586 -136.942068)
		(width 0.508)
		(layer "F.Cu")
		(net "GND")
	)
	(segment
		(start 25.6794 -130.0099)
		(end 26.7589 -130.0099)
		(width 0.508)
		(layer "F.Cu")
		(net "GND")
	)
	(segment
		(start 64.732408 -166.71925)
		(end 64.0715 -166.71925)
		(width 0.508)
		(layer "F.Cu")
		(net "GND")
	)
	(segment
		(start 77.84338 -188.5188)
		(end 77.84338 -188.86678)
		(width 0.508)
		(layer "F.Cu")
		(net "GND")
	)
	(segment
		(start 46.88713 -144.187164)
		(end 46.500034 -143.800068)
		(width 0.3556)
		(layer "F.Cu")
		(net "GND")
	)
	(segment
		(start 83.406996 -175.76038)
		(end 84.5312 -175.76038)
		(width 0.508)
		(layer "F.Cu")
		(net "GND")
	)
	(segment
		(start 27.502358 -145.821654)
		(end 27.502358 -146.30146)
		(width 0.508)
		(layer "F.Cu")
		(net "GND")
	)
	(segment
		(start 79.925164 -76.950062)
		(end 81.397094 -76.950062)
		(width 0.508)
		(layer "F.Cu")
		(net "GND")
	)
	(segment
		(start 71.5899 -174.3456)
		(end 70.9676 -174.3456)
		(width 0.508)
		(layer "F.Cu")
		(net "GND")
	)
	(segment
		(start 47.771812 -163.566602)
		(end 46.940978 -163.566602)
		(width 0.508)
		(layer "F.Cu")
		(net "GND")
	)
	(segment
		(start 40.099996 -143.800068)
		(end 40.500046 -144.200118)
		(width 0.254)
		(layer "F.Cu")
		(net "GND")
	)
	(segment
		(start 89.912698 -26.4668)
		(end 90.805 -26.4668)
		(width 0.508)
		(layer "F.Cu")
		(net "GND")
	)
	(segment
		(start 67.945 -163.9824)
		(end 67.945 -164.821108)
		(width 0.508)
		(layer "F.Cu")
		(net "GND")
	)
	(segment
		(start 182.649876 -136.14527)
		(end 182.726076 -136.22147)
		(width 0.254)
		(layer "F.Cu")
		(net "GND")
	)
	(segment
		(start 77.2414 -169.291)
		(end 77.367384 -169.165016)
		(width 0.508)
		(layer "F.Cu")
		(net "GND")
	)
	(segment
		(start 47.29988 -149.399752)
		(end 47.699676 -148.999956)
		(width 0.3556)
		(layer "F.Cu")
		(net "GND")
	)
	(segment
		(start 18.650458 -176.72939)
		(end 18.650458 -177.61839)
		(width 0.508)
		(layer "F.Cu")
		(net "GND")
	)
	(segment
		(start 42.291 -161.8615)
		(end 42.291 -162.6362)
		(width 0.508)
		(layer "F.Cu")
		(net "GND")
	)
	(segment
		(start 71.78548 -163.6141)
		(end 71.78548 -162.8013)
		(width 0.508)
		(layer "F.Cu")
		(net "GND")
	)
	(segment
		(start 40.099996 -145.400014)
		(end 39.699946 -144.999964)
		(width 0.3556)
		(layer "F.Cu")
		(net "GND")
	)
	(segment
		(start 75.475084 -81.7499)
		(end 77.01915 -81.7499)
		(width 0.508)
		(layer "F.Cu")
		(net "GND")
	)
	(segment
		(start 48.499522 -144.200372)
		(end 48.09998 -144.599914)
		(width 0.3556)
		(layer "F.Cu")
		(net "GND")
	)
	(segment
		(start 51.299872 -153.40457)
		(end 51.299872 -153.399998)
		(width 0.3556)
		(layer "F.Cu")
		(net "GND")
	)
	(segment
		(start 62.484 -152.908)
		(end 62.0649 -152.908)
		(width 0.508)
		(layer "F.Cu")
		(net "GND")
	)
	(segment
		(start 98.0567 -177.292)
		(end 98.0567 -178.1048)
		(width 0.508)
		(layer "F.Cu")
		(net "GND")
	)
	(segment
		(start 75.475084 -88.149938)
		(end 77.018388 -88.149938)
		(width 0.508)
		(layer "F.Cu")
		(net "GND")
	)
	(segment
		(start 81.344008 -74.550016)
		(end 81.758028 -74.135996)
		(width 0.508)
		(layer "F.Cu")
		(net "GND")
	)
	(segment
		(start 49.299622 -143.400272)
		(end 48.899826 -143.000476)
		(width 0.3556)
		(layer "F.Cu")
		(net "GND")
	)
	(segment
		(start 60.452 -158.8135)
		(end 59.436 -158.8135)
		(width 0.508)
		(layer "F.Cu")
		(net "GND")
	)
	(segment
		(start 17.634458 -146.161506)
		(end 17.634712 -146.161506)
		(width 0.3048)
		(layer "F.Cu")
		(net "GND")
	)
	(segment
		(start 76.9874 -168.7068)
		(end 77.2414 -168.9608)
		(width 0.508)
		(layer "F.Cu")
		(net "GND")
	)
	(segment
		(start 22.834854 -145.761964)
		(end 22.834346 -145.761456)
		(width 0.3048)
		(layer "F.Cu")
		(net "GND")
	)
	(segment
		(start 81.182464 -87.350092)
		(end 81.643728 -86.888828)
		(width 0.508)
		(layer "F.Cu")
		(net "GND")
	)
	(segment
		(start 123.663456 -12.054078)
		(end 124.46889 -12.054078)
		(width 0.508)
		(layer "F.Cu")
		(net "GND")
	)
	(segment
		(start 56.49976 -153.800048)
		(end 56.099964 -153.400252)
		(width 0.254)
		(layer "F.Cu")
		(net "GND")
	)
	(segment
		(start 23.234396 -138.961622)
		(end 23.996142 -138.961622)
		(width 0.3048)
		(layer "F.Cu")
		(net "GND")
	)
	(segment
		(start 79.925164 -54.550056)
		(end 81.262728 -54.550056)
		(width 0.254)
		(layer "F.Cu")
		(net "GND")
	)
	(segment
		(start 79.321406 -135.684006)
		(end 79.057246 -135.419846)
		(width 0.3048)
		(layer "F.Cu")
		(net "GND")
	)
	(segment
		(start 89.250266 -132.3086)
		(end 89.8652 -132.3086)
		(width 0.508)
		(layer "F.Cu")
		(net "GND")
	)
	(segment
		(start 65.18275 -158.647384)
		(end 65.741042 -158.647384)
		(width 0.254)
		(layer "F.Cu")
		(net "GND")
	)
	(segment
		(start 88.471756 -162.648392)
		(end 88.471756 -163.538662)
		(width 0.508)
		(layer "F.Cu")
		(net "GND")
	)
	(segment
		(start 46.89983 -145.838164)
		(end 46.89983 -145.800064)
		(width 0.3556)
		(layer "F.Cu")
		(net "GND")
	)
	(segment
		(start 96.3803 -180.4416)
		(end 96.3803 -181.4576)
		(width 0.508)
		(layer "F.Cu")
		(net "GND")
	)
	(segment
		(start 95.31604 -123.7615)
		(end 96.379792 -123.7615)
		(width 0.254)
		(layer "F.Cu")
		(net "GND")
	)
	(segment
		(start 218.339416 -54.853078)
		(end 218.339416 -54.373018)
		(width 0.508)
		(layer "F.Cu")
		(net "GND")
	)
	(segment
		(start 46.52518 -145.400014)
		(end 46.500034 -145.400014)
		(width 0.3556)
		(layer "F.Cu")
		(net "GND")
	)
	(segment
		(start 184.15 -134.875016)
		(end 184.15 -136.25449)
		(width 0.254)
		(layer "F.Cu")
		(net "GND")
	)
	(segment
		(start 79.925164 -55.349902)
		(end 81.229454 -55.349902)
		(width 0.254)
		(layer "F.Cu")
		(net "GND")
	)
	(segment
		(start 52.8955 -159.2326)
		(end 52.1462 -159.2326)
		(width 0.508)
		(layer "F.Cu")
		(net "GND")
	)
	(segment
		(start 218.685872 -54.026562)
		(end 218.685872 -53.483256)
		(width 0.508)
		(layer "F.Cu")
		(net "GND")
	)
	(segment
		(start 49.699926 -145.400014)
		(end 49.699672 -145.400014)
		(width 0.3556)
		(layer "F.Cu")
		(net "GND")
	)
	(segment
		(start 147.092416 -11.675618)
		(end 146.1262 -11.675618)
		(width 0.508)
		(layer "F.Cu")
		(net "GND")
	)
	(segment
		(start 54.136036 -130.064764)
		(end 53.7718 -130.429)
		(width 0.508)
		(layer "F.Cu")
		(net "GND")
	)
	(segment
		(start 47.29988 -142.999968)
		(end 47.115476 -142.815564)
		(width 0.3556)
		(layer "F.Cu")
		(net "GND")
	)
	(segment
		(start 77.035152 -53.749956)
		(end 77.596492 -54.311296)
		(width 0.254)
		(layer "F.Cu")
		(net "GND")
	)
	(segment
		(start 93.68663 -50.546)
		(end 94.120716 -50.111914)
		(width 0.508)
		(layer "F.Cu")
		(net "GND")
	)
	(segment
		(start 92.978478 -60.9854)
		(end 93.27642 -61.283342)
		(width 0.508)
		(layer "F.Cu")
		(net "GND")
	)
	(segment
		(start 188.649864 -134.875016)
		(end 188.649864 -136.25449)
		(width 0.254)
		(layer "F.Cu")
		(net "GND")
	)
	(segment
		(start 81.101692 -92.95003)
		(end 81.491328 -93.339666)
		(width 0.508)
		(layer "F.Cu")
		(net "GND")
	)
	(segment
		(start 56.3626 -159.9184)
		(end 56.3626 -159.2961)
		(width 0.508)
		(layer "F.Cu")
		(net "GND")
	)
	(segment
		(start 75.475084 -91.350084)
		(end 76.738734 -91.350084)
		(width 0.508)
		(layer "F.Cu")
		(net "GND")
	)
	(segment
		(start 75.475084 -58.550048)
		(end 76.744576 -58.550048)
		(width 0.508)
		(layer "F.Cu")
		(net "GND")
	)
	(segment
		(start 46.684438 -142.815564)
		(end 46.500034 -142.999968)
		(width 0.3556)
		(layer "F.Cu")
		(net "GND")
	)
	(segment
		(start 47.39513 -151.095202)
		(end 47.39513 -151.704802)
		(width 0.254)
		(layer "F.Cu")
		(net "GND")
	)
	(segment
		(start 42.500042 -144.599914)
		(end 42.900092 -144.999964)
		(width 0.3556)
		(layer "F.Cu")
		(net "GND")
	)
	(segment
		(start 47.29988 -150.999952)
		(end 47.39513 -151.095202)
		(width 0.254)
		(layer "F.Cu")
		(net "GND")
	)
	(segment
		(start 90.186764 -166.975536)
		(end 89.827354 -166.616126)
		(width 0.508)
		(layer "F.Cu")
		(net "GND")
	)
	(segment
		(start 94.1832 -50.04943)
		(end 94.120716 -50.111914)
		(width 0.508)
		(layer "F.Cu")
		(net "GND")
	)
	(segment
		(start 79.925164 -83.3501)
		(end 81.304892 -83.3501)
		(width 0.508)
		(layer "F.Cu")
		(net "GND")
	)
	(segment
		(start 75.475084 -68.950078)
		(end 77.088238 -68.950078)
		(width 0.508)
		(layer "F.Cu")
		(net "GND")
	)
	(segment
		(start 54.713124 -162.926268)
		(end 53.773324 -162.926268)
		(width 0.508)
		(layer "F.Cu")
		(net "GND")
	)
	(segment
		(start 215.0237 -43.044618)
		(end 214.16264 -43.044618)
		(width 0.508)
		(layer "F.Cu")
		(net "GND")
	)
	(segment
		(start 88.9762 -137.6807)
		(end 89.53754 -137.6807)
		(width 0.254)
		(layer "F.Cu")
		(net "GND")
	)
	(segment
		(start 52.790852 -127.6985)
		(end 52.705 -127.612648)
		(width 0.508)
		(layer "F.Cu")
		(net "GND")
	)
	(segment
		(start 18.434558 -145.36166)
		(end 19.0627 -145.36166)
		(width 0.254)
		(layer "F.Cu")
		(net "GND")
	)
	(segment
		(start 79.925164 -80.149954)
		(end 81.304892 -80.149954)
		(width 0.508)
		(layer "F.Cu")
		(net "GND")
	)
	(segment
		(start 66.5226 -149.5806)
		(end 66.350134 -149.753066)
		(width 0.508)
		(layer "F.Cu")
		(net "GND")
	)
	(segment
		(start 81.397094 -76.950062)
		(end 81.758028 -77.310996)
		(width 0.508)
		(layer "F.Cu")
		(net "GND")
	)
	(segment
		(start 46.89983 -145.800064)
		(end 46.500034 -146.19986)
		(width 0.3556)
		(layer "F.Cu")
		(net "GND")
	)
	(segment
		(start 62.611 -153.035)
		(end 62.484 -152.908)
		(width 0.508)
		(layer "F.Cu")
		(net "GND")
	)
	(segment
		(start 79.925164 -84.149946)
		(end 81.182718 -84.149946)
		(width 0.508)
		(layer "F.Cu")
		(net "GND")
	)
	(segment
		(start 89.4334 -171.11472)
		(end 89.4334 -170.815)
		(width 0.254)
		(layer "F.Cu")
		(net "GND")
	)
	(segment
		(start 64.140842 -160.979104)
		(end 64.827912 -160.292034)
		(width 0.508)
		(layer "F.Cu")
		(net "GND")
	)
	(segment
		(start 64.92494 -158.905194)
		(end 65.18275 -158.647384)
		(width 0.254)
		(layer "F.Cu")
		(net "GND")
	)
	(segment
		(start 66.8147 -169.164)
		(end 66.8147 -168.274492)
		(width 0.508)
		(layer "F.Cu")
		(net "GND")
	)
	(segment
		(start 187.2615 -108.4072)
		(end 188.087 -108.4072)
		(width 0.508)
		(layer "F.Cu")
		(net "GND")
	)
	(segment
		(start 47.699676 -153.000202)
		(end 47.29988 -153.399998)
		(width 0.254)
		(layer "F.Cu")
		(net "GND")
	)
	(segment
		(start 67.924934 -158.06801)
		(end 68.6562 -158.06801)
		(width 0.508)
		(layer "F.Cu")
		(net "GND")
	)
	(segment
		(start 18.737072 -16.44777)
		(end 18.737072 -17.69237)
		(width 0.508)
		(layer "F.Cu")
		(net "GND")
	)
	(segment
		(start 49.299876 -145.800064)
		(end 49.699672 -146.19986)
		(width 0.3556)
		(layer "F.Cu")
		(net "GND")
	)
	(segment
		(start 39.299896 -153.399998)
		(end 39.114984 -153.58491)
		(width 0.254)
		(layer "F.Cu")
		(net "GND")
	)
	(segment
		(start 88.5317 -138.1252)
		(end 88.9762 -137.6807)
		(width 0.254)
		(layer "F.Cu")
		(net "GND")
	)
	(segment
		(start 218.339416 -54.373018)
		(end 218.685872 -54.026562)
		(width 0.508)
		(layer "F.Cu")
		(net "GND")
	)
	(segment
		(start 22.43455 -148.56206)
		(end 22.834854 -148.962364)
		(width 0.3048)
		(layer "F.Cu")
		(net "GND")
	)
	(segment
		(start 183.422036 -103.32339)
		(end 184.011062 -103.32339)
		(width 0.254)
		(layer "F.Cu")
		(net "GND")
	)
	(segment
		(start 54.0004 -130.6576)
		(end 53.7718 -130.429)
		(width 0.508)
		(layer "F.Cu")
		(net "GND")
	)
	(segment
		(start 22.43455 -146.161506)
		(end 22.0345 -145.761456)
		(width 0.3048)
		(layer "F.Cu")
		(net "GND")
	)
	(segment
		(start 92.456 -60.9854)
		(end 92.978478 -60.9854)
		(width 0.508)
		(layer "F.Cu")
		(net "GND")
	)
	(segment
		(start 76.9874 -168.05402)
		(end 76.9874 -168.7068)
		(width 0.508)
		(layer "F.Cu")
		(net "GND")
	)
	(segment
		(start 84.2645 -148.59)
		(end 84.2645 -147.674076)
		(width 0.508)
		(layer "F.Cu")
		(net "GND")
	)
	(segment
		(start 98.8695 -137.3886)
		(end 98.8695 -135.4836)
		(width 0.508)
		(layer "F.Cu")
		(net "GND")
	)
	(segment
		(start 94.488 -15.7861)
		(end 95.3262 -15.7861)
		(width 0.4064)
		(layer "F.Cu")
		(net "GND")
	)
	(segment
		(start 61.9125 -149.8092)
		(end 61.9633 -149.7584)
		(width 0.254)
		(layer "F.Cu")
		(net "GND")
	)
	(segment
		(start 203.149962 -134.875016)
		(end 203.149962 -136.25449)
		(width 0.254)
		(layer "F.Cu")
		(net "GND")
	)
	(segment
		(start 38.899846 -136.200134)
		(end 38.9001 -136.200134)
		(width 0.3556)
		(layer "F.Cu")
		(net "GND")
	)
	(segment
		(start 47.401734 -142.999968)
		(end 47.29988 -142.999968)
		(width 0.3556)
		(layer "F.Cu")
		(net "GND")
	)
	(segment
		(start 182.649876 -134.875016)
		(end 182.649876 -136.14527)
		(width 0.254)
		(layer "F.Cu")
		(net "GND")
	)
	(segment
		(start 76.738734 -91.350084)
		(end 77.283818 -91.895168)
		(width 0.508)
		(layer "F.Cu")
		(net "GND")
	)
	(segment
		(start 42.499788 -147.80006)
		(end 42.500042 -147.80006)
		(width 0.3556)
		(layer "F.Cu")
		(net "GND")
	)
	(segment
		(start 16.530574 -136.864344)
		(end 16.364458 -136.864344)
		(width 0.3048)
		(layer "F.Cu")
		(net "GND")
	)
	(segment
		(start 184.011062 -103.32339)
		(end 184.223152 -103.1113)
		(width 0.254)
		(layer "F.Cu")
		(net "GND")
	)
	(segment
		(start 217.067384 -40.40759)
		(end 217.067384 -39.443152)
		(width 0.508)
		(layer "F.Cu")
		(net "GND")
	)
	(segment
		(start 93.27642 -61.283342)
		(end 93.27642 -61.292232)
		(width 0.508)
		(layer "F.Cu")
		(net "GND")
	)
	(segment
		(start 79.925164 -64.149986)
		(end 81.108042 -64.149986)
		(width 0.508)
		(layer "F.Cu")
		(net "GND")
	)
	(segment
		(start 79.925164 -74.550016)
		(end 81.344008 -74.550016)
		(width 0.508)
		(layer "F.Cu")
		(net "GND")
	)
	(segment
		(start 71.7804 -174.1551)
		(end 71.5899 -174.3456)
		(width 0.508)
		(layer "F.Cu")
		(net "GND")
	)
	(segment
		(start 91.251532 -151.945848)
		(end 91.251532 -152.73528)
		(width 0.254)
		(layer "F.Cu")
		(net "GND")
	)
	(segment
		(start 69.9262 -118.6942)
		(end 69.4436 -118.2116)
		(width 0.508)
		(layer "F.Cu")
		(net "GND")
	)
	(segment
		(start 47.712122 -145.81251)
		(end 47.712376 -145.81251)
		(width 0.3556)
		(layer "F.Cu")
		(net "GND")
	)
	(segment
		(start 80.815942 -172.324522)
		(end 81.64195 -172.324522)
		(width 0.508)
		(layer "F.Cu")
		(net "GND")
	)
	(segment
		(start 65.532 -166.9415)
		(end 64.954658 -166.9415)
		(width 0.508)
		(layer "F.Cu")
		(net "GND")
	)
	(segment
		(start 47.712376 -145.81251)
		(end 47.71263 -145.81251)
		(width 0.3556)
		(layer "F.Cu")
		(net "GND")
	)
	(segment
		(start 50.060098 -172.699934)
		(end 48.708818 -172.699934)
		(width 0.508)
		(layer "F.Cu")
		(net "GND")
	)
	(segment
		(start 76.809092 -65.749932)
		(end 77.355192 -66.296032)
		(width 0.508)
		(layer "F.Cu")
		(net "GND")
	)
	(segment
		(start 122.219212 -10.241534)
		(end 121.3485 -10.241534)
		(width 0.254)
		(layer "F.Cu")
		(net "GND")
	)
	(segment
		(start 58.928 -163.627562)
		(end 58.48858 -164.066982)
		(width 0.508)
		(layer "F.Cu")
		(net "GND")
	)
	(segment
		(start 49.299622 -145.800064)
		(end 49.299876 -145.800064)
		(width 0.3556)
		(layer "F.Cu")
		(net "GND")
	)
	(segment
		(start 87.638636 -27.576272)
		(end 87.647526 -27.567382)
		(width 0.508)
		(layer "F.Cu")
		(net "GND")
	)
	(segment
		(start 79.925164 -87.350092)
		(end 81.182464 -87.350092)
		(width 0.508)
		(layer "F.Cu")
		(net "GND")
	)
	(segment
		(start 56.515 -136.184894)
		(end 56.099964 -136.59993)
		(width 0.254)
		(layer "F.Cu")
		(net "GND")
	)
	(segment
		(start 54.500018 -149.400006)
		(end 54.099968 -148.999956)
		(width 0.3556)
		(layer "F.Cu")
		(net "GND")
	)
	(segment
		(start 91.72448 -148.012404)
		(end 91.68892 -147.976844)
		(width 0.508)
		(layer "F.Cu")
		(net "GND")
	)
	(segment
		(start 26.2636 -139.761468)
		(end 26.993088 -139.03198)
		(width 0.3048)
		(layer "F.Cu")
		(net "GND")
	)
	(segment
		(start 16.04137 -165.789102)
		(end 16.480536 -165.349936)
		(width 0.254)
		(layer "F.Cu")
		(net "GND")
	)
	(segment
		(start 49.299368 -143.400526)
		(end 48.899826 -143.800068)
		(width 0.3556)
		(layer "F.Cu")
		(net "GND")
	)
	(segment
		(start 75.475084 -53.749956)
		(end 77.035152 -53.749956)
		(width 0.254)
		(layer "F.Cu")
		(net "GND")
	)
	(segment
		(start 181.8894 -111.4679)
		(end 181.8894 -112.2934)
		(width 0.508)
		(layer "F.Cu")
		(net "GND")
	)
	(segment
		(start 34.791396 -136.589008)
		(end 34.791396 -135.757666)
		(width 0.508)
		(layer "F.Cu")
		(net "GND")
	)
	(segment
		(start 48.09998 -143.000476)
		(end 48.499776 -143.400272)
		(width 0.3556)
		(layer "F.Cu")
		(net "GND")
	)
	(segment
		(start 53.848 -127.6985)
		(end 52.790852 -127.6985)
		(width 0.508)
		(layer "F.Cu")
		(net "GND")
	)
	(segment
		(start 75.475084 -79.350108)
		(end 77.027278 -79.350108)
		(width 0.508)
		(layer "F.Cu")
		(net "GND")
	)
	(segment
		(start 173.649894 -134.875016)
		(end 173.649894 -133.225794)
		(width 0.254)
		(layer "F.Cu")
		(net "GND")
	)
	(segment
		(start 80.9625 -152.90927)
		(end 80.663288 -153.208482)
		(width 0.508)
		(layer "F.Cu")
		(net "GND")
	)
	(segment
		(start 39.1922 -178.68011)
		(end 38.38702 -178.68011)
		(width 0.508)
		(layer "F.Cu")
		(net "GND")
	)
	(segment
		(start 38.9001 -136.200134)
		(end 39.299896 -136.59993)
		(width 0.3556)
		(layer "F.Cu")
		(net "GND")
	)
	(segment
		(start 75.83678 -188.4426)
		(end 75.83678 -188.89218)
		(width 0.508)
		(layer "F.Cu")
		(net "GND")
	)
	(segment
		(start 75.9714 -149.6568)
		(end 75.632818 -149.318218)
		(width 0.508)
		(layer "F.Cu")
		(net "GND")
	)
	(segment
		(start 89.827354 -165.92169)
		(end 90.184986 -165.564058)
		(width 0.508)
		(layer "F.Cu")
		(net "GND")
	)
	(segment
		(start 75.475084 -51.34991)
		(end 76.991718 -51.34991)
		(width 0.508)
		(layer "F.Cu")
		(net "GND")
	)
	(segment
		(start 200.149968 -134.875016)
		(end 200.149968 -136.25449)
		(width 0.254)
		(layer "F.Cu")
		(net "GND")
	)
	(segment
		(start 91.452446 -165.564058)
		(end 90.1954 -165.564058)
		(width 0.508)
		(layer "F.Cu")
		(net "GND")
	)
	(segment
		(start 48.09998 -142.999968)
		(end 48.09998 -143.000476)
		(width 0.3556)
		(layer "F.Cu")
		(net "GND")
	)
	(segment
		(start 75.475084 -75.350116)
		(end 77.020166 -75.350116)
		(width 0.508)
		(layer "F.Cu")
		(net "GND")
	)
	(segment
		(start 49.699672 -145.400014)
		(end 49.299622 -145.800064)
		(width 0.3556)
		(layer "F.Cu")
		(net "GND")
	)
	(segment
		(start 81.268062 -67.350132)
		(end 81.605374 -67.687444)
		(width 0.508)
		(layer "F.Cu")
		(net "GND")
	)
	(segment
		(start 77.018388 -88.149938)
		(end 77.283818 -88.415368)
		(width 0.508)
		(layer "F.Cu")
		(net "GND")
	)
	(segment
		(start 80.9625 -152.146)
		(end 80.9625 -152.90927)
		(width 0.508)
		(layer "F.Cu")
		(net "GND")
	)
	(segment
		(start 77.101192 -66.550032)
		(end 77.355192 -66.296032)
		(width 0.508)
		(layer "F.Cu")
		(net "GND")
	)
	(segment
		(start 72.91959 -158.06801)
		(end 73.787 -157.2006)
		(width 0.508)
		(layer "F.Cu")
		(net "GND")
	)
	(segment
		(start 64.0715 -166.71925)
		(end 62.92215 -166.71925)
		(width 0.508)
		(layer "F.Cu")
		(net "GND")
	)
	(segment
		(start 64.954658 -166.9415)
		(end 64.732408 -166.71925)
		(width 0.508)
		(layer "F.Cu")
		(net "GND")
	)
	(segment
		(start 91.096084 -151.499824)
		(end 91.096084 -151.7904)
		(width 0.254)
		(layer "F.Cu")
		(net "GND")
	)
	(segment
		(start 81.182464 -71.350124)
		(end 81.643728 -70.88886)
		(width 0.508)
		(layer "F.Cu")
		(net "GND")
	)
	(segment
		(start 22.43455 -148.561552)
		(end 22.43455 -148.56206)
		(width 0.3048)
		(layer "F.Cu")
		(net "GND")
	)
	(segment
		(start 77.81798 -187.648596)
		(end 77.81798 -188.5188)
		(width 0.508)
		(layer "F.Cu")
		(net "GND")
	)
	(segment
		(start 76.74991 -95.350076)
		(end 77.283818 -94.816168)
		(width 0.508)
		(layer "F.Cu")
		(net "GND")
	)
	(segment
		(start 95.43288 -21.9202)
		(end 96.7232 -21.9202)
		(width 0.508)
		(layer "F.Cu")
		(net "GND")
	)
	(segment
		(start 214.83828 -93.109288)
		(end 214.83828 -93.212666)
		(width 0.508)
		(layer "F.Cu")
		(net "GND")
	)
	(segment
		(start 51.699668 -138.600434)
		(end 51.699414 -138.600434)
		(width 0.3556)
		(layer "F.Cu")
		(net "GND")
	)
	(segment
		(start 49.699926 -136.600438)
		(end 49.699926 -136.59993)
		(width 0.254)
		(layer "F.Cu")
		(net "GND")
	)
	(segment
		(start 75.475084 -72.95007)
		(end 77.026516 -72.95007)
		(width 0.508)
		(layer "F.Cu")
		(net "GND")
	)
	(segment
		(start 35.2806 -133.603746)
		(end 30.098746 -133.603746)
		(width 0.381)
		(layer "F.Cu")
		(net "GND")
	)
	(segment
		(start 90.184986 -165.564058)
		(end 90.1954 -165.564058)
		(width 0.508)
		(layer "F.Cu")
		(net "GND")
	)
	(segment
		(start 49.699926 -142.999968)
		(end 49.699926 -143.000222)
		(width 0.3556)
		(layer "F.Cu")
		(net "GND")
	)
	(segment
		(start 77.150214 -158.867602)
		(end 77.58938 -158.428436)
		(width 0.254)
		(layer "F.Cu")
		(net "GND")
	)
	(segment
		(start 23.234396 -141.361668)
		(end 23.233888 -141.361668)
		(width 0.254)
		(layer "F.Cu")
		(net "GND")
	)
	(segment
		(start 50.099722 -150.599648)
		(end 49.699926 -150.199852)
		(width 0.3556)
		(layer "F.Cu")
		(net "GND")
	)
	(segment
		(start 48.499776 -146.600164)
		(end 48.50003 -146.600164)
		(width 0.3556)
		(layer "F.Cu")
		(net "GND")
	)
	(segment
		(start 99.8347 -151.6888)
		(end 100.6348 -151.6888)
		(width 0.508)
		(layer "F.Cu")
		(net "GND")
	)
	(segment
		(start 47.39513 -151.704802)
		(end 47.29988 -151.800052)
		(width 0.254)
		(layer "F.Cu")
		(net "GND")
	)
	(segment
		(start 74.887328 -175.754538)
		(end 74.880216 -175.76165)
		(width 0.508)
		(layer "F.Cu")
		(net "GND")
	)
	(segment
		(start 12.954 -12.5095)
		(end 14.0335 -11.43)
		(width 0.508)
		(layer "F.Cu")
		(net "GND")
	)
	(segment
		(start 17.634712 -146.161506)
		(end 18.034508 -146.561302)
		(width 0.3048)
		(layer "F.Cu")
		(net "GND")
	)
	(segment
		(start 81.182718 -84.149946)
		(end 81.643728 -83.688936)
		(width 0.508)
		(layer "F.Cu")
		(net "GND")
	)
	(segment
		(start 49.464722 -147.235164)
		(end 49.13503 -147.235164)
		(width 0.3556)
		(layer "F.Cu")
		(net "GND")
	)
	(segment
		(start 81.1657 -133.6294)
		(end 81.1657 -133.1595)
		(width 0.508)
		(layer "F.Cu")
		(net "GND")
	)
	(segment
		(start 77.4192 -140.828522)
		(end 75.977496 -140.828522)
		(width 0.254)
		(layer "F.Cu")
		(net "GND")
	)
	(segment
		(start 47.7266 -149.8092)
		(end 47.335948 -150.199852)
		(width 0.3556)
		(layer "F.Cu")
		(net "GND")
	)
	(segment
		(start 42.900092 -144.999964)
		(end 43.299888 -145.39976)
		(width 0.3556)
		(layer "F.Cu")
		(net "GND")
	)
	(segment
		(start 76.744576 -58.550048)
		(end 77.516228 -57.778396)
		(width 0.508)
		(layer "F.Cu")
		(net "GND")
	)
	(segment
		(start 21.6916 -161.281364)
		(end 21.6916 -159.965136)
		(width 0.508)
		(layer "F.Cu")
		(net "GND")
	)
	(segment
		(start 10.541508 -167.616886)
		(end 9.642094 -167.616886)
		(width 0.508)
		(layer "F.Cu")
		(net "GND")
	)
	(segment
		(start 16.834612 -145.36166)
		(end 17.234662 -145.76171)
		(width 0.3048)
		(layer "F.Cu")
		(net "GND")
	)
	(segment
		(start 50.099722 -150.599902)
		(end 50.099722 -150.599648)
		(width 0.3556)
		(layer "F.Cu")
		(net "GND")
	)
	(segment
		(start 78.015846 -52.15001)
		(end 77.827378 -52.338478)
		(width 0.508)
		(layer "F.Cu")
		(net "GND")
	)
	(segment
		(start 66.350134 -149.753066)
		(end 65.661032 -149.753066)
		(width 0.508)
		(layer "F.Cu")
		(net "GND")
	)
	(segment
		(start 30.098746 -133.603746)
		(end 29.4767 -132.9817)
		(width 0.381)
		(layer "F.Cu")
		(net "GND")
	)
	(segment
		(start 94.328742 -162.821366)
		(end 94.021656 -162.51428)
		(width 0.254)
		(layer "F.Cu")
		(net "GND")
	)
	(segment
		(start 73.8886 -149.098)
		(end 73.0504 -149.098)
		(width 0.508)
		(layer "F.Cu")
		(net "GND")
	)
	(segment
		(start 47.29988 -146.19986)
		(end 47.324772 -146.19986)
		(width 0.3556)
		(layer "F.Cu")
		(net "GND")
	)
	(segment
		(start 89.066116 -132.23875)
		(end 89.123266 -132.1816)
		(width 0.508)
		(layer "F.Cu")
		(net "GND")
	)
	(segment
		(start 31.390844 -124.5362)
		(end 30.022038 -124.5362)
		(width 0.508)
		(layer "F.Cu")
		(net "GND")
	)
	(segment
		(start 50.500026 -150.999952)
		(end 50.499772 -150.999952)
		(width 0.3556)
		(layer "F.Cu")
		(net "GND")
	)
	(segment
		(start 46.377098 -117.795294)
		(end 47.308516 -117.795294)
		(width 0.508)
		(layer "F.Cu")
		(net "GND")
	)
	(segment
		(start 48.09998 -146.99996)
		(end 47.700184 -146.600164)
		(width 0.3556)
		(layer "F.Cu")
		(net "GND")
	)
	(segment
		(start 75.475084 -95.350076)
		(end 76.74991 -95.350076)
		(width 0.508)
		(layer "F.Cu")
		(net "GND")
	)
	(segment
		(start 75.81138 -188.4426)
		(end 75.83678 -188.4426)
		(width 0.508)
		(layer "F.Cu")
		(net "GND")
	)
	(segment
		(start 179.649882 -134.875016)
		(end 179.649882 -133.225794)
		(width 0.254)
		(layer "F.Cu")
		(net "GND")
	)
	(segment
		(start 75.475084 -63.35014)
		(end 77.100684 -63.35014)
		(width 0.254)
		(layer "F.Cu")
		(net "GND")
	)
	(segment
		(start 75.475084 -88.950038)
		(end 76.749148 -88.950038)
		(width 0.508)
		(layer "F.Cu")
		(net "GND")
	)
	(segment
		(start 84.5185 -167.29075)
		(end 84.44865 -167.2209)
		(width 0.508)
		(layer "F.Cu")
		(net "GND")
	)
	(segment
		(start 77.01915 -81.7499)
		(end 77.283818 -82.014568)
		(width 0.508)
		(layer "F.Cu")
		(net "GND")
	)
	(segment
		(start 74.44105 -177.020982)
		(end 74.44105 -177.883058)
		(width 0.254)
		(layer "F.Cu")
		(net "GND")
	)
	(segment
		(start 87.5538 -130.0226)
		(end 87.5284 -129.9972)
		(width 0.508)
		(layer "F.Cu")
		(net "GND")
	)
	(segment
		(start 77.372718 -149.817074)
		(end 77.685646 -149.817074)
		(width 0.508)
		(layer "F.Cu")
		(net "GND")
	)
	(segment
		(start 47.69993 -152.999948)
		(end 47.69993 -153.000202)
		(width 0.254)
		(layer "F.Cu")
		(net "GND")
	)
	(segment
		(start 77.851762 -158.166054)
		(end 77.58938 -158.428436)
		(width 0.508)
		(layer "F.Cu")
		(net "GND")
	)
	(segment
		(start 80.6704 -154.1399)
		(end 80.6704 -153.238708)
		(width 0.508)
		(layer "F.Cu")
		(net "GND")
	)
	(segment
		(start 71.890128 -187.792614)
		(end 71.717662 -187.96508)
		(width 0.508)
		(layer "F.Cu")
		(net "GND")
	)
	(segment
		(start 49.299622 -145.800064)
		(end 49.299622 -145.79981)
		(width 0.3556)
		(layer "F.Cu")
		(net "GND")
	)
	(segment
		(start 84.79282 -174.060104)
		(end 85.504274 -174.060104)
		(width 0.508)
		(layer "F.Cu")
		(net "GND")
	)
	(segment
		(start 26.416 -121.6025)
		(end 26.416 -120.777)
		(width 0.508)
		(layer "F.Cu")
		(net "GND")
	)
	(segment
		(start 76.740258 -78.550008)
		(end 77.283818 -79.093568)
		(width 0.508)
		(layer "F.Cu")
		(net "GND")
	)
	(segment
		(start 89.0016 -134.2263)
		(end 88.23706 -134.2263)
		(width 0.508)
		(layer "F.Cu")
		(net "GND")
	)
	(segment
		(start 123.384056 -13.167614)
		(end 122.613928 -13.167614)
		(width 0.508)
		(layer "F.Cu")
		(net "GND")
	)
	(segment
		(start 79.925164 -77.749908)
		(end 79.925418 -77.750162)
		(width 0.508)
		(layer "F.Cu")
		(net "GND")
	)
	(segment
		(start 92.151454 -139.216638)
		(end 92.012262 -139.077446)
		(width 0.254)
		(layer "F.Cu")
		(net "GND")
	)
	(segment
		(start 70.9549 -174.3329)
		(end 70.9676 -174.3456)
		(width 0.4064)
		(layer "F.Cu")
		(net "GND")
	)
	(segment
		(start 64.457834 -159.921956)
		(end 64.827912 -160.292034)
		(width 0.508)
		(layer "F.Cu")
		(net "GND")
	)
	(segment
		(start 76.74102 -72.14997)
		(end 77.283818 -72.692768)
		(width 0.508)
		(layer "F.Cu")
		(net "GND")
	)
	(segment
		(start 81.318862 -77.750162)
		(end 81.758028 -77.310996)
		(width 0.508)
		(layer "F.Cu")
		(net "GND")
	)
	(segment
		(start 77.100684 -63.35014)
		(end 77.490828 -62.959996)
		(width 0.254)
		(layer "F.Cu")
		(net "GND")
	)
	(segment
		(start 70.19544 -174.3329)
		(end 70.9549 -174.3329)
		(width 0.4064)
		(layer "F.Cu")
		(net "GND")
	)
	(segment
		(start 42.500042 -142.999968)
		(end 42.900092 -142.599918)
		(width 0.3556)
		(layer "F.Cu")
		(net "GND")
	)
	(segment
		(start 79.857092 -170.244516)
		(end 79.857092 -169.860468)
		(width 0.508)
		(layer "F.Cu")
		(net "GND")
	)
	(segment
		(start 81.229454 -55.349902)
		(end 81.577688 -55.698136)
		(width 0.254)
		(layer "F.Cu")
		(net "GND")
	)
	(segment
		(start 49.699926 -146.99996)
		(end 49.464722 -147.235164)
		(width 0.3556)
		(layer "F.Cu")
		(net "GND")
	)
	(segment
		(start 77.027278 -79.350108)
		(end 77.283818 -79.093568)
		(width 0.508)
		(layer "F.Cu")
		(net "GND")
	)
	(segment
		(start 197.149974 -134.875016)
		(end 197.149974 -136.25449)
		(width 0.254)
		(layer "F.Cu")
		(net "GND")
	)
	(segment
		(start 205.067662 -103.06939)
		(end 205.279752 -102.8573)
		(width 0.254)
		(layer "F.Cu")
		(net "GND")
	)
	(segment
		(start 29.4767 -130.3655)
		(end 29.9212 -129.921)
		(width 0.381)
		(layer "F.Cu")
		(net "GND")
	)
	(segment
		(start 47.687484 -144.187672)
		(end 47.29988 -143.800068)
		(width 0.3556)
		(layer "F.Cu")
		(net "GND")
	)
	(segment
		(start 75.475084 -66.550032)
		(end 77.101192 -66.550032)
		(width 0.508)
		(layer "F.Cu")
		(net "GND")
	)
	(segment
		(start 77.036168 -54.550056)
		(end 77.274928 -54.311296)
		(width 0.254)
		(layer "F.Cu")
		(net "GND")
	)
	(segment
		(start 79.321406 -135.935974)
		(end 79.321406 -135.684006)
		(width 0.3048)
		(layer "F.Cu")
		(net "GND")
	)
	(segment
		(start 77.020166 -75.350116)
		(end 77.283818 -75.613768)
		(width 0.508)
		(layer "F.Cu")
		(net "GND")
	)
	(segment
		(start 100.2792 -154.8638)
		(end 100.2792 -155.3718)
		(width 0.508)
		(layer "F.Cu")
		(net "GND")
	)
	(segment
		(start 42.900092 -149.800056)
		(end 42.900092 -149.799802)
		(width 0.3556)
		(layer "F.Cu")
		(net "GND")
	)
	(segment
		(start 81.182718 -90.549984)
		(end 81.643728 -90.088974)
		(width 0.508)
		(layer "F.Cu")
		(net "GND")
	)
	(segment
		(start 74.680572 -169.473372)
		(end 75.103228 -169.896028)
		(width 0.508)
		(layer "F.Cu")
		(net "GND")
	)
	(segment
		(start 75.81138 -187.648596)
		(end 75.81138 -188.4426)
		(width 0.508)
		(layer "F.Cu")
		(net "GND")
	)
	(segment
		(start 37.680646 -176.69891)
		(end 37.655246 -176.72431)
		(width 0.508)
		(layer "F.Cu")
		(net "GND")
	)
	(segment
		(start 52.8066 -162.9283)
		(end 52.8828 -163.0045)
		(width 0.508)
		(layer "F.Cu")
		(net "GND")
	)
	(segment
		(start 74.880216 -176.581816)
		(end 74.44105 -177.020982)
		(width 0.254)
		(layer "F.Cu")
		(net "GND")
	)
	(segment
		(start 29.4767 -132.9817)
		(end 29.4767 -130.3655)
		(width 0.381)
		(layer "F.Cu")
		(net "GND")
	)
	(segment
		(start 122.613928 -13.167614)
		(end 122.528838 -13.252704)
		(width 0.508)
		(layer "F.Cu")
		(net "GND")
	)
	(segment
		(start 75.475084 -92.14993)
		(end 77.029056 -92.14993)
		(width 0.508)
		(layer "F.Cu")
		(net "GND")
	)
	(segment
		(start 67.146932 -157.290008)
		(end 67.924934 -158.06801)
		(width 0.508)
		(layer "F.Cu")
		(net "GND")
	)
	(segment
		(start 47.69993 -153.000202)
		(end 47.699676 -153.000202)
		(width 0.254)
		(layer "F.Cu")
		(net "GND")
	)
	(segment
		(start 92.9386 -50.419)
		(end 93.0656 -50.546)
		(width 0.508)
		(layer "F.Cu")
		(net "GND")
	)
	(segment
		(start 71.0184 -134.0866)
		(end 71.8312 -134.8994)
		(width 0.508)
		(layer "F.Cu")
		(net "GND")
	)
	(segment
		(start 34.293048 -130.696208)
		(end 34.293048 -129.5908)
		(width 0.508)
		(layer "F.Cu")
		(net "GND")
	)
	(segment
		(start 75.475084 -94.549976)
		(end 77.017626 -94.549976)
		(width 0.508)
		(layer "F.Cu")
		(net "GND")
	)
	(segment
		(start 23.234396 -142.961614)
		(end 23.234142 -142.961614)
		(width 0.3048)
		(layer "F.Cu")
		(net "GND")
	)
	(segment
		(start 81.304892 -80.149954)
		(end 81.643728 -80.48879)
		(width 0.508)
		(layer "F.Cu")
		(net "GND")
	)
	(segment
		(start 149.516338 -8.053578)
		(end 149.516338 -7.113778)
		(width 0.254)
		(layer "F.Cu")
		(net "GND")
	)
	(segment
		(start 187.649866 -134.875016)
		(end 187.649866 -136.25449)
		(width 0.254)
		(layer "F.Cu")
		(net "GND")
	)
	(segment
		(start 79.925164 -86.549992)
		(end 81.304892 -86.549992)
		(width 0.508)
		(layer "F.Cu")
		(net "GND")
	)
	(segment
		(start 91.72448 -148.751544)
		(end 91.72448 -148.012404)
		(width 0.508)
		(layer "F.Cu")
		(net "GND")
	)
	(segment
		(start 94.03588 -147.468844)
		(end 94.03588 -147.213828)
		(width 0.508)
		(layer "F.Cu")
		(net "GND")
	)
	(segment
		(start 99.7204 -155.9306)
		(end 99.3775 -155.9306)
		(width 0.508)
		(layer "F.Cu")
		(net "GND")
	)
	(segment
		(start 49.299876 -136.99998)
		(end 48.899826 -136.59993)
		(width 0.254)
		(layer "F.Cu")
		(net "GND")
	)
	(segment
		(start 39.114984 -153.58491)
		(end 39.114984 -153.585164)
		(width 0.254)
		(layer "F.Cu")
		(net "GND")
	)
	(segment
		(start 95.0468 -164.051234)
		(end 95.0468 -166.41191)
		(width 0.508)
		(layer "F.Cu")
		(net "GND")
	)
	(segment
		(start 21.023072 -16.44777)
		(end 21.023072 -17.71777)
		(width 0.508)
		(layer "F.Cu")
		(net "GND")
	)
	(segment
		(start 16.833342 -136.561576)
		(end 16.530574 -136.864344)
		(width 0.3048)
		(layer "F.Cu")
		(net "GND")
	)
	(segment
		(start 195.64985 -134.875016)
		(end 195.64985 -136.25449)
		(width 0.254)
		(layer "F.Cu")
		(net "GND")
	)
	(segment
		(start 74.880216 -175.76165)
		(end 74.880216 -176.581816)
		(width 0.508)
		(layer "F.Cu")
		(net "GND")
	)
	(segment
		(start 69.10578 -181.76748)
		(end 68.9737 -181.6354)
		(width 0.508)
		(layer "F.Cu")
		(net "GND")
	)
	(segment
		(start 95.060008 -162.821366)
		(end 94.328742 -162.821366)
		(width 0.254)
		(layer "F.Cu")
		(net "GND")
	)
	(segment
		(start 81.259934 -64.950086)
		(end 81.584038 -64.625982)
		(width 0.508)
		(layer "F.Cu")
		(net "GND")
	)
	(segment
		(start 23.234396 -145.362422)
		(end 22.834854 -145.761964)
		(width 0.3048)
		(layer "F.Cu")
		(net "GND")
	)
	(segment
		(start 88.3285 -130.0226)
		(end 87.5538 -130.0226)
		(width 0.508)
		(layer "F.Cu")
		(net "GND")
	)
	(segment
		(start 50.099722 -137.000234)
		(end 49.699926 -136.600438)
		(width 0.254)
		(layer "F.Cu")
		(net "GND")
	)
	(segment
		(start 64.0715 -170.27525)
		(end 62.94755 -170.27525)
		(width 0.508)
		(layer "F.Cu")
		(net "GND")
	)
	(segment
		(start 30.3022 -130.7719)
		(end 30.3022 -129.9464)
		(width 0.508)
		(layer "F.Cu")
		(net "GND")
	)
	(segment
		(start 47.29988 -152.599898)
		(end 47.69993 -152.999948)
		(width 0.254)
		(layer "F.Cu")
		(net "GND")
	)
	(segment
		(start 213.275164 -89.386156)
		(end 213.275164 -88.992456)
		(width 0.508)
		(layer "F.Cu")
		(net "GND")
	)
	(segment
		(start 81.143602 -96.149922)
		(end 81.516728 -95.776796)
		(width 0.254)
		(layer "F.Cu")
		(net "GND")
	)
	(segment
		(start 204.216 -111.2139)
		(end 204.216 -112.0394)
		(width 0.508)
		(layer "F.Cu")
		(net "GND")
	)
	(segment
		(start 17.634458 -147.761452)
		(end 17.234408 -148.161502)
		(width 0.254)
		(layer "F.Cu")
		(net "GND")
	)
	(segment
		(start 15.619222 -138.961622)
		(end 15.5194 -138.8618)
		(width 0.254)
		(layer "F.Cu")
		(net "GND")
	)
	(segment
		(start 77.63891 -52.15001)
		(end 77.827378 -52.338478)
		(width 0.508)
		(layer "F.Cu")
		(net "GND")
	)
	(segment
		(start 23.055072 -17.71777)
		(end 23.055072 -15.81277)
		(width 0.508)
		(layer "F.Cu")
		(net "GND")
	)
	(segment
		(start 79.925164 -92.95003)
		(end 81.101692 -92.95003)
		(width 0.508)
		(layer "F.Cu")
		(net "GND")
	)
	(segment
		(start 86.1949 -167.29075)
		(end 86.1949 -168.0337)
		(width 0.508)
		(layer "F.Cu")
		(net "GND")
	)
	(segment
		(start 94.03588 -147.213828)
		(end 94.729554 -146.520154)
		(width 0.508)
		(layer "F.Cu")
		(net "GND")
	)
	(segment
		(start 71.8312 -134.8994)
		(end 71.9963 -134.8994)
		(width 0.508)
		(layer "F.Cu")
		(net "GND")
	)
	(segment
		(start 98.8695 -134.8359)
		(end 98.8695 -135.4836)
		(width 0.508)
		(layer "F.Cu")
		(net "GND")
	)
	(segment
		(start 74.58583 -137.421112)
		(end 74.2188 -137.788142)
		(width 0.508)
		(layer "F.Cu")
		(net "GND")
	)
	(segment
		(start 23.234396 -145.36166)
		(end 23.234396 -145.362422)
		(width 0.3048)
		(layer "F.Cu")
		(net "GND")
	)
	(segment
		(start 80.772 -172.28058)
		(end 80.815942 -172.324522)
		(width 0.508)
		(layer "F.Cu")
		(net "GND")
	)
	(segment
		(start 47.699676 -148.999956)
		(end 47.29988 -148.60016)
		(width 0.3556)
		(layer "F.Cu")
		(net "GND")
	)
	(segment
		(start 81.304892 -70.550024)
		(end 81.643728 -70.88886)
		(width 0.508)
		(layer "F.Cu")
		(net "GND")
	)
	(segment
		(start 71.363078 -146.421602)
		(end 70.9803 -146.80438)
		(width 0.508)
		(layer "F.Cu")
		(net "GND")
	)
	(segment
		(start 34.293048 -129.5908)
		(end 30.6578 -129.5908)
		(width 0.381)
		(layer "F.Cu")
		(net "GND")
	)
	(segment
		(start 48.499776 -145.800064)
		(end 48.50003 -145.800064)
		(width 0.3556)
		(layer "F.Cu")
		(net "GND")
	)
	(segment
		(start 81.304892 -83.3501)
		(end 81.643728 -83.688936)
		(width 0.508)
		(layer "F.Cu")
		(net "GND")
	)
	(segment
		(start 201.649838 -134.875016)
		(end 201.649838 -136.25449)
		(width 0.254)
		(layer "F.Cu")
		(net "GND")
	)
	(segment
		(start 42.500042 -146.19986)
		(end 43.299888 -145.400014)
		(width 0.3556)
		(layer "F.Cu")
		(net "GND")
	)
	(segment
		(start 95.0468 -166.41191)
		(end 94.483174 -166.975536)
		(width 0.508)
		(layer "F.Cu")
		(net "GND")
	)
	(segment
		(start 75.632818 -149.318218)
		(end 75.632818 -148.810472)
		(width 0.508)
		(layer "F.Cu")
		(net "GND")
	)
	(segment
		(start 81.262728 -54.550056)
		(end 82.255868 -55.543196)
		(width 0.254)
		(layer "F.Cu")
		(net "GND")
	)
	(segment
		(start 79.925164 -70.550024)
		(end 81.304892 -70.550024)
		(width 0.508)
		(layer "F.Cu")
		(net "GND")
	)
	(segment
		(start 89.45372 -163.90747)
		(end 89.292938 -164.068252)
		(width 0.508)
		(layer "F.Cu")
		(net "GND")
	)
	(segment
		(start 17.634458 -148.561552)
		(end 17.234408 -148.961602)
		(width 0.3048)
		(layer "F.Cu")
		(net "GND")
	)
	(segment
		(start 80.772 -172.28058)
		(end 79.93888 -172.28058)
		(width 0.508)
		(layer "F.Cu")
		(net "GND")
	)
	(segment
		(start 52.900072 -147.80006)
		(end 52.899818 -147.80006)
		(width 0.3556)
		(layer "F.Cu")
		(net "GND")
	)
	(segment
		(start 74.176128 -148.810472)
		(end 73.8886 -149.098)
		(width 0.508)
		(layer "F.Cu")
		(net "GND")
	)
	(segment
		(start 47.29988 -145.400014)
		(end 47.29988 -145.438114)
		(width 0.3556)
		(layer "F.Cu")
		(net "GND")
	)
	(segment
		(start 46.900338 -141.00048)
		(end 46.900084 -141.00048)
		(width 0.3556)
		(layer "F.Cu")
		(net "GND")
	)
	(segment
		(start 48.499776 -145.79981)
		(end 48.499776 -145.800064)
		(width 0.3556)
		(layer "F.Cu")
		(net "GND")
	)
	(segment
		(start 54.0004 -131.3053)
		(end 54.0004 -130.6576)
		(width 0.508)
		(layer "F.Cu")
		(net "GND")
	)
	(segment
		(start 216.08542 -89.923112)
		(end 216.08542 -89.022682)
		(width 0.508)
		(layer "F.Cu")
		(net "GND")
	)
	(segment
		(start 89.827354 -166.616126)
		(end 89.827354 -165.92169)
		(width 0.508)
		(layer "F.Cu")
		(net "GND")
	)
	(segment
		(start 123.57989 -12.052046)
		(end 123.661424 -12.052046)
		(width 0.508)
		(layer "F.Cu")
		(net "GND")
	)
	(segment
		(start 68.6562 -158.06801)
		(end 72.91959 -158.06801)
		(width 0.508)
		(layer "F.Cu")
		(net "GND")
	)
	(segment
		(start 77.2414 -168.9608)
		(end 77.2414 -169.291)
		(width 0.508)
		(layer "F.Cu")
		(net "GND")
	)
	(segment
		(start 88.092026 -132.23875)
		(end 89.066116 -132.23875)
		(width 0.508)
		(layer "F.Cu")
		(net "GND")
	)
	(segment
		(start 66.757042 -158.660084)
		(end 65.753742 -158.660084)
		(width 0.254)
		(layer "F.Cu")
		(net "GND")
	)
	(segment
		(start 52.499768 -141.00048)
		(end 52.499514 -141.00048)
		(width 0.3556)
		(layer "F.Cu")
		(net "GND")
	)
	(segment
		(start 79.857092 -169.860468)
		(end 80.552544 -169.165016)
		(width 0.508)
		(layer "F.Cu")
		(net "GND")
	)
	(segment
		(start 122.612658 -10.63498)
		(end 122.219212 -10.241534)
		(width 0.254)
		(layer "F.Cu")
		(net "GND")
	)
	(segment
		(start 81.304892 -89.750138)
		(end 81.643728 -90.088974)
		(width 0.508)
		(layer "F.Cu")
		(net "GND")
	)
	(segment
		(start 50.499772 -150.999952)
		(end 50.099722 -150.599902)
		(width 0.3556)
		(layer "F.Cu")
		(net "GND")
	)
	(segment
		(start 183.1594 -111.4679)
		(end 183.1594 -112.2934)
		(width 0.508)
		(layer "F.Cu")
		(net "GND")
	)
	(segment
		(start 95.50908 -13.4112)
		(end 97.166938 -13.4112)
		(width 0.508)
		(layer "F.Cu")
		(net "GND")
	)
	(segment
		(start 217.75928 -103.040688)
		(end 217.75928 -103.828088)
		(width 0.508)
		(layer "F.Cu")
		(net "GND")
	)
	(segment
		(start 218.092528 -55.099966)
		(end 218.339416 -54.853078)
		(width 0.508)
		(layer "F.Cu")
		(net "GND")
	)
	(segment
		(start 68.9737 -181.6354)
		(end 68.28028 -181.6354)
		(width 0.508)
		(layer "F.Cu")
		(net "GND")
	)
	(segment
		(start 43.700192 -141.00048)
		(end 43.700446 -141.00048)
		(width 0.3556)
		(layer "F.Cu")
		(net "GND")
	)
	(segment
		(start 78.115668 -149.387052)
		(end 78.13929 -149.410674)
		(width 0.3556)
		(layer "F.Cu")
		(net "GND")
	)
	(segment
		(start 66.276474 -177.376074)
		(end 66.5226 -177.6222)
		(width 0.4064)
		(layer "F.Cu")
		(net "GND")
	)
	(segment
		(start 59.933586 -136.942068)
		(end 59.600592 -137.275062)
		(width 0.508)
		(layer "F.Cu")
		(net "GND")
	)
	(segment
		(start 22.43455 -143.76146)
		(end 22.0345 -144.16151)
		(width 0.3048)
		(layer "F.Cu")
		(net "GND")
	)
	(segment
		(start 65.753742 -158.660084)
		(end 65.741042 -158.647384)
		(width 0.254)
		(layer "F.Cu")
		(net "GND")
	)
	(segment
		(start 90.3478 -129.61112)
		(end 90.548206 -129.811526)
		(width 0.254)
		(layer "F.Cu")
		(net "GND")
	)
	(segment
		(start 23.234142 -142.961614)
		(end 22.834346 -143.36141)
		(width 0.3048)
		(layer "F.Cu")
		(net "GND")
	)
	(segment
		(start 89.53754 -137.6807)
		(end 89.594436 -137.623804)
		(width 0.254)
		(layer "F.Cu")
		(net "GND")
	)
	(segment
		(start 67.945 -164.821108)
		(end 68.187824 -165.063932)
		(width 0.508)
		(layer "F.Cu")
		(net "GND")
	)
	(segment
		(start 75.475084 -65.749932)
		(end 76.809092 -65.749932)
		(width 0.508)
		(layer "F.Cu")
		(net "GND")
	)
	(segment
		(start 16.834612 -141.361668)
		(end 17.234662 -141.761718)
		(width 0.3048)
		(layer "F.Cu")
		(net "GND")
	)
	(segment
		(start 47.73295 -143.412718)
		(end 47.73295 -143.331184)
		(width 0.3556)
		(layer "F.Cu")
		(net "GND")
	)
	(segment
		(start 42.099992 -148.199856)
		(end 42.499788 -147.80006)
		(width 0.3556)
		(layer "F.Cu")
		(net "GND")
	)
	(segment
		(start 12.954 -13.208)
		(end 12.954 -12.5095)
		(width 0.508)
		(layer "F.Cu")
		(net "GND")
	)
	(segment
		(start 170.6499 -134.875016)
		(end 170.6499 -133.225794)
		(width 0.254)
		(layer "F.Cu")
		(net "GND")
	)
	(segment
		(start 22.834854 -148.962364)
		(end 22.834854 -149.216364)
		(width 0.3048)
		(layer "F.Cu")
		(net "GND")
	)
	(segment
		(start 54.8005 -130.064764)
		(end 54.136036 -130.064764)
		(width 0.508)
		(layer "F.Cu")
		(net "GND")
	)
	(segment
		(start 146.537426 -10.05459)
		(end 146.468846 -10.05459)
		(width 0.508)
		(layer "F.Cu")
		(net "GND")
	)
	(segment
		(start 50.500026 -150.199852)
		(end 50.899822 -149.800056)
		(width 0.3048)
		(layer "F.Cu")
		(net "GND")
	)
	(segment
		(start 52.899818 -150.199852)
		(end 52.499768 -150.599902)
		(width 0.254)
		(layer "F.Cu")
		(net "GND")
	)
	(segment
		(start 46.89983 -145.838164)
		(end 46.96333 -145.838164)
		(width 0.3556)
		(layer "F.Cu")
		(net "GND")
	)
	(segment
		(start 76.991718 -51.34991)
		(end 77.126592 -51.484784)
		(width 0.508)
		(layer "F.Cu")
		(net "GND")
	)
	(segment
		(start 63.709296 -159.921956)
		(end 64.457834 -159.921956)
		(width 0.508)
		(layer "F.Cu")
		(net "GND")
	)
	(segment
		(start 23.055072 -15.81277)
		(end 23.055072 -15.11427)
		(width 0.508)
		(layer "F.Cu")
		(net "GND")
	)
	(segment
		(start 50.500026 -151.799798)
		(end 50.500026 -151.800052)
		(width 0.3556)
		(layer "F.Cu")
		(net "GND")
	)
	(segment
		(start 79.925164 -89.750138)
		(end 81.304892 -89.750138)
		(width 0.508)
		(layer "F.Cu")
		(net "GND")
	)
	(segment
		(start 75.475084 -54.550056)
		(end 77.036168 -54.550056)
		(width 0.254)
		(layer "F.Cu")
		(net "GND")
	)
	(segment
		(start 23.234396 -139.761468)
		(end 26.2636 -139.761468)
		(width 0.3048)
		(layer "F.Cu")
		(net "GND")
	)
	(segment
		(start 217.75928 -103.828088)
		(end 217.60688 -103.980488)
		(width 0.508)
		(layer "F.Cu")
		(net "GND")
	)
	(segment
		(start 47.324772 -146.19986)
		(end 47.712122 -145.81251)
		(width 0.3556)
		(layer "F.Cu")
		(net "GND")
	)
	(segment
		(start 199.9107 -107.3912)
		(end 199.0852 -107.3912)
		(width 0.508)
		(layer "F.Cu")
		(net "GND")
	)
	(segment
		(start 51.699414 -138.600434)
		(end 51.299872 -138.999976)
		(width 0.3556)
		(layer "F.Cu")
		(net "GND")
	)
	(segment
		(start 47.29988 -137.40003)
		(end 46.89983 -136.99998)
		(width 0.254)
		(layer "F.Cu")
		(net "GND")
	)
	(segment
		(start 213.275164 -88.992456)
		(end 213.643464 -88.624156)
		(width 0.508)
		(layer "F.Cu")
		(net "GND")
	)
	(segment
		(start 11.362436 -170.6372)
		(end 10.4394 -170.6372)
		(width 0.508)
		(layer "F.Cu")
		(net "GND")
	)
	(segment
		(start 48.499776 -143.400272)
		(end 48.499776 -143.400526)
		(width 0.3556)
		(layer "F.Cu")
		(net "GND")
	)
	(segment
		(start 89.4334 -170.815)
		(end 89.8398 -170.4086)
		(width 0.254)
		(layer "F.Cu")
		(net "GND")
	)
	(segment
		(start 68.326762 -178.901598)
		(end 69.152262 -178.901598)
		(width 0.508)
		(layer "F.Cu")
		(net "GND")
	)
	(segment
		(start 79.925164 -73.749916)
		(end 81.371948 -73.749916)
		(width 0.508)
		(layer "F.Cu")
		(net "GND")
	)
	(segment
		(start 40.099996 -146.99996)
		(end 39.699946 -147.40001)
		(width 0.3556)
		(layer "F.Cu")
		(net "GND")
	)
	(segment
		(start 213.649814 -134.875016)
		(end 213.649814 -136.25449)
		(width 0.254)
		(layer "F.Cu")
		(net "GND")
	)
	(segment
		(start 75.475084 -84.950046)
		(end 76.739496 -84.950046)
		(width 0.508)
		(layer "F.Cu")
		(net "GND")
	)
	(segment
		(start 95.43288 -20.7518)
		(end 95.43288 -19.98472)
		(width 0.3048)
		(layer "F.Cu")
		(net "GND")
	)
	(segment
		(start 77.017626 -94.549976)
		(end 77.283818 -94.816168)
		(width 0.508)
		(layer "F.Cu")
		(net "GND")
	)
	(segment
		(start 49.699926 -144.599914)
		(end 49.699418 -144.599914)
		(width 0.3556)
		(layer "F.Cu")
		(net "GND")
	)
	(segment
		(start 176.649888 -134.875016)
		(end 176.649888 -133.225794)
		(width 0.254)
		(layer "F.Cu")
		(net "GND")
	)
	(segment
		(start 75.475084 -69.749924)
		(end 76.8223 -69.749924)
		(width 0.508)
		(layer "F.Cu")
		(net "GND")
	)
	(segment
		(start 77.367384 -169.165016)
		(end 78.545944 -169.165016)
		(width 0.508)
		(layer "F.Cu")
		(net "GND")
	)
	(segment
		(start 94.483174 -166.975536)
		(end 90.186764 -166.975536)
		(width 0.508)
		(layer "F.Cu")
		(net "GND")
	)
	(segment
		(start 77.126592 -51.484784)
		(end 77.648562 -51.484784)
		(width 0.508)
		(layer "F.Cu")
		(net "GND")
	)
	(segment
		(start 48.6156 -128.4859)
		(end 48.6156 -129.286)
		(width 0.508)
		(layer "F.Cu")
		(net "GND")
	)
	(segment
		(start 92.44965 -53.936646)
		(end 92.44965 -53.352446)
		(width 0.381)
		(layer "F.Cu")
		(net "GND")
	)
	(segment
		(start 44.099988 -149.400006)
		(end 44.099988 -148.599906)
		(width 0.3556)
		(layer "F.Cu")
		(net "GND")
	)
	(segment
		(start 89.292938 -164.068252)
		(end 89.292938 -164.661596)
		(width 0.508)
		(layer "F.Cu")
		(net "GND")
	)
	(segment
		(start 94.03588 -147.468844)
		(end 94.737936 -148.1709)
		(width 0.381)
		(layer "F.Cu")
		(net "GND")
	)
	(segment
		(start 84.63153 -147.307046)
		(end 85.070442 -147.307046)
		(width 0.508)
		(layer "F.Cu")
		(net "GND")
	)
	(segment
		(start 58.928 -163.2331)
		(end 58.928 -163.627562)
		(width 0.508)
		(layer "F.Cu")
		(net "GND")
	)
	(segment
		(start 49.299622 -141.00048)
		(end 49.299368 -141.00048)
		(width 0.254)
		(layer "F.Cu")
		(net "GND")
	)
	(segment
		(start 49.299368 -141.00048)
		(end 48.899826 -141.400022)
		(width 0.254)
		(layer "F.Cu")
		(net "GND")
	)
	(segment
		(start 48.499776 -144.200372)
		(end 48.499522 -144.200372)
		(width 0.3556)
		(layer "F.Cu")
		(net "GND")
	)
	(segment
		(start 46.900084 -146.600164)
		(end 46.89983 -146.600164)
		(width 0.3556)
		(layer "F.Cu")
		(net "GND")
	)
	(segment
		(start 16.834358 -144.56156)
		(end 16.434054 -144.961864)
		(width 0.3048)
		(layer "F.Cu")
		(net "GND")
	)
	(segment
		(start 83.406996 -173.80458)
		(end 84.537296 -173.80458)
		(width 0.508)
		(layer "F.Cu")
		(net "GND")
	)
	(segment
		(start 48.499776 -143.400526)
		(end 48.499776 -143.422624)
		(width 0.3556)
		(layer "F.Cu")
		(net "GND")
	)
	(segment
		(start 77.029056 -92.14993)
		(end 77.283818 -91.895168)
		(width 0.508)
		(layer "F.Cu")
		(net "GND")
	)
	(segment
		(start 50.899822 -151.399748)
		(end 50.899822 -151.400002)
		(width 0.3556)
		(layer "F.Cu")
		(net "GND")
	)
	(segment
		(start 40.099488 -142.199868)
		(end 39.699438 -141.799818)
		(width 0.3556)
		(layer "F.Cu")
		(net "GND")
	)
	(segment
		(start 77.851762 -157.6197)
		(end 77.851762 -158.166054)
		(width 0.508)
		(layer "F.Cu")
		(net "GND")
	)
	(segment
		(start 92.6084 -126.401068)
		(end 93.1926 -126.985268)
		(width 0.254)
		(layer "F.Cu")
		(net "GND")
	)
	(segment
		(start 77.274928 -54.311296)
		(end 77.596492 -54.311296)
		(width 0.254)
		(layer "F.Cu")
		(net "GND")
	)
	(segment
		(start 66.808604 -170.111674)
		(end 66.808604 -169.170096)
		(width 0.508)
		(layer "F.Cu")
		(net "GND")
	)
	(segment
		(start 56.19115 -124.5362)
		(end 57.6834 -124.5362)
		(width 0.508)
		(layer "F.Cu")
		(net "GND")
	)
	(segment
		(start 84.537296 -173.80458)
		(end 84.79282 -174.060104)
		(width 0.508)
		(layer "F.Cu")
		(net "GND")
	)
	(segment
		(start 77.81798 -188.5188)
		(end 77.84338 -188.5188)
		(width 0.508)
		(layer "F.Cu")
		(net "GND")
	)
	(segment
		(start 43.700192 -149.799802)
		(end 44.099988 -149.400006)
		(width 0.3556)
		(layer "F.Cu")
		(net "GND")
	)
	(segment
		(start 27.502358 -146.30146)
		(end 27.50947 -146.308572)
		(width 0.508)
		(layer "F.Cu")
		(net "GND")
	)
	(segment
		(start 76.748386 -82.55)
		(end 77.283818 -82.014568)
		(width 0.508)
		(layer "F.Cu")
		(net "GND")
	)
	(segment
		(start 70.485 -153.6192)
		(end 69.7992 -154.305)
		(width 0.508)
		(layer "F.Cu")
		(net "GND")
	)
	(segment
		(start 75.475084 -72.14997)
		(end 76.74102 -72.14997)
		(width 0.508)
		(layer "F.Cu")
		(net "GND")
	)
	(segment
		(start 94.737936 -148.1709)
		(end 95.1484 -148.1709)
		(width 0.381)
		(layer "F.Cu")
		(net "GND")
	)
	(segment
		(start 29.9212 -129.921)
		(end 30.3276 -129.921)
		(width 0.381)
		(layer "F.Cu")
		(net "GND")
	)
	(segment
		(start 90.368374 -132.811774)
		(end 91.208352 -132.811774)
		(width 0.508)
		(layer "F.Cu")
		(net "GND")
	)
	(segment
		(start 49.299622 -143.400526)
		(end 49.299368 -143.400526)
		(width 0.3556)
		(layer "F.Cu")
		(net "GND")
	)
	(segment
		(start 47.69993 -146.600164)
		(end 47.699676 -146.600164)
		(width 0.3556)
		(layer "F.Cu")
		(net "GND")
	)
	(segment
		(start 86.368636 -28.476448)
		(end 86.368636 -27.553412)
		(width 0.508)
		(layer "F.Cu")
		(net "GND")
	)
	(segment
		(start 47.29988 -145.438114)
		(end 46.89983 -145.838164)
		(width 0.3556)
		(layer "F.Cu")
		(net "GND")
	)
	(segment
		(start 94.488 -18.3007)
		(end 95.3262 -18.3007)
		(width 0.4064)
		(layer "F.Cu")
		(net "GND")
	)
	(segment
		(start 122.675904 -13.39977)
		(end 122.528838 -13.252704)
		(width 0.508)
		(layer "F.Cu")
		(net "GND")
	)
	(segment
		(start 74.680572 -169.108628)
		(end 74.680572 -169.473372)
		(width 0.508)
		(layer "F.Cu")
		(net "GND")
	)
	(segment
		(start 122.675904 -14.167612)
		(end 122.675904 -13.39977)
		(width 0.508)
		(layer "F.Cu")
		(net "GND")
	)
	(segment
		(start 52.1462 -159.2326)
		(end 51.6382 -159.7406)
		(width 0.508)
		(layer "F.Cu")
		(net "GND")
	)
	(segment
		(start 38.544246 -176.69891)
		(end 37.680646 -176.69891)
		(width 0.508)
		(layer "F.Cu")
		(net "GND")
	)
	(segment
		(start 47.699676 -146.600164)
		(end 47.29988 -146.99996)
		(width 0.3556)
		(layer "F.Cu")
		(net "GND")
	)
	(segment
		(start 79.925164 -52.15001)
		(end 78.015846 -52.15001)
		(width 0.508)
		(layer "F.Cu")
		(net "GND")
	)
	(segment
		(start 66.276474 -175.913796)
		(end 66.276474 -177.376074)
		(width 0.4064)
		(layer "F.Cu")
		(net "GND")
	)
	(segment
		(start 76.739496 -84.950046)
		(end 77.283818 -85.494368)
		(width 0.508)
		(layer "F.Cu")
		(net "GND")
	)
	(segment
		(start 16.458184 -164.5539)
		(end 16.458184 -165.327584)
		(width 0.508)
		(layer "F.Cu")
		(net "GND")
	)
	(segment
		(start 46.91253 -144.187164)
		(end 46.88713 -144.187164)
		(width 0.3556)
		(layer "F.Cu")
		(net "GND")
	)
	(segment
		(start 40.099996 -148.599906)
		(end 39.699946 -148.999956)
		(width 0.3048)
		(layer "F.Cu")
		(net "GND")
	)
	(segment
		(start 49.699672 -146.19986)
		(end 49.699926 -146.19986)
		(width 0.3556)
		(layer "F.Cu")
		(net "GND")
	)
	(segment
		(start 95.50908 -12.2428)
		(end 97.188274 -12.2428)
		(width 0.508)
		(layer "F.Cu")
		(net "GND")
	)
	(segment
		(start 51.6509 -128.7018)
		(end 51.6509 -127.8382)
		(width 0.508)
		(layer "F.Cu")
		(net "GND")
	)
	(segment
		(start 46.88713 -144.187164)
		(end 47.29988 -144.599914)
		(width 0.3556)
		(layer "F.Cu")
		(net "GND")
	)
	(segment
		(start 46.500034 -144.600168)
		(end 46.500034 -144.599914)
		(width 0.3556)
		(layer "F.Cu")
		(net "GND")
	)
	(segment
		(start 49.299622 -144.200372)
		(end 49.699926 -143.800068)
		(width 0.3556)
		(layer "F.Cu")
		(net "GND")
	)
	(segment
		(start 46.89983 -136.99998)
		(end 47.29988 -136.59993)
		(width 0.254)
		(layer "F.Cu")
		(net "GND")
	)
	(segment
		(start 125.2855 -7.62)
		(end 125.2855 -8.5344)
		(width 0.254)
		(layer "F.Cu")
		(net "GND")
	)
	(segment
		(start 213.390988 -40.719756)
		(end 213.390988 -39.779956)
		(width 0.508)
		(layer "F.Cu")
		(net "GND")
	)
	(segment
		(start 79.925418 -77.750162)
		(end 81.318862 -77.750162)
		(width 0.508)
		(layer "F.Cu")
		(net "GND")
	)
	(segment
		(start 23.234396 -146.961606)
		(end 23.234396 -146.961352)
		(width 0.254)
		(layer "F.Cu")
		(net "GND")
	)
	(segment
		(start 86.368636 -27.553412)
		(end 86.38032 -27.541728)
		(width 0.508)
		(layer "F.Cu")
		(net "GND")
	)
	(segment
		(start 68.6562 -158.06801)
		(end 68.6562 -157.158944)
		(width 0.254)
		(layer "F.Cu")
		(net "GND")
	)
	(segment
		(start 88.773 -29.464)
		(end 88.6206 -29.3116)
		(width 0.254)
		(layer "F.Cu")
		(net "GND")
	)
	(segment
		(start 28.64993 -179.57673)
		(end 28.2702 -179.197)
		(width 0.508)
		(layer "F.Cu")
		(net "GND")
	)
	(segment
		(start 66.802 -171.6405)
		(end 67.7037 -171.6405)
		(width 0.508)
		(layer "F.Cu")
		(net "GND")
	)
	(segment
		(start 79.925164 -67.350132)
		(end 81.268062 -67.350132)
		(width 0.508)
		(layer "F.Cu")
		(net "GND")
	)
	(segment
		(start 204.649832 -134.875016)
		(end 204.649832 -136.25449)
		(width 0.254)
		(layer "F.Cu")
		(net "GND")
	)
	(segment
		(start 214.83828 -93.212666)
		(end 215.32088 -93.695266)
		(width 0.508)
		(layer "F.Cu")
		(net "GND")
	)
	(segment
		(start 61.907674 -178.390296)
		(end 61.907674 -177.96256)
		(width 0.254)
		(layer "F.Cu")
		(net "GND")
	)
	(segment
		(start 69.4436 -118.2116)
		(end 69.0499 -118.2116)
		(width 0.508)
		(layer "F.Cu")
		(net "GND")
	)
	(segment
		(start 89.447116 -45.5422)
		(end 90.2462 -45.5422)
		(width 0.254)
		(layer "F.Cu")
		(net "GND")
	)
	(segment
		(start 58.50001 -172.699934)
		(end 59.7154 -172.699934)
		(width 0.508)
		(layer "F.Cu")
		(net "GND")
	)
	(segment
		(start 86.1949 -168.0337)
		(end 86.36 -168.1988)
		(width 0.508)
		(layer "F.Cu")
		(net "GND")
	)
	(segment
		(start 50.899822 -151.400002)
		(end 50.500026 -151.799798)
		(width 0.3556)
		(layer "F.Cu")
		(net "GND")
	)
	(segment
		(start 30.6578 -129.5908)
		(end 30.3276 -129.921)
		(width 0.381)
		(layer "F.Cu")
		(net "GND")
	)
	(segment
		(start 77.685646 -149.817074)
		(end 78.115668 -149.387052)
		(width 0.508)
		(layer "F.Cu")
		(net "GND")
	)
	(segment
		(start 61.907674 -177.96256)
		(end 62.476634 -177.3936)
		(width 0.254)
		(layer "F.Cu")
		(net "GND")
	)
	(segment
		(start 73.787 -157.2006)
		(end 73.787 -154.8384)
		(width 0.508)
		(layer "F.Cu")
		(net "GND")
	)
	(segment
		(start 78.13929 -149.410674)
		(end 79.314548 -149.410674)
		(width 0.3556)
		(layer "F.Cu")
		(net "GND")
	)
	(segment
		(start 80.663288 -153.231596)
		(end 80.663288 -153.208482)
		(width 0.508)
		(layer "F.Cu")
		(net "GND")
	)
	(segment
		(start 88.31072 -162.487356)
		(end 88.471756 -162.648392)
		(width 0.508)
		(layer "F.Cu")
		(net "GND")
	)
	(via
		(at 78.115668 -149.387052)
		(size 0.508)
		(drill 0.254)
		(layers "F.Cu" "B.Cu")
		(net "GND")
	)
	(via
		(at 48.6918 -179.06619)
		(size 0.7112)
		(drill 0.4064)
		(layers "F.Cu" "B.Cu")
		(net "GND")
	)
	(via
		(at 187.97651 -24.38019)
		(size 0.7112)
		(drill 0.4064)
		(layers "F.Cu" "B.Cu")
		(net "GND")
	)
	(via
		(at 80.4418 -160.4518)
		(size 0.6096)
		(drill 0.3048)
		(layers "F.Cu" "B.Cu")
		(net "GND")
	)
	(via
		(at 218.661488 -47.31131)
		(size 0.5588)
		(drill 0.3048)
		(layers "F.Cu" "B.Cu")
		(net "GND")
	)
	(via
		(at 2.162556 -57.300622)
		(size 0.7112)
		(drill 0.4064)
		(layers "F.Cu" "B.Cu")
		(net "GND")
	)
	(via
		(at 228.781864 -79.008732)
		(size 0.7112)
		(drill 0.4064)
		(layers "F.Cu" "B.Cu")
		(net "GND")
	)
	(via
		(at 81.36128 -180.77688)
		(size 0.7112)
		(drill 0.4064)
		(layers "F.Cu" "B.Cu")
		(net "GND")
	)
	(via
		(at 198.13651 -29.46019)
		(size 0.7112)
		(drill 0.4064)
		(layers "F.Cu" "B.Cu")
		(net "GND")
	)
	(via
		(at 98.848672 -188.867288)
		(size 0.7112)
		(drill 0.4064)
		(layers "F.Cu" "B.Cu")
		(net "GND")
	)
	(via
		(at 82.2452 -57.658)
		(size 0.508)
		(drill 0.254)
		(layers "F.Cu" "B.Cu")
		(net "GND")
	)
	(via
		(at 71.2724 -180.7718)
		(size 0.508)
		(drill 0.254)
		(layers "F.Cu" "B.Cu")
		(net "GND")
	)
	(via
		(at 2.162556 -80.160622)
		(size 0.7112)
		(drill 0.4064)
		(layers "F.Cu" "B.Cu")
		(net "GND")
	)
	(via
		(at 48.61433 -191.837564)
		(size 0.7112)
		(drill 0.4064)
		(layers "F.Cu" "B.Cu")
		(net "GND")
	)
	(via
		(at 33.37433 -191.837564)
		(size 0.7112)
		(drill 0.4064)
		(layers "F.Cu" "B.Cu")
		(net "GND")
	)
	(via
		(at 187.97651 -21.84019)
		(size 0.7112)
		(drill 0.4064)
		(layers "F.Cu" "B.Cu")
		(net "GND")
	)
	(via
		(at 70.9803 -146.80438)
		(size 0.508)
		(drill 0.254)
		(layers "F.Cu" "B.Cu")
		(net "GND")
	)
	(via
		(at 208.29651 -37.08019)
		(size 0.7112)
		(drill 0.4064)
		(layers "F.Cu" "B.Cu")
		(net "GND")
	)
	(via
		(at 75.192636 -16.256508)
		(size 0.7112)
		(drill 0.4064)
		(layers "F.Cu" "B.Cu")
		(net "GND")
	)
	(via
		(at 220.490288 -47.31131)
		(size 0.5588)
		(drill 0.3048)
		(layers "F.Cu" "B.Cu")
		(net "GND")
	)
	(via
		(at 100.6348 -151.6888)
		(size 0.508)
		(drill 0.254)
		(layers "F.Cu" "B.Cu")
		(net "GND")
	)
	(via
		(at 222.25508 -96.411288)
		(size 0.5588)
		(drill 0.3048)
		(layers "F.Cu" "B.Cu")
		(net "GND")
	)
	(via
		(at 146.462496 -85.90407)
		(size 0.7112)
		(drill 0.4064)
		(layers "F.Cu" "B.Cu")
		(net "GND")
	)
	(via
		(at 190.51651 -47.24019)
		(size 0.7112)
		(drill 0.4064)
		(layers "F.Cu" "B.Cu")
		(net "GND")
	)
	(via
		(at 70.6501 -161.8615)
		(size 0.508)
		(drill 0.254)
		(layers "F.Cu" "B.Cu")
		(net "GND")
	)
	(via
		(at 75.192636 -22.606508)
		(size 0.7112)
		(drill 0.4064)
		(layers "F.Cu" "B.Cu")
		(net "GND")
	)
	(via
		(at 8.559038 -142.459964)
		(size 0.508)
		(drill 0.254)
		(layers "F.Cu" "B.Cu")
		(net "GND")
	)
	(via
		(at 2.162556 -133.500622)
		(size 0.7112)
		(drill 0.4064)
		(layers "F.Cu" "B.Cu")
		(net "GND")
	)
	(via
		(at 78.296262 -135.936228)
		(size 0.6096)
		(drill 0.3048)
		(layers "F.Cu" "B.Cu")
		(net "GND")
	)
	(via
		(at 108.89996 -45.600112)
		(size 0.6604)
		(drill 0.3556)
		(layers "F.Cu" "B.Cu")
		(net "GND")
	)
	(via
		(at 51.2318 -179.06619)
		(size 0.7112)
		(drill 0.4064)
		(layers "F.Cu" "B.Cu")
		(net "GND")
	)
	(via
		(at 190.51651 -57.40019)
		(size 0.7112)
		(drill 0.4064)
		(layers "F.Cu" "B.Cu")
		(net "GND")
	)
	(via
		(at 28.367482 -23.689564)
		(size 0.7112)
		(drill 0.4064)
		(layers "F.Cu" "B.Cu")
		(net "GND")
	)
	(via
		(at 187.97651 -75.18019)
		(size 0.7112)
		(drill 0.4064)
		(layers "F.Cu" "B.Cu")
		(net "GND")
	)
	(via
		(at 221.404688 -49.85131)
		(size 0.5588)
		(drill 0.3048)
		(layers "F.Cu" "B.Cu")
		(net "GND")
	)
	(via
		(at 66.757804 -168.217596)
		(size 0.508)
		(drill 0.254)
		(layers "F.Cu" "B.Cu")
		(net "GND")
	)
	(via
		(at 82.90433 -191.837564)
		(size 0.7112)
		(drill 0.4064)
		(layers "F.Cu" "B.Cu")
		(net "GND")
	)
	(via
		(at 71.78548 -162.8013)
		(size 0.508)
		(drill 0.254)
		(layers "F.Cu" "B.Cu")
		(net "GND")
	)
	(via
		(at 188.087 -108.4072)
		(size 0.508)
		(drill 0.254)
		(layers "F.Cu" "B.Cu")
		(net "GND")
	)
	(via
		(at 171.69765 -157.837378)
		(size 0.7112)
		(drill 0.4064)
		(layers "F.Cu" "B.Cu")
		(net "GND")
	)
	(via
		(at 193.05651 -110.74019)
		(size 0.7112)
		(drill 0.4064)
		(layers "F.Cu" "B.Cu")
		(net "GND")
	)
	(via
		(at 76.501244 -163.4871)
		(size 0.5588)
		(drill 0.3048)
		(layers "F.Cu" "B.Cu")
		(net "GND")
	)
	(via
		(at 232.837482 -155.543758)
		(size 0.7112)
		(drill 0.4064)
		(layers "F.Cu" "B.Cu")
		(net "GND")
	)
	(via
		(at 232.272078 -184.620154)
		(size 0.7112)
		(drill 0.4064)
		(layers "F.Cu" "B.Cu")
		(net "GND")
	)
	(via
		(at 22.834346 -145.761456)
		(size 0.508)
		(drill 0.254)
		(layers "F.Cu" "B.Cu")
		(net "GND")
	)
	(via
		(at 89.292938 -164.068252)
		(size 0.508)
		(drill 0.254)
		(layers "F.Cu" "B.Cu")
		(net "GND")
	)
	(via
		(at 74.2696 -161.798)
		(size 0.508)
		(drill 0.254)
		(layers "F.Cu" "B.Cu")
		(net "GND")
	)
	(via
		(at 37.592 -119.126)
		(size 0.508)
		(drill 0.254)
		(layers "F.Cu" "B.Cu")
		(net "GND")
	)
	(via
		(at 195.59651 -95.50019)
		(size 0.7112)
		(drill 0.4064)
		(layers "F.Cu" "B.Cu")
		(net "GND")
	)
	(via
		(at 147.560284 -151.684736)
		(size 0.7112)
		(drill 0.4064)
		(layers "F.Cu" "B.Cu")
		(net "GND")
	)
	(via
		(at 200.67651 -62.48019)
		(size 0.7112)
		(drill 0.4064)
		(layers "F.Cu" "B.Cu")
		(net "GND")
	)
	(via
		(at 217.60688 -103.980488)
		(size 0.508)
		(drill 0.254)
		(layers "F.Cu" "B.Cu")
		(net "GND")
	)
	(via
		(at 69.9262 -118.6942)
		(size 0.508)
		(drill 0.254)
		(layers "F.Cu" "B.Cu")
		(net "GND")
	)
	(via
		(at 213.390988 -39.779956)
		(size 0.508)
		(drill 0.254)
		(layers "F.Cu" "B.Cu")
		(net "GND")
	)
	(via
		(at 232.837482 -161.893758)
		(size 0.7112)
		(drill 0.4064)
		(layers "F.Cu" "B.Cu")
		(net "GND")
	)
	(via
		(at 184.39765 -157.837378)
		(size 0.7112)
		(drill 0.4064)
		(layers "F.Cu" "B.Cu")
		(net "GND")
	)
	(via
		(at 10.4394 -170.6372)
		(size 0.508)
		(drill 0.254)
		(layers "F.Cu" "B.Cu")
		(net "GND")
	)
	(via
		(at 232.837482 -123.793758)
		(size 0.7112)
		(drill 0.4064)
		(layers "F.Cu" "B.Cu")
		(net "GND")
	)
	(via
		(at 28.367482 -21.149564)
		(size 0.7112)
		(drill 0.4064)
		(layers "F.Cu" "B.Cu")
		(net "GND")
	)
	(via
		(at 37.18433 -191.837564)
		(size 0.7112)
		(drill 0.4064)
		(layers "F.Cu" "B.Cu")
		(net "GND")
	)
	(via
		(at 228.041962 -55.291736)
		(size 0.7112)
		(drill 0.4064)
		(layers "F.Cu" "B.Cu")
		(net "GND")
	)
	(via
		(at 198.13651 -59.94019)
		(size 0.7112)
		(drill 0.4064)
		(layers "F.Cu" "B.Cu")
		(net "GND")
	)
	(via
		(at 166.077138 -6.885178)
		(size 0.7112)
		(drill 0.4064)
		(layers "F.Cu" "B.Cu")
		(net "GND")
	)
	(via
		(at 2.162556 -129.690622)
		(size 0.7112)
		(drill 0.4064)
		(layers "F.Cu" "B.Cu")
		(net "GND")
	)
	(via
		(at 207.147414 -89.938606)
		(size 0.508)
		(drill 0.254)
		(layers "F.Cu" "B.Cu")
		(net "GND")
	)
	(via
		(at 201.829416 -131.846828)
		(size 0.7112)
		(drill 0.4064)
		(layers "F.Cu" "B.Cu")
		(net "GND")
	)
	(via
		(at 22.834854 -149.216364)
		(size 0.508)
		(drill 0.254)
		(layers "F.Cu" "B.Cu")
		(net "GND")
	)
	(via
		(at 10.52449 -2.162556)
		(size 0.7112)
		(drill 0.4064)
		(layers "F.Cu" "B.Cu")
		(net "GND")
	)
	(via
		(at 133.35 -19.3802)
		(size 0.7112)
		(drill 0.4064)
		(layers "F.Cu" "B.Cu")
		(net "GND")
	)
	(via
		(at 68.6562 -158.06801)
		(size 0.508)
		(drill 0.254)
		(layers "F.Cu" "B.Cu")
		(net "GND")
	)
	(via
		(at 198.13651 -32.00019)
		(size 0.7112)
		(drill 0.4064)
		(layers "F.Cu" "B.Cu")
		(net "GND")
	)
	(via
		(at 193.05651 -92.96019)
		(size 0.7112)
		(drill 0.4064)
		(layers "F.Cu" "B.Cu")
		(net "GND")
	)
	(via
		(at 40.99433 -191.837564)
		(size 0.7112)
		(drill 0.4064)
		(layers "F.Cu" "B.Cu")
		(net "GND")
	)
	(via
		(at 89.123266 -132.1816)
		(size 0.508)
		(drill 0.254)
		(layers "F.Cu" "B.Cu")
		(net "GND")
	)
	(via
		(at 174.851568 -132.202428)
		(size 0.7112)
		(drill 0.4064)
		(layers "F.Cu" "B.Cu")
		(net "GND")
	)
	(via
		(at 18.14449 -2.162556)
		(size 0.7112)
		(drill 0.4064)
		(layers "F.Cu" "B.Cu")
		(net "GND")
	)
	(via
		(at 232.837482 -92.043758)
		(size 0.7112)
		(drill 0.4064)
		(layers "F.Cu" "B.Cu")
		(net "GND")
	)
	(via
		(at 18.650458 -177.61839)
		(size 0.508)
		(drill 0.254)
		(layers "F.Cu" "B.Cu")
		(net "GND")
	)
	(via
		(at 62.94755 -170.27525)
		(size 0.508)
		(drill 0.254)
		(layers "F.Cu" "B.Cu")
		(net "GND")
	)
	(via
		(at 74.880216 -176.581816)
		(size 0.508)
		(drill 0.254)
		(layers "F.Cu" "B.Cu")
		(net "GND")
	)
	(via
		(at 146.462496 -60.50407)
		(size 0.7112)
		(drill 0.4064)
		(layers "F.Cu" "B.Cu")
		(net "GND")
	)
	(via
		(at 17.234408 -148.161502)
		(size 0.508)
		(drill 0.254)
		(layers "F.Cu" "B.Cu")
		(net "GND")
	)
	(via
		(at 11.79449 -2.162556)
		(size 0.7112)
		(drill 0.4064)
		(layers "F.Cu" "B.Cu")
		(net "GND")
	)
	(via
		(at 2.162556 -6.500622)
		(size 0.7112)
		(drill 0.4064)
		(layers "F.Cu" "B.Cu")
		(net "GND")
	)
	(via
		(at 232.837482 -84.423758)
		(size 0.7112)
		(drill 0.4064)
		(layers "F.Cu" "B.Cu")
		(net "GND")
	)
	(via
		(at 23.055072 -17.71777)
		(size 0.508)
		(drill 0.254)
		(layers "F.Cu" "B.Cu")
		(net "GND")
	)
	(via
		(at 146.462496 -143.05407)
		(size 0.7112)
		(drill 0.4064)
		(layers "F.Cu" "B.Cu")
		(net "GND")
	)
	(via
		(at 200.67651 -67.56019)
		(size 0.7112)
		(drill 0.4064)
		(layers "F.Cu" "B.Cu")
		(net "GND")
	)
	(via
		(at 2.162556 -15.390622)
		(size 0.7112)
		(drill 0.4064)
		(layers "F.Cu" "B.Cu")
		(net "GND")
	)
	(via
		(at 208.294986 -84.252054)
		(size 0.508)
		(drill 0.254)
		(layers "F.Cu" "B.Cu")
		(net "GND")
	)
	(via
		(at 100.2792 -154.8638)
		(size 0.508)
		(drill 0.254)
		(layers "F.Cu" "B.Cu")
		(net "GND")
	)
	(via
		(at 40.500046 -144.200118)
		(size 0.4572)
		(drill 0.2032)
		(layers "F.Cu" "B.Cu")
		(net "GND")
	)
	(via
		(at 75.83678 -188.89218)
		(size 0.508)
		(drill 0.254)
		(layers "F.Cu" "B.Cu")
		(net "GND")
	)
	(via
		(at 28.367482 -94.809564)
		(size 0.7112)
		(drill 0.4064)
		(layers "F.Cu" "B.Cu")
		(net "GND")
	)
	(via
		(at 227.88753 -70.024752)
		(size 0.7112)
		(drill 0.4064)
		(layers "F.Cu" "B.Cu")
		(net "GND")
	)
	(via
		(at 182.89651 -115.82019)
		(size 0.7112)
		(drill 0.4064)
		(layers "F.Cu" "B.Cu")
		(net "GND")
	)
	(via
		(at 15.3924 -170.4086)
		(size 0.5588)
		(drill 0.3048)
		(layers "F.Cu" "B.Cu")
		(net "GND")
	)
	(via
		(at 65.12433 -191.837564)
		(size 0.7112)
		(drill 0.4064)
		(layers "F.Cu" "B.Cu")
		(net "GND")
	)
	(via
		(at 190.51651 -44.70019)
		(size 0.7112)
		(drill 0.4064)
		(layers "F.Cu" "B.Cu")
		(net "GND")
	)
	(via
		(at 193.05651 -113.28019)
		(size 0.7112)
		(drill 0.4064)
		(layers "F.Cu" "B.Cu")
		(net "GND")
	)
	(via
		(at 48.615092 -129.286)
		(size 0.508)
		(drill 0.254)
		(layers "F.Cu" "B.Cu")
		(net "GND")
	)
	(via
		(at 28.367482 -30.039564)
		(size 0.7112)
		(drill 0.4064)
		(layers "F.Cu" "B.Cu")
		(net "GND")
	)
	(via
		(at 146.462496 -102.41407)
		(size 0.7112)
		(drill 0.4064)
		(layers "F.Cu" "B.Cu")
		(net "GND")
	)
	(via
		(at 48.499776 -145.800064)
		(size 0.4572)
		(drill 0.2032)
		(layers "F.Cu" "B.Cu")
		(net "GND")
	)
	(via
		(at 86.38032 -27.541728)
		(size 0.508)
		(drill 0.254)
		(layers "F.Cu" "B.Cu")
		(net "GND")
	)
	(via
		(at 198.13651 -115.82019)
		(size 0.7112)
		(drill 0.4064)
		(layers "F.Cu" "B.Cu")
		(net "GND")
	)
	(via
		(at 28.367482 -84.649564)
		(size 0.7112)
		(drill 0.4064)
		(layers "F.Cu" "B.Cu")
		(net "GND")
	)
	(via
		(at 92.751656 -155.60548)
		(size 0.5588)
		(drill 0.3048)
		(layers "F.Cu" "B.Cu")
		(net "GND")
	)
	(via
		(at 79.041244 -162.1917)
		(size 0.5588)
		(drill 0.3048)
		(layers "F.Cu" "B.Cu")
		(net "GND")
	)
	(via
		(at 146.462496 -130.35407)
		(size 0.7112)
		(drill 0.4064)
		(layers "F.Cu" "B.Cu")
		(net "GND")
	)
	(via
		(at 20.597876 -127.550164)
		(size 0.508)
		(drill 0.254)
		(layers "F.Cu" "B.Cu")
		(net "GND")
	)
	(via
		(at 182.89651 -32.00019)
		(size 0.7112)
		(drill 0.4064)
		(layers "F.Cu" "B.Cu")
		(net "GND")
	)
	(via
		(at 200.67651 -100.58019)
		(size 0.7112)
		(drill 0.4064)
		(layers "F.Cu" "B.Cu")
		(net "GND")
	)
	(via
		(at 232.837482 -130.143758)
		(size 0.7112)
		(drill 0.4064)
		(layers "F.Cu" "B.Cu")
		(net "GND")
	)
	(via
		(at 172.96765 -157.837378)
		(size 0.7112)
		(drill 0.4064)
		(layers "F.Cu" "B.Cu")
		(net "GND")
	)
	(via
		(at 223.106488 -48.58131)
		(size 0.5588)
		(drill 0.3048)
		(layers "F.Cu" "B.Cu")
		(net "GND")
	)
	(via
		(at 204.216 -112.0394)
		(size 0.508)
		(drill 0.254)
		(layers "F.Cu" "B.Cu")
		(net "GND")
	)
	(via
		(at 2.162556 -155.090622)
		(size 0.7112)
		(drill 0.4064)
		(layers "F.Cu" "B.Cu")
		(net "GND")
	)
	(via
		(at 232.837482 -46.323758)
		(size 0.7112)
		(drill 0.4064)
		(layers "F.Cu" "B.Cu")
		(net "GND")
	)
	(via
		(at 51.699668 -149.800056)
		(size 0.4572)
		(drill 0.2032)
		(layers "F.Cu" "B.Cu")
		(net "GND")
	)
	(via
		(at 122.528838 -13.252704)
		(size 0.508)
		(drill 0.254)
		(layers "F.Cu" "B.Cu")
		(net "GND")
	)
	(via
		(at 90.2462 -45.5422)
		(size 0.508)
		(drill 0.254)
		(layers "F.Cu" "B.Cu")
		(net "GND")
	)
	(via
		(at 19.151346 -127.553466)
		(size 0.508)
		(drill 0.254)
		(layers "F.Cu" "B.Cu")
		(net "GND")
	)
	(via
		(at 48.499776 -143.400526)
		(size 0.4572)
		(drill 0.2032)
		(layers "F.Cu" "B.Cu")
		(net "GND")
	)
	(via
		(at 217.162634 -170.767502)
		(size 0.7112)
		(drill 0.4064)
		(layers "F.Cu" "B.Cu")
		(net "GND")
	)
	(via
		(at 208.29651 -65.02019)
		(size 0.7112)
		(drill 0.4064)
		(layers "F.Cu" "B.Cu")
		(net "GND")
	)
	(via
		(at 185.43651 -98.04019)
		(size 0.7112)
		(drill 0.4064)
		(layers "F.Cu" "B.Cu")
		(net "GND")
	)
	(via
		(at 173.837346 -119.883936)
		(size 0.7112)
		(drill 0.4064)
		(layers "F.Cu" "B.Cu")
		(net "GND")
	)
	(via
		(at 182.89651 -118.36019)
		(size 0.7112)
		(drill 0.4064)
		(layers "F.Cu" "B.Cu")
		(net "GND")
	)
	(via
		(at 2.162556 -148.740622)
		(size 0.7112)
		(drill 0.4064)
		(layers "F.Cu" "B.Cu")
		(net "GND")
	)
	(via
		(at 7.40791 -135.283448)
		(size 0.508)
		(drill 0.254)
		(layers "F.Cu" "B.Cu")
		(net "GND")
	)
	(via
		(at 28.367482 -24.959564)
		(size 0.7112)
		(drill 0.4064)
		(layers "F.Cu" "B.Cu")
		(net "GND")
	)
	(via
		(at 98.5012 -134.4676)
		(size 0.508)
		(drill 0.254)
		(layers "F.Cu" "B.Cu")
		(net "GND")
	)
	(via
		(at 198.13651 -87.88019)
		(size 0.7112)
		(drill 0.4064)
		(layers "F.Cu" "B.Cu")
		(net "GND")
	)
	(via
		(at 198.13651 -57.40019)
		(size 0.7112)
		(drill 0.4064)
		(layers "F.Cu" "B.Cu")
		(net "GND")
	)
	(via
		(at 64.827912 -160.292034)
		(size 0.508)
		(drill 0.254)
		(layers "F.Cu" "B.Cu")
		(net "GND")
	)
	(via
		(at 194.55765 -157.837378)
		(size 0.7112)
		(drill 0.4064)
		(layers "F.Cu" "B.Cu")
		(net "GND")
	)
	(via
		(at 232.837482 -57.753758)
		(size 0.7112)
		(drill 0.4064)
		(layers "F.Cu" "B.Cu")
		(net "GND")
	)
	(via
		(at 175.50765 -157.837378)
		(size 0.7112)
		(drill 0.4064)
		(layers "F.Cu" "B.Cu")
		(net "GND")
	)
	(via
		(at 46.940978 -163.566602)
		(size 0.508)
		(drill 0.254)
		(layers "F.Cu" "B.Cu")
		(net "GND")
	)
	(via
		(at 203.44765 -157.837378)
		(size 0.7112)
		(drill 0.4064)
		(layers "F.Cu" "B.Cu")
		(net "GND")
	)
	(via
		(at 141.40434 -16.440404)
		(size 0.7112)
		(drill 0.4064)
		(layers "F.Cu" "B.Cu")
		(net "GND")
	)
	(via
		(at 227.511864 -79.008732)
		(size 0.7112)
		(drill 0.4064)
		(layers "F.Cu" "B.Cu")
		(net "GND")
	)
	(via
		(at 195.59651 -26.92019)
		(size 0.7112)
		(drill 0.4064)
		(layers "F.Cu" "B.Cu")
		(net "GND")
	)
	(via
		(at 232.837482 -103.473758)
		(size 0.7112)
		(drill 0.4064)
		(layers "F.Cu" "B.Cu")
		(net "GND")
	)
	(via
		(at 170.42765 -157.837378)
		(size 0.7112)
		(drill 0.4064)
		(layers "F.Cu" "B.Cu")
		(net "GND")
	)
	(via
		(at 24.083772 -166.489634)
		(size 0.6096)
		(drill 0.3048)
		(layers "F.Cu" "B.Cu")
		(net "GND")
	)
	(via
		(at 42.900092 -144.999964)
		(size 0.4572)
		(drill 0.2032)
		(layers "F.Cu" "B.Cu")
		(net "GND")
	)
	(via
		(at 17.234408 -148.961602)
		(size 0.508)
		(drill 0.254)
		(layers "F.Cu" "B.Cu")
		(net "GND")
	)
	(via
		(at 22.0345 -145.761456)
		(size 0.508)
		(drill 0.254)
		(layers "F.Cu" "B.Cu")
		(net "GND")
	)
	(via
		(at 159.168338 -17.146778)
		(size 0.7112)
		(drill 0.4064)
		(layers "F.Cu" "B.Cu")
		(net "GND")
	)
	(via
		(at 232.837482 -50.133758)
		(size 0.7112)
		(drill 0.4064)
		(layers "F.Cu" "B.Cu")
		(net "GND")
	)
	(via
		(at 2.162556 -77.620622)
		(size 0.7112)
		(drill 0.4064)
		(layers "F.Cu" "B.Cu")
		(net "GND")
	)
	(via
		(at 182.89651 -39.62019)
		(size 0.7112)
		(drill 0.4064)
		(layers "F.Cu" "B.Cu")
		(net "GND")
	)
	(via
		(at 131.79806 -15.17142)
		(size 0.508)
		(drill 0.254)
		(layers "F.Cu" "B.Cu")
		(net "GND")
	)
	(via
		(at 48.56734 -156.9466)
		(size 0.508)
		(drill 0.254)
		(layers "F.Cu" "B.Cu")
		(net "GND")
	)
	(via
		(at 232.837482 -150.463758)
		(size 0.7112)
		(drill 0.4064)
		(layers "F.Cu" "B.Cu")
		(net "GND")
	)
	(via
		(at 27.03449 -2.162556)
		(size 0.7112)
		(drill 0.4064)
		(layers "F.Cu" "B.Cu")
		(net "GND")
	)
	(via
		(at 26.6319 -162.3441)
		(size 0.508)
		(drill 0.254)
		(layers "F.Cu" "B.Cu")
		(net "GND")
	)
	(via
		(at 2.162556 -54.760622)
		(size 0.7112)
		(drill 0.4064)
		(layers "F.Cu" "B.Cu")
		(net "GND")
	)
	(via
		(at 193.05651 -29.46019)
		(size 0.7112)
		(drill 0.4064)
		(layers "F.Cu" "B.Cu")
		(net "GND")
	)
	(via
		(at 208.29651 -29.46019)
		(size 0.7112)
		(drill 0.4064)
		(layers "F.Cu" "B.Cu")
		(net "GND")
	)
	(via
		(at 195.59651 -98.04019)
		(size 0.7112)
		(drill 0.4064)
		(layers "F.Cu" "B.Cu")
		(net "GND")
	)
	(via
		(at 180.35651 -39.62019)
		(size 0.7112)
		(drill 0.4064)
		(layers "F.Cu" "B.Cu")
		(net "GND")
	)
	(via
		(at 218.661488 -49.85131)
		(size 0.5588)
		(drill 0.3048)
		(layers "F.Cu" "B.Cu")
		(net "GND")
	)
	(via
		(at 159.168338 -19.686778)
		(size 0.7112)
		(drill 0.4064)
		(layers "F.Cu" "B.Cu")
		(net "GND")
	)
	(via
		(at 232.837482 -116.173758)
		(size 0.7112)
		(drill 0.4064)
		(layers "F.Cu" "B.Cu")
		(net "GND")
	)
	(via
		(at 98.0567 -178.1048)
		(size 0.508)
		(drill 0.254)
		(layers "F.Cu" "B.Cu")
		(net "GND")
	)
	(via
		(at 56.37784 -128.07442)
		(size 0.508)
		(drill 0.254)
		(layers "F.Cu" "B.Cu")
		(net "GND")
	)
	(via
		(at 2.162556 -162.710622)
		(size 0.7112)
		(drill 0.4064)
		(layers "F.Cu" "B.Cu")
		(net "GND")
	)
	(via
		(at 187.97651 -110.74019)
		(size 0.7112)
		(drill 0.4064)
		(layers "F.Cu" "B.Cu")
		(net "GND")
	)
	(via
		(at 200.67651 -92.96019)
		(size 0.7112)
		(drill 0.4064)
		(layers "F.Cu" "B.Cu")
		(net "GND")
	)
	(via
		(at 222.25508 -97.325688)
		(size 0.5588)
		(drill 0.3048)
		(layers "F.Cu" "B.Cu")
		(net "GND")
	)
	(via
		(at 228.630988 -16.183356)
		(size 0.7112)
		(drill 0.4064)
		(layers "F.Cu" "B.Cu")
		(net "GND")
	)
	(via
		(at 217.162634 -178.387502)
		(size 0.7112)
		(drill 0.4064)
		(layers "F.Cu" "B.Cu")
		(net "GND")
	)
	(via
		(at 35.538664 -179.278788)
		(size 0.5588)
		(drill 0.3048)
		(layers "F.Cu" "B.Cu")
		(net "GND")
	)
	(via
		(at 177.81651 -39.62019)
		(size 0.7112)
		(drill 0.4064)
		(layers "F.Cu" "B.Cu")
		(net "GND")
	)
	(via
		(at 198.13651 -92.96019)
		(size 0.7112)
		(drill 0.4064)
		(layers "F.Cu" "B.Cu")
		(net "GND")
	)
	(via
		(at 2.162556 -142.390622)
		(size 0.7112)
		(drill 0.4064)
		(layers "F.Cu" "B.Cu")
		(net "GND")
	)
	(via
		(at 68.326762 -178.901598)
		(size 0.508)
		(drill 0.254)
		(layers "F.Cu" "B.Cu")
		(net "GND")
	)
	(via
		(at 28.367482 -71.949564)
		(size 0.7112)
		(drill 0.4064)
		(layers "F.Cu" "B.Cu")
		(net "GND")
	)
	(via
		(at 229.311962 -54.021736)
		(size 0.7112)
		(drill 0.4064)
		(layers "F.Cu" "B.Cu")
		(net "GND")
	)
	(via
		(at 52.5018 -179.06619)
		(size 0.7112)
		(drill 0.4064)
		(layers "F.Cu" "B.Cu")
		(net "GND")
	)
	(via
		(at 193.05651 -39.62019)
		(size 0.7112)
		(drill 0.4064)
		(layers "F.Cu" "B.Cu")
		(net "GND")
	)
	(via
		(at 75.467972 -169.896028)
		(size 0.508)
		(drill 0.254)
		(layers "F.Cu" "B.Cu")
		(net "GND")
	)
	(via
		(at 9.525 -147.1676)
		(size 0.6096)
		(drill 0.3048)
		(layers "F.Cu" "B.Cu")
		(net "GND")
	)
	(via
		(at 66.5226 -177.6222)
		(size 0.508)
		(drill 0.254)
		(layers "F.Cu" "B.Cu")
		(net "GND")
	)
	(via
		(at 75.192636 -3.556508)
		(size 0.7112)
		(drill 0.4064)
		(layers "F.Cu" "B.Cu")
		(net "GND")
	)
	(via
		(at 182.528718 -70.036944)
		(size 0.7112)
		(drill 0.4064)
		(layers "F.Cu" "B.Cu")
		(net "GND")
	)
	(via
		(at 91.1606 -157.1752)
		(size 0.5588)
		(drill 0.3048)
		(layers "F.Cu" "B.Cu")
		(net "GND")
	)
	(via
		(at 198.13651 -37.08019)
		(size 0.7112)
		(drill 0.4064)
		(layers "F.Cu" "B.Cu")
		(net "GND")
	)
	(via
		(at 83.958684 -2.162556)
		(size 0.7112)
		(drill 0.4064)
		(layers "F.Cu" "B.Cu")
		(net "GND")
	)
	(via
		(at 227.58273 -73.840848)
		(size 0.7112)
		(drill 0.4064)
		(layers "F.Cu" "B.Cu")
		(net "GND")
	)
	(via
		(at 4.17449 -2.162556)
		(size 0.7112)
		(drill 0.4064)
		(layers "F.Cu" "B.Cu")
		(net "GND")
	)
	(via
		(at 2.162556 -24.280622)
		(size 0.7112)
		(drill 0.4064)
		(layers "F.Cu" "B.Cu")
		(net "GND")
	)
	(via
		(at 92.3036 -29.4513)
		(size 0.4572)
		(drill 0.2032)
		(layers "F.Cu" "B.Cu")
		(net "GND")
	)
	(via
		(at 34.791396 -135.757666)
		(size 0.508)
		(drill 0.254)
		(layers "F.Cu" "B.Cu")
		(net "GND")
	)
	(via
		(at 190.51651 -80.26019)
		(size 0.7112)
		(drill 0.4064)
		(layers "F.Cu" "B.Cu")
		(net "GND")
	)
	(via
		(at 75.192636 -30.226508)
		(size 0.7112)
		(drill 0.4064)
		(layers "F.Cu" "B.Cu")
		(net "GND")
	)
	(via
		(at 16.326358 -127.552958)
		(size 0.508)
		(drill 0.254)
		(layers "F.Cu" "B.Cu")
		(net "GND")
	)
	(via
		(at 81.63433 -191.837564)
		(size 0.7112)
		(drill 0.4064)
		(layers "F.Cu" "B.Cu")
		(net "GND")
	)
	(via
		(at 190.51651 -118.36019)
		(size 0.7112)
		(drill 0.4064)
		(layers "F.Cu" "B.Cu")
		(net "GND")
	)
	(via
		(at 228.86162 -75.26782)
		(size 0.7112)
		(drill 0.4064)
		(layers "F.Cu" "B.Cu")
		(net "GND")
	)
	(via
		(at 232.837482 -109.823758)
		(size 0.7112)
		(drill 0.4064)
		(layers "F.Cu" "B.Cu")
		(net "GND")
	)
	(via
		(at 2.162556 -146.200622)
		(size 0.7112)
		(drill 0.4064)
		(layers "F.Cu" "B.Cu")
		(net "GND")
	)
	(via
		(at 220.1672 -103.1494)
		(size 0.6096)
		(drill 0.3048)
		(layers "F.Cu" "B.Cu")
		(net "GND")
	)
	(via
		(at 26.5557 -164.3507)
		(size 0.508)
		(drill 0.254)
		(layers "F.Cu" "B.Cu")
		(net "GND")
	)
	(via
		(at 46.91253 -144.187164)
		(size 0.4572)
		(drill 0.2032)
		(layers "F.Cu" "B.Cu")
		(net "GND")
	)
	(via
		(at 232.837482 -19.653758)
		(size 0.7112)
		(drill 0.4064)
		(layers "F.Cu" "B.Cu")
		(net "GND")
	)
	(via
		(at 232.837482 -132.683758)
		(size 0.7112)
		(drill 0.4064)
		(layers "F.Cu" "B.Cu")
		(net "GND")
	)
	(via
		(at 177.81651 -29.46019)
		(size 0.7112)
		(drill 0.4064)
		(layers "F.Cu" "B.Cu")
		(net "GND")
	)
	(via
		(at 58.48858 -164.066982)
		(size 0.508)
		(drill 0.254)
		(layers "F.Cu" "B.Cu")
		(net "GND")
	)
	(via
		(at 232.837482 -78.073758)
		(size 0.7112)
		(drill 0.4064)
		(layers "F.Cu" "B.Cu")
		(net "GND")
	)
	(via
		(at 195.59651 -108.20019)
		(size 0.7112)
		(drill 0.4064)
		(layers "F.Cu" "B.Cu")
		(net "GND")
	)
	(via
		(at 228.1682 -72.1868)
		(size 0.6096)
		(drill 0.3048)
		(layers "F.Cu" "B.Cu")
		(net "GND")
	)
	(via
		(at 28.367482 -106.239564)
		(size 0.7112)
		(drill 0.4064)
		(layers "F.Cu" "B.Cu")
		(net "GND")
	)
	(via
		(at 2.162556 -160.170622)
		(size 0.7112)
		(drill 0.4064)
		(layers "F.Cu" "B.Cu")
		(net "GND")
	)
	(via
		(at 228.7524 -51.114706)
		(size 0.7112)
		(drill 0.4064)
		(layers "F.Cu" "B.Cu")
		(net "GND")
	)
	(via
		(at 25.231598 -171.134024)
		(size 0.7112)
		(drill 0.4064)
		(layers "F.Cu" "B.Cu")
		(net "GND")
	)
	(via
		(at 185.43651 -29.46019)
		(size 0.7112)
		(drill 0.4064)
		(layers "F.Cu" "B.Cu")
		(net "GND")
	)
	(via
		(at 187.97651 -54.86019)
		(size 0.7112)
		(drill 0.4064)
		(layers "F.Cu" "B.Cu")
		(net "GND")
	)
	(via
		(at 205.75651 -72.64019)
		(size 0.7112)
		(drill 0.4064)
		(layers "F.Cu" "B.Cu")
		(net "GND")
	)
	(via
		(at 8.669528 -132.39623)
		(size 0.508)
		(drill 0.254)
		(layers "F.Cu" "B.Cu")
		(net "GND")
	)
	(via
		(at 200.798684 -2.162556)
		(size 0.7112)
		(drill 0.4064)
		(layers "F.Cu" "B.Cu")
		(net "GND")
	)
	(via
		(at 28.367482 -78.299564)
		(size 0.7112)
		(drill 0.4064)
		(layers "F.Cu" "B.Cu")
		(net "GND")
	)
	(via
		(at 2.162556 -30.630622)
		(size 0.7112)
		(drill 0.4064)
		(layers "F.Cu" "B.Cu")
		(net "GND")
	)
	(via
		(at 200.67651 -82.80019)
		(size 0.7112)
		(drill 0.4064)
		(layers "F.Cu" "B.Cu")
		(net "GND")
	)
	(via
		(at 203.21651 -59.94019)
		(size 0.7112)
		(drill 0.4064)
		(layers "F.Cu" "B.Cu")
		(net "GND")
	)
	(via
		(at 184.288684 -2.162556)
		(size 0.7112)
		(drill 0.4064)
		(layers "F.Cu" "B.Cu")
		(net "GND")
	)
	(via
		(at 52.499768 -141.00048)
		(size 0.4572)
		(drill 0.2032)
		(layers "F.Cu" "B.Cu")
		(net "GND")
	)
	(via
		(at 9.642094 -167.616886)
		(size 0.508)
		(drill 0.254)
		(layers "F.Cu" "B.Cu")
		(net "GND")
	)
	(via
		(at 34.294826 -180.49113)
		(size 0.5588)
		(drill 0.3048)
		(layers "F.Cu" "B.Cu")
		(net "GND")
	)
	(via
		(at 51.699668 -138.600434)
		(size 0.4572)
		(drill 0.2032)
		(layers "F.Cu" "B.Cu")
		(net "GND")
	)
	(via
		(at 42.26433 -191.837564)
		(size 0.7112)
		(drill 0.4064)
		(layers "F.Cu" "B.Cu")
		(net "GND")
	)
	(via
		(at 2.162556 -128.420622)
		(size 0.7112)
		(drill 0.4064)
		(layers "F.Cu" "B.Cu")
		(net "GND")
	)
	(via
		(at 87.61476 -156.90088)
		(size 0.508)
		(drill 0.254)
		(layers "F.Cu" "B.Cu")
		(net "GND")
	)
	(via
		(at 149.264116 -155.092654)
		(size 0.7112)
		(drill 0.4064)
		(layers "F.Cu" "B.Cu")
		(net "GND")
	)
	(via
		(at 146.462496 -89.71407)
		(size 0.7112)
		(drill 0.4064)
		(layers "F.Cu" "B.Cu")
		(net "GND")
	)
	(via
		(at 208.8642 -106.4006)
		(size 0.508)
		(drill 0.254)
		(layers "F.Cu" "B.Cu")
		(net "GND")
	)
	(via
		(at 89.8398 -170.4086)
		(size 0.508)
		(drill 0.254)
		(layers "F.Cu" "B.Cu")
		(net "GND")
	)
	(via
		(at 146.462496 -52.88407)
		(size 0.7112)
		(drill 0.4064)
		(layers "F.Cu" "B.Cu")
		(net "GND")
	)
	(via
		(at 208.29651 -59.94019)
		(size 0.7112)
		(drill 0.4064)
		(layers "F.Cu" "B.Cu")
		(net "GND")
	)
	(via
		(at 61.2902 -161.5186)
		(size 0.508)
		(drill 0.254)
		(layers "F.Cu" "B.Cu")
		(net "GND")
	)
	(via
		(at 180.35651 -59.94019)
		(size 0.7112)
		(drill 0.4064)
		(layers "F.Cu" "B.Cu")
		(net "GND")
	)
	(via
		(at 75.192636 -2.286508)
		(size 0.7112)
		(drill 0.4064)
		(layers "F.Cu" "B.Cu")
		(net "GND")
	)
	(via
		(at 232.837482 -81.883758)
		(size 0.7112)
		(drill 0.4064)
		(layers "F.Cu" "B.Cu")
		(net "GND")
	)
	(via
		(at 62.6872 -149.7584)
		(size 0.508)
		(drill 0.254)
		(layers "F.Cu" "B.Cu")
		(net "GND")
	)
	(via
		(at 232.837482 -170.783758)
		(size 0.7112)
		(drill 0.4064)
		(layers "F.Cu" "B.Cu")
		(net "GND")
	)
	(via
		(at 2.162556 -56.030622)
		(size 0.7112)
		(drill 0.4064)
		(layers "F.Cu" "B.Cu")
		(net "GND")
	)
	(via
		(at 154.468322 -10.898124)
		(size 0.5588)
		(drill 0.3048)
		(layers "F.Cu" "B.Cu")
		(net "GND")
	)
	(via
		(at 76.552044 -160.9471)
		(size 0.5588)
		(drill 0.3048)
		(layers "F.Cu" "B.Cu")
		(net "GND")
	)
	(via
		(at 21.023072 -17.71777)
		(size 0.508)
		(drill 0.254)
		(layers "F.Cu" "B.Cu")
		(net "GND")
	)
	(via
		(at 195.59651 -44.70019)
		(size 0.7112)
		(drill 0.4064)
		(layers "F.Cu" "B.Cu")
		(net "GND")
	)
	(via
		(at 146.462496 -131.62407)
		(size 0.7112)
		(drill 0.4064)
		(layers "F.Cu" "B.Cu")
		(net "GND")
	)
	(via
		(at 58.3692 -150.6728)
		(size 0.508)
		(drill 0.254)
		(layers "F.Cu" "B.Cu")
		(net "GND")
	)
	(via
		(at 216.08542 -89.022682)
		(size 0.508)
		(drill 0.254)
		(layers "F.Cu" "B.Cu")
		(net "GND")
	)
	(via
		(at 9.56564 -143.8656)
		(size 0.508)
		(drill 0.254)
		(layers "F.Cu" "B.Cu")
		(net "GND")
	)
	(via
		(at 30.207712 -189.17285)
		(size 0.7112)
		(drill 0.4064)
		(layers "F.Cu" "B.Cu")
		(net "GND")
	)
	(via
		(at 199.289416 -131.846828)
		(size 0.7112)
		(drill 0.4064)
		(layers "F.Cu" "B.Cu")
		(net "GND")
	)
	(via
		(at 146.462496 -94.79407)
		(size 0.7112)
		(drill 0.4064)
		(layers "F.Cu" "B.Cu")
		(net "GND")
	)
	(via
		(at 205.75651 -32.00019)
		(size 0.7112)
		(drill 0.4064)
		(layers "F.Cu" "B.Cu")
		(net "GND")
	)
	(via
		(at 2.162556 -123.340622)
		(size 0.7112)
		(drill 0.4064)
		(layers "F.Cu" "B.Cu")
		(net "GND")
	)
	(via
		(at 34.294826 -183.79313)
		(size 0.5588)
		(drill 0.3048)
		(layers "F.Cu" "B.Cu")
		(net "GND")
	)
	(via
		(at 87.647526 -27.567382)
		(size 0.508)
		(drill 0.254)
		(layers "F.Cu" "B.Cu")
		(net "GND")
	)
	(via
		(at 146.462496 -98.60407)
		(size 0.7112)
		(drill 0.4064)
		(layers "F.Cu" "B.Cu")
		(net "GND")
	)
	(via
		(at 2.162556 -39.520622)
		(size 0.7112)
		(drill 0.4064)
		(layers "F.Cu" "B.Cu")
		(net "GND")
	)
	(via
		(at 181.85765 -157.837378)
		(size 0.7112)
		(drill 0.4064)
		(layers "F.Cu" "B.Cu")
		(net "GND")
	)
	(via
		(at 3.661156 -186.4868)
		(size 0.7112)
		(drill 0.4064)
		(layers "F.Cu" "B.Cu")
		(net "GND")
	)
	(via
		(at 15.5194 -138.8618)
		(size 0.508)
		(drill 0.254)
		(layers "F.Cu" "B.Cu")
		(net "GND")
	)
	(via
		(at 185.43651 -87.88019)
		(size 0.7112)
		(drill 0.4064)
		(layers "F.Cu" "B.Cu")
		(net "GND")
	)
	(via
		(at 77.58938 -158.428436)
		(size 0.508)
		(drill 0.254)
		(layers "F.Cu" "B.Cu")
		(net "GND")
	)
	(via
		(at 81.584038 -64.625982)
		(size 0.508)
		(drill 0.254)
		(layers "F.Cu" "B.Cu")
		(net "GND")
	)
	(via
		(at 28.367482 -60.519564)
		(size 0.7112)
		(drill 0.4064)
		(layers "F.Cu" "B.Cu")
		(net "GND")
	)
	(via
		(at 232.837482 -153.003758)
		(size 0.7112)
		(drill 0.4064)
		(layers "F.Cu" "B.Cu")
		(net "GND")
	)
	(via
		(at 27.667712 -189.17285)
		(size 0.7112)
		(drill 0.4064)
		(layers "F.Cu" "B.Cu")
		(net "GND")
	)
	(via
		(at 5.44449 -2.162556)
		(size 0.7112)
		(drill 0.4064)
		(layers "F.Cu" "B.Cu")
		(net "GND")
	)
	(via
		(at 232.837482 -5.683758)
		(size 0.7112)
		(drill 0.4064)
		(layers "F.Cu" "B.Cu")
		(net "GND")
	)
	(via
		(at 2.162556 -105.560622)
		(size 0.7112)
		(drill 0.4064)
		(layers "F.Cu" "B.Cu")
		(net "GND")
	)
	(via
		(at 100.1522 -146.4564)
		(size 0.508)
		(drill 0.254)
		(layers "F.Cu" "B.Cu")
		(net "GND")
	)
	(via
		(at 66.5226 -149.5806)
		(size 0.508)
		(drill 0.254)
		(layers "F.Cu" "B.Cu")
		(net "GND")
	)
	(via
		(at 23.857712 -189.17285)
		(size 0.7112)
		(drill 0.4064)
		(layers "F.Cu" "B.Cu")
		(net "GND")
	)
	(via
		(at 77.796644 -160.9471)
		(size 0.5588)
		(drill 0.3048)
		(layers "F.Cu" "B.Cu")
		(net "GND")
	)
	(via
		(at 28.367482 -88.459564)
		(size 0.7112)
		(drill 0.4064)
		(layers "F.Cu" "B.Cu")
		(net "GND")
	)
	(via
		(at 75.192636 -7.366508)
		(size 0.7112)
		(drill 0.4064)
		(layers "F.Cu" "B.Cu")
		(net "GND")
	)
	(via
		(at 2.162556 -166.520622)
		(size 0.7112)
		(drill 0.4064)
		(layers "F.Cu" "B.Cu")
		(net "GND")
	)
	(via
		(at 2.162556 -144.930622)
		(size 0.7112)
		(drill 0.4064)
		(layers "F.Cu" "B.Cu")
		(net "GND")
	)
	(via
		(at 229.311962 -52.751736)
		(size 0.7112)
		(drill 0.4064)
		(layers "F.Cu" "B.Cu")
		(net "GND")
	)
	(via
		(at 2.162556 -28.090622)
		(size 0.7112)
		(drill 0.4064)
		(layers "F.Cu" "B.Cu")
		(net "GND")
	)
	(via
		(at 232.837482 -175.863758)
		(size 0.7112)
		(drill 0.4064)
		(layers "F.Cu" "B.Cu")
		(net "GND")
	)
	(via
		(at 216.772744 -27.664918)
		(size 0.7112)
		(drill 0.4064)
		(layers "F.Cu" "B.Cu")
		(net "GND")
	)
	(via
		(at 25.75433 -191.837564)
		(size 0.7112)
		(drill 0.4064)
		(layers "F.Cu" "B.Cu")
		(net "GND")
	)
	(via
		(at 73.81748 -180.37048)
		(size 0.5588)
		(drill 0.3048)
		(layers "F.Cu" "B.Cu")
		(net "GND")
	)
	(via
		(at 2.162556 -47.140622)
		(size 0.7112)
		(drill 0.4064)
		(layers "F.Cu" "B.Cu")
		(net "GND")
	)
	(via
		(at 195.59651 -54.86019)
		(size 0.7112)
		(drill 0.4064)
		(layers "F.Cu" "B.Cu")
		(net "GND")
	)
	(via
		(at 193.05651 -72.64019)
		(size 0.7112)
		(drill 0.4064)
		(layers "F.Cu" "B.Cu")
		(net "GND")
	)
	(via
		(at 76.55433 -191.837564)
		(size 0.7112)
		(drill 0.4064)
		(layers "F.Cu" "B.Cu")
		(net "GND")
	)
	(via
		(at 28.367482 -16.069564)
		(size 0.7112)
		(drill 0.4064)
		(layers "F.Cu" "B.Cu")
		(net "GND")
	)
	(via
		(at 28.367482 -51.629564)
		(size 0.7112)
		(drill 0.4064)
		(layers "F.Cu" "B.Cu")
		(net "GND")
	)
	(via
		(at 179.649882 -133.225794)
		(size 0.508)
		(drill 0.254)
		(layers "F.Cu" "B.Cu")
		(net "GND")
	)
	(via
		(at 146.462496 -69.39407)
		(size 0.7112)
		(drill 0.4064)
		(layers "F.Cu" "B.Cu")
		(net "GND")
	)
	(via
		(at 122.612658 -10.63498)
		(size 0.508)
		(drill 0.254)
		(layers "F.Cu" "B.Cu")
		(net "GND")
	)
	(via
		(at 93.573346 -144.112488)
		(size 0.508)
		(drill 0.254)
		(layers "F.Cu" "B.Cu")
		(net "GND")
	)
	(via
		(at 193.05651 -42.16019)
		(size 0.7112)
		(drill 0.4064)
		(layers "F.Cu" "B.Cu")
		(net "GND")
	)
	(via
		(at 2.162556 -143.660622)
		(size 0.7112)
		(drill 0.4064)
		(layers "F.Cu" "B.Cu")
		(net "GND")
	)
	(via
		(at 56.515 -160.0708)
		(size 0.508)
		(drill 0.254)
		(layers "F.Cu" "B.Cu")
		(net "GND")
	)
	(via
		(at 232.837482 -106.013758)
		(size 0.7112)
		(drill 0.4064)
		(layers "F.Cu" "B.Cu")
		(net "GND")
	)
	(via
		(at 89.987628 -47.680372)
		(size 0.508)
		(drill 0.254)
		(layers "F.Cu" "B.Cu")
		(net "GND")
	)
	(via
		(at 203.21651 -115.82019)
		(size 0.7112)
		(drill 0.4064)
		(layers "F.Cu" "B.Cu")
		(net "GND")
	)
	(via
		(at 220.42628 -98.240088)
		(size 0.5588)
		(drill 0.3048)
		(layers "F.Cu" "B.Cu")
		(net "GND")
	)
	(via
		(at 93.345 -133.8072)
		(size 0.508)
		(drill 0.254)
		(layers "F.Cu" "B.Cu")
		(net "GND")
	)
	(via
		(at 35.538664 -181.107588)
		(size 0.5588)
		(drill 0.3048)
		(layers "F.Cu" "B.Cu")
		(net "GND")
	)
	(via
		(at 42.900092 -142.599918)
		(size 0.4572)
		(drill 0.2032)
		(layers "F.Cu" "B.Cu")
		(net "GND")
	)
	(via
		(at 54.082442 -156.21)
		(size 0.508)
		(drill 0.254)
		(layers "F.Cu" "B.Cu")
		(net "GND")
	)
	(via
		(at 85.09 -156.3116)
		(size 0.7112)
		(drill 0.4064)
		(layers "F.Cu" "B.Cu")
		(net "GND")
	)
	(via
		(at 2.162556 -53.490622)
		(size 0.7112)
		(drill 0.4064)
		(layers "F.Cu" "B.Cu")
		(net "GND")
	)
	(via
		(at 100.09378 -20.53336)
		(size 0.508)
		(drill 0.254)
		(layers "F.Cu" "B.Cu")
		(net "GND")
	)
	(via
		(at 76.35748 -181.66588)
		(size 0.5588)
		(drill 0.3048)
		(layers "F.Cu" "B.Cu")
		(net "GND")
	)
	(via
		(at 2.162556 -86.510622)
		(size 0.7112)
		(drill 0.4064)
		(layers "F.Cu" "B.Cu")
		(net "GND")
	)
	(via
		(at 179.39385 -113.280444)
		(size 0.5588)
		(drill 0.3048)
		(layers "F.Cu" "B.Cu")
		(net "GND")
	)
	(via
		(at 232.837482 -18.383758)
		(size 0.7112)
		(drill 0.4064)
		(layers "F.Cu" "B.Cu")
		(net "GND")
	)
	(via
		(at 42.099992 -148.199856)
		(size 0.4572)
		(drill 0.2032)
		(layers "F.Cu" "B.Cu")
		(net "GND")
	)
	(via
		(at 75.192636 -9.906508)
		(size 0.7112)
		(drill 0.4064)
		(layers "F.Cu" "B.Cu")
		(net "GND")
	)
	(via
		(at 180.35651 -65.02019)
		(size 0.7112)
		(drill 0.4064)
		(layers "F.Cu" "B.Cu")
		(net "GND")
	)
	(via
		(at 222.319088 -49.85131)
		(size 0.5588)
		(drill 0.3048)
		(layers "F.Cu" "B.Cu")
		(net "GND")
	)
	(via
		(at 177.522886 -70.638416)
		(size 0.7112)
		(drill 0.4064)
		(layers "F.Cu" "B.Cu")
		(net "GND")
	)
	(via
		(at 193.05651 -62.48019)
		(size 0.7112)
		(drill 0.4064)
		(layers "F.Cu" "B.Cu")
		(net "GND")
	)
	(via
		(at 219.804488 -48.58131)
		(size 0.5588)
		(drill 0.3048)
		(layers "F.Cu" "B.Cu")
		(net "GND")
	)
	(via
		(at 200.67651 -72.64019)
		(size 0.7112)
		(drill 0.4064)
		(layers "F.Cu" "B.Cu")
		(net "GND")
	)
	(via
		(at 181.150006 -133.225794)
		(size 0.508)
		(drill 0.254)
		(layers "F.Cu" "B.Cu")
		(net "GND")
	)
	(via
		(at 195.59651 -24.38019)
		(size 0.7112)
		(drill 0.4064)
		(layers "F.Cu" "B.Cu")
		(net "GND")
	)
	(via
		(at 28.367482 -83.379564)
		(size 0.7112)
		(drill 0.4064)
		(layers "F.Cu" "B.Cu")
		(net "GND")
	)
	(via
		(at 70.9676 -174.3456)
		(size 0.508)
		(drill 0.254)
		(layers "F.Cu" "B.Cu")
		(net "GND")
	)
	(via
		(at 232.837482 -102.203758)
		(size 0.7112)
		(drill 0.4064)
		(layers "F.Cu" "B.Cu")
		(net "GND")
	)
	(via
		(at 232.837482 -126.333758)
		(size 0.7112)
		(drill 0.4064)
		(layers "F.Cu" "B.Cu")
		(net "GND")
	)
	(via
		(at 232.837482 -172.053758)
		(size 0.7112)
		(drill 0.4064)
		(layers "F.Cu" "B.Cu")
		(net "GND")
	)
	(via
		(at 84.17433 -191.837564)
		(size 0.7112)
		(drill 0.4064)
		(layers "F.Cu" "B.Cu")
		(net "GND")
	)
	(via
		(at 82.7024 -162.5854)
		(size 0.7112)
		(drill 0.4064)
		(layers "F.Cu" "B.Cu")
		(net "GND")
	)
	(via
		(at 2.162556 -174.140622)
		(size 0.7112)
		(drill 0.4064)
		(layers "F.Cu" "B.Cu")
		(net "GND")
	)
	(via
		(at 214.768684 -2.162556)
		(size 0.7112)
		(drill 0.4064)
		(layers "F.Cu" "B.Cu")
		(net "GND")
	)
	(via
		(at 99.416616 -187.7314)
		(size 0.7112)
		(drill 0.4064)
		(layers "F.Cu" "B.Cu")
		(net "GND")
	)
	(via
		(at 16.434054 -143.361664)
		(size 0.508)
		(drill 0.254)
		(layers "F.Cu" "B.Cu")
		(net "GND")
	)
	(via
		(at 84.5312 -175.76038)
		(size 0.508)
		(drill 0.254)
		(layers "F.Cu" "B.Cu")
		(net "GND")
	)
	(via
		(at 224.95891 -104.353614)
		(size 0.7112)
		(drill 0.4064)
		(layers "F.Cu" "B.Cu")
		(net "GND")
	)
	(via
		(at 95.504 -19.9136)
		(size 0.508)
		(drill 0.254)
		(layers "F.Cu" "B.Cu")
		(net "GND")
	)
	(via
		(at 2.162556 -100.480622)
		(size 0.7112)
		(drill 0.4064)
		(layers "F.Cu" "B.Cu")
		(net "GND")
	)
	(via
		(at 25.127712 -189.17285)
		(size 0.7112)
		(drill 0.4064)
		(layers "F.Cu" "B.Cu")
		(net "GND")
	)
	(via
		(at 172.150024 -133.225794)
		(size 0.508)
		(drill 0.254)
		(layers "F.Cu" "B.Cu")
		(net "GND")
	)
	(via
		(at 9.25449 -2.162556)
		(size 0.7112)
		(drill 0.4064)
		(layers "F.Cu" "B.Cu")
		(net "GND")
	)
	(via
		(at 2.162556 -17.930622)
		(size 0.7112)
		(drill 0.4064)
		(layers "F.Cu" "B.Cu")
		(net "GND")
	)
	(via
		(at 97.9678 -162.8902)
		(size 0.508)
		(drill 0.254)
		(layers "F.Cu" "B.Cu")
		(net "GND")
	)
	(via
		(at 146.462496 -70.66407)
		(size 0.7112)
		(drill 0.4064)
		(layers "F.Cu" "B.Cu")
		(net "GND")
	)
	(via
		(at 180.4797 -4.7117)
		(size 0.508)
		(drill 0.254)
		(layers "F.Cu" "B.Cu")
		(net "GND")
	)
	(via
		(at 146.462496 -108.76407)
		(size 0.7112)
		(drill 0.4064)
		(layers "F.Cu" "B.Cu")
		(net "GND")
	)
	(via
		(at 28.367482 -68.139564)
		(size 0.7112)
		(drill 0.4064)
		(layers "F.Cu" "B.Cu")
		(net "GND")
	)
	(via
		(at 2.162556 -19.200622)
		(size 0.7112)
		(drill 0.4064)
		(layers "F.Cu" "B.Cu")
		(net "GND")
	)
	(via
		(at 198.36765 -157.837378)
		(size 0.7112)
		(drill 0.4064)
		(layers "F.Cu" "B.Cu")
		(net "GND")
	)
	(via
		(at 185.43651 -92.96019)
		(size 0.7112)
		(drill 0.4064)
		(layers "F.Cu" "B.Cu")
		(net "GND")
	)
	(via
		(at 30.022038 -124.5362)
		(size 0.508)
		(drill 0.254)
		(layers "F.Cu" "B.Cu")
		(net "GND")
	)
	(via
		(at 232.837482 -36.163758)
		(size 0.7112)
		(drill 0.4064)
		(layers "F.Cu" "B.Cu")
		(net "GND")
	)
	(via
		(at 54.6862 -130.0988)
		(size 0.6096)
		(drill 0.3048)
		(layers "F.Cu" "B.Cu")
		(net "GND")
	)
	(via
		(at 35.2806 -133.603746)
		(size 0.508)
		(drill 0.254)
		(layers "F.Cu" "B.Cu")
		(net "GND")
	)
	(via
		(at 146.468846 -10.05459)
		(size 0.508)
		(drill 0.254)
		(layers "F.Cu" "B.Cu")
		(net "GND")
	)
	(via
		(at 73.79208 -181.64048)
		(size 0.5588)
		(drill 0.3048)
		(layers "F.Cu" "B.Cu")
		(net "GND")
	)
	(via
		(at 79.321406 -135.935974)
		(size 0.5588)
		(drill 0.3048)
		(layers "F.Cu" "B.Cu")
		(net "GND")
	)
	(via
		(at 203.21651 -92.96019)
		(size 0.7112)
		(drill 0.4064)
		(layers "F.Cu" "B.Cu")
		(net "GND")
	)
	(via
		(at 203.21651 -67.56019)
		(size 0.7112)
		(drill 0.4064)
		(layers "F.Cu" "B.Cu")
		(net "GND")
	)
	(via
		(at 232.837482 -94.583758)
		(size 0.7112)
		(drill 0.4064)
		(layers "F.Cu" "B.Cu")
		(net "GND")
	)
	(via
		(at 232.837482 -38.703758)
		(size 0.7112)
		(drill 0.4064)
		(layers "F.Cu" "B.Cu")
		(net "GND")
	)
	(via
		(at 86.36 -168.1988)
		(size 0.508)
		(drill 0.254)
		(layers "F.Cu" "B.Cu")
		(net "GND")
	)
	(via
		(at 176.824386 -57.360566)
		(size 0.7112)
		(drill 0.4064)
		(layers "F.Cu" "B.Cu")
		(net "GND")
	)
	(via
		(at 200.67651 -77.72019)
		(size 0.7112)
		(drill 0.4064)
		(layers "F.Cu" "B.Cu")
		(net "GND")
	)
	(via
		(at 198.13651 -113.28019)
		(size 0.7112)
		(drill 0.4064)
		(layers "F.Cu" "B.Cu")
		(net "GND")
	)
	(via
		(at 232.837482 -34.893758)
		(size 0.7112)
		(drill 0.4064)
		(layers "F.Cu" "B.Cu")
		(net "GND")
	)
	(via
		(at 65.6844 -155.7274)
		(size 0.508)
		(drill 0.254)
		(layers "F.Cu" "B.Cu")
		(net "GND")
	)
	(via
		(at 176.345088 -125.929644)
		(size 0.7112)
		(drill 0.4064)
		(layers "F.Cu" "B.Cu")
		(net "GND")
	)
	(via
		(at 205.75651 -62.48019)
		(size 0.7112)
		(drill 0.4064)
		(layers "F.Cu" "B.Cu")
		(net "GND")
	)
	(via
		(at 77.596492 -54.311296)
		(size 0.508)
		(drill 0.254)
		(layers "F.Cu" "B.Cu")
		(net "GND")
	)
	(via
		(at 185.43651 -115.82019)
		(size 0.7112)
		(drill 0.4064)
		(layers "F.Cu" "B.Cu")
		(net "GND")
	)
	(via
		(at 22.9616 -169.545)
		(size 0.7112)
		(drill 0.4064)
		(layers "F.Cu" "B.Cu")
		(net "GND")
	)
	(via
		(at 21.94433 -191.837564)
		(size 0.7112)
		(drill 0.4064)
		(layers "F.Cu" "B.Cu")
		(net "GND")
	)
	(via
		(at 195.59651 -100.58019)
		(size 0.7112)
		(drill 0.4064)
		(layers "F.Cu" "B.Cu")
		(net "GND")
	)
	(via
		(at 28.367482 -66.869564)
		(size 0.7112)
		(drill 0.4064)
		(layers "F.Cu" "B.Cu")
		(net "GND")
	)
	(via
		(at 232.837482 -156.813758)
		(size 0.7112)
		(drill 0.4064)
		(layers "F.Cu" "B.Cu")
		(net "GND")
	)
	(via
		(at 193.05651 -34.54019)
		(size 0.7112)
		(drill 0.4064)
		(layers "F.Cu" "B.Cu")
		(net "GND")
	)
	(via
		(at 190.51651 -49.78019)
		(size 0.7112)
		(drill 0.4064)
		(layers "F.Cu" "B.Cu")
		(net "GND")
	)
	(via
		(at 190.51651 -67.56019)
		(size 0.7112)
		(drill 0.4064)
		(layers "F.Cu" "B.Cu")
		(net "GND")
	)
	(via
		(at 232.837482 -51.403758)
		(size 0.7112)
		(drill 0.4064)
		(layers "F.Cu" "B.Cu")
		(net "GND")
	)
	(via
		(at 228.76891 -104.353614)
		(size 0.7112)
		(drill 0.4064)
		(layers "F.Cu" "B.Cu")
		(net "GND")
	)
	(via
		(at 2.162556 -7.770622)
		(size 0.7112)
		(drill 0.4064)
		(layers "F.Cu" "B.Cu")
		(net "GND")
	)
	(via
		(at 187.97651 -47.24019)
		(size 0.7112)
		(drill 0.4064)
		(layers "F.Cu" "B.Cu")
		(net "GND")
	)
	(via
		(at 149.516338 -7.113778)
		(size 0.508)
		(drill 0.254)
		(layers "F.Cu" "B.Cu")
		(net "GND")
	)
	(via
		(at 232.837482 -56.483758)
		(size 0.7112)
		(drill 0.4064)
		(layers "F.Cu" "B.Cu")
		(net "GND")
	)
	(via
		(at 232.837482 -107.283758)
		(size 0.7112)
		(drill 0.4064)
		(layers "F.Cu" "B.Cu")
		(net "GND")
	)
	(via
		(at 146.462496 -96.06407)
		(size 0.7112)
		(drill 0.4064)
		(layers "F.Cu" "B.Cu")
		(net "GND")
	)
	(via
		(at 193.05651 -77.72019)
		(size 0.7112)
		(drill 0.4064)
		(layers "F.Cu" "B.Cu")
		(net "GND")
	)
	(via
		(at 6.71449 -2.162556)
		(size 0.7112)
		(drill 0.4064)
		(layers "F.Cu" "B.Cu")
		(net "GND")
	)
	(via
		(at 78.878684 -2.162556)
		(size 0.7112)
		(drill 0.4064)
		(layers "F.Cu" "B.Cu")
		(net "GND")
	)
	(via
		(at 2.162556 -118.260622)
		(size 0.7112)
		(drill 0.4064)
		(layers "F.Cu" "B.Cu")
		(net "GND")
	)
	(via
		(at 232.837482 -160.623758)
		(size 0.7112)
		(drill 0.4064)
		(layers "F.Cu" "B.Cu")
		(net "GND")
	)
	(via
		(at 119.70004 -45.600112)
		(size 0.6604)
		(drill 0.3556)
		(layers "F.Cu" "B.Cu")
		(net "GND")
	)
	(via
		(at 21.9202 -178.6128)
		(size 0.7112)
		(drill 0.4064)
		(layers "F.Cu" "B.Cu")
		(net "GND")
	)
	(via
		(at 193.05651 -118.36019)
		(size 0.7112)
		(drill 0.4064)
		(layers "F.Cu" "B.Cu")
		(net "GND")
	)
	(via
		(at 49.299622 -143.400526)
		(size 0.4572)
		(drill 0.2032)
		(layers "F.Cu" "B.Cu")
		(net "GND")
	)
	(via
		(at 227.59162 -75.26782)
		(size 0.7112)
		(drill 0.4064)
		(layers "F.Cu" "B.Cu")
		(net "GND")
	)
	(via
		(at 184.223152 -103.1113)
		(size 0.508)
		(drill 0.254)
		(layers "F.Cu" "B.Cu")
		(net "GND")
	)
	(via
		(at 146.462496 -136.70407)
		(size 0.7112)
		(drill 0.4064)
		(layers "F.Cu" "B.Cu")
		(net "GND")
	)
	(via
		(at 232.837482 -169.513758)
		(size 0.7112)
		(drill 0.4064)
		(layers "F.Cu" "B.Cu")
		(net "GND")
	)
	(via
		(at 52.42433 -191.837564)
		(size 0.7112)
		(drill 0.4064)
		(layers "F.Cu" "B.Cu")
		(net "GND")
	)
	(via
		(at 2.162556 -181.760622)
		(size 0.7112)
		(drill 0.4064)
		(layers "F.Cu" "B.Cu")
		(net "GND")
	)
	(via
		(at 224.338388 -15.040356)
		(size 0.7112)
		(drill 0.4064)
		(layers "F.Cu" "B.Cu")
		(net "GND")
	)
	(via
		(at 77.837284 -62.959996)
		(size 0.508)
		(drill 0.254)
		(layers "F.Cu" "B.Cu")
		(net "GND")
	)
	(via
		(at 146.462496 -65.58407)
		(size 0.7112)
		(drill 0.4064)
		(layers "F.Cu" "B.Cu")
		(net "GND")
	)
	(via
		(at 75.9714 -149.6568)
		(size 0.508)
		(drill 0.254)
		(layers "F.Cu" "B.Cu")
		(net "GND")
	)
	(via
		(at 203.21651 -77.72019)
		(size 0.7112)
		(drill 0.4064)
		(layers "F.Cu" "B.Cu")
		(net "GND")
	)
	(via
		(at 2.162556 -150.010622)
		(size 0.7112)
		(drill 0.4064)
		(layers "F.Cu" "B.Cu")
		(net "GND")
	)
	(via
		(at 232.837482 -12.033758)
		(size 0.7112)
		(drill 0.4064)
		(layers "F.Cu" "B.Cu")
		(net "GND")
	)
	(via
		(at 8.636 -15.0876)
		(size 0.508)
		(drill 0.254)
		(layers "F.Cu" "B.Cu")
		(net "GND")
	)
	(via
		(at 28.367482 -3.369564)
		(size 0.7112)
		(drill 0.4064)
		(layers "F.Cu" "B.Cu")
		(net "GND")
	)
	(via
		(at 28.367482 -103.699564)
		(size 0.7112)
		(drill 0.4064)
		(layers "F.Cu" "B.Cu")
		(net "GND")
	)
	(via
		(at 182.89651 -85.34019)
		(size 0.7112)
		(drill 0.4064)
		(layers "F.Cu" "B.Cu")
		(net "GND")
	)
	(via
		(at 232.837482 -39.973758)
		(size 0.7112)
		(drill 0.4064)
		(layers "F.Cu" "B.Cu")
		(net "GND")
	)
	(via
		(at 223.233488 -47.31131)
		(size 0.5588)
		(drill 0.3048)
		(layers "F.Cu" "B.Cu")
		(net "GND")
	)
	(via
		(at 232.837482 -163.163758)
		(size 0.7112)
		(drill 0.4064)
		(layers "F.Cu" "B.Cu")
		(net "GND")
	)
	(via
		(at 24.49449 -2.162556)
		(size 0.7112)
		(drill 0.4064)
		(layers "F.Cu" "B.Cu")
		(net "GND")
	)
	(via
		(at 146.462496 -141.78407)
		(size 0.7112)
		(drill 0.4064)
		(layers "F.Cu" "B.Cu")
		(net "GND")
	)
	(via
		(at 146.462496 -101.14407)
		(size 0.7112)
		(drill 0.4064)
		(layers "F.Cu" "B.Cu")
		(net "GND")
	)
	(via
		(at 187.97651 -42.16019)
		(size 0.7112)
		(drill 0.4064)
		(layers "F.Cu" "B.Cu")
		(net "GND")
	)
	(via
		(at 54.3306 -120.5611)
		(size 0.508)
		(drill 0.254)
		(layers "F.Cu" "B.Cu")
		(net "GND")
	)
	(via
		(at 168.529 -125.476)
		(size 0.7112)
		(drill 0.4064)
		(layers "F.Cu" "B.Cu")
		(net "GND")
	)
	(via
		(at 232.837482 -149.193758)
		(size 0.7112)
		(drill 0.4064)
		(layers "F.Cu" "B.Cu")
		(net "GND")
	)
	(via
		(at 190.51651 -42.16019)
		(size 0.7112)
		(drill 0.4064)
		(layers "F.Cu" "B.Cu")
		(net "GND")
	)
	(via
		(at 198.13651 -82.80019)
		(size 0.7112)
		(drill 0.4064)
		(layers "F.Cu" "B.Cu")
		(net "GND")
	)
	(via
		(at 187.97651 -87.88019)
		(size 0.7112)
		(drill 0.4064)
		(layers "F.Cu" "B.Cu")
		(net "GND")
	)
	(via
		(at 2.162556 -153.820622)
		(size 0.7112)
		(drill 0.4064)
		(layers "F.Cu" "B.Cu")
		(net "GND")
	)
	(via
		(at 198.13651 -62.48019)
		(size 0.7112)
		(drill 0.4064)
		(layers "F.Cu" "B.Cu")
		(net "GND")
	)
	(via
		(at 200.67651 -87.88019)
		(size 0.7112)
		(drill 0.4064)
		(layers "F.Cu" "B.Cu")
		(net "GND")
	)
	(via
		(at 28.367482 -79.569564)
		(size 0.7112)
		(drill 0.4064)
		(layers "F.Cu" "B.Cu")
		(net "GND")
	)
	(via
		(at 193.05651 -115.82019)
		(size 0.7112)
		(drill 0.4064)
		(layers "F.Cu" "B.Cu")
		(net "GND")
	)
	(via
		(at 2.162556 -119.530622)
		(size 0.7112)
		(drill 0.4064)
		(layers "F.Cu" "B.Cu")
		(net "GND")
	)
	(via
		(at 195.82765 -157.837378)
		(size 0.7112)
		(drill 0.4064)
		(layers "F.Cu" "B.Cu")
		(net "GND")
	)
	(via
		(at 28.367482 -75.759564)
		(size 0.7112)
		(drill 0.4064)
		(layers "F.Cu" "B.Cu")
		(net "GND")
	)
	(via
		(at 187.97651 -80.26019)
		(size 0.7112)
		(drill 0.4064)
		(layers "F.Cu" "B.Cu")
		(net "GND")
	)
	(via
		(at 185.43651 -113.28019)
		(size 0.7112)
		(drill 0.4064)
		(layers "F.Cu" "B.Cu")
		(net "GND")
	)
	(via
		(at 185.43651 -24.38019)
		(size 0.7112)
		(drill 0.4064)
		(layers "F.Cu" "B.Cu")
		(net "GND")
	)
	(via
		(at 28.367482 -26.229564)
		(size 0.7112)
		(drill 0.4064)
		(layers "F.Cu" "B.Cu")
		(net "GND")
	)
	(via
		(at 28.367482 -19.879564)
		(size 0.7112)
		(drill 0.4064)
		(layers "F.Cu" "B.Cu")
		(net "GND")
	)
	(via
		(at 82.688684 -2.162556)
		(size 0.7112)
		(drill 0.4064)
		(layers "F.Cu" "B.Cu")
		(net "GND")
	)
	(via
		(at 2.162556 -104.290622)
		(size 0.7112)
		(drill 0.4064)
		(layers "F.Cu" "B.Cu")
		(net "GND")
	)
	(via
		(at 232.837482 -6.953758)
		(size 0.7112)
		(drill 0.4064)
		(layers "F.Cu" "B.Cu")
		(net "GND")
	)
	(via
		(at 25.231598 -173.674024)
		(size 0.7112)
		(drill 0.4064)
		(layers "F.Cu" "B.Cu")
		(net "GND")
	)
	(via
		(at 28.367482 -82.109564)
		(size 0.7112)
		(drill 0.4064)
		(layers "F.Cu" "B.Cu")
		(net "GND")
	)
	(via
		(at 225.557588 -15.040356)
		(size 0.7112)
		(drill 0.4064)
		(layers "F.Cu" "B.Cu")
		(net "GND")
	)
	(via
		(at 217.162634 -173.307502)
		(size 0.7112)
		(drill 0.4064)
		(layers "F.Cu" "B.Cu")
		(net "GND")
	)
	(via
		(at 227.88753 -68.754752)
		(size 0.7112)
		(drill 0.4064)
		(layers "F.Cu" "B.Cu")
		(net "GND")
	)
	(via
		(at 173.649894 -133.225794)
		(size 0.508)
		(drill 0.254)
		(layers "F.Cu" "B.Cu")
		(net "GND")
	)
	(via
		(at 28.30449 -2.162556)
		(size 0.7112)
		(drill 0.4064)
		(layers "F.Cu" "B.Cu")
		(net "GND")
	)
	(via
		(at 198.13651 -100.58019)
		(size 0.7112)
		(drill 0.4064)
		(layers "F.Cu" "B.Cu")
		(net "GND")
	)
	(via
		(at 220.883988 -48.58131)
		(size 0.5588)
		(drill 0.3048)
		(layers "F.Cu" "B.Cu")
		(net "GND")
	)
	(via
		(at 55.6768 -163.9062)
		(size 0.508)
		(drill 0.254)
		(layers "F.Cu" "B.Cu")
		(net "GND")
	)
	(via
		(at 67.7037 -171.6405)
		(size 0.508)
		(drill 0.254)
		(layers "F.Cu" "B.Cu")
		(net "GND")
	)
	(via
		(at 198.13651 -34.54019)
		(size 0.7112)
		(drill 0.4064)
		(layers "F.Cu" "B.Cu")
		(net "GND")
	)
	(via
		(at 232.837482 -183.483758)
		(size 0.7112)
		(drill 0.4064)
		(layers "F.Cu" "B.Cu")
		(net "GND")
	)
	(via
		(at 38.899846 -153.800302)
		(size 0.4572)
		(drill 0.2032)
		(layers "F.Cu" "B.Cu")
		(net "GND")
	)
	(via
		(at 180.35651 -90.42019)
		(size 0.7112)
		(drill 0.4064)
		(layers "F.Cu" "B.Cu")
		(net "GND")
	)
	(via
		(at 198.13651 -26.92019)
		(size 0.7112)
		(drill 0.4064)
		(layers "F.Cu" "B.Cu")
		(net "GND")
	)
	(via
		(at 28.367482 -42.739564)
		(size 0.7112)
		(drill 0.4064)
		(layers "F.Cu" "B.Cu")
		(net "GND")
	)
	(via
		(at 92.7862 -154.051)
		(size 0.5588)
		(drill 0.3048)
		(layers "F.Cu" "B.Cu")
		(net "GND")
	)
	(via
		(at 200.67651 -115.82019)
		(size 0.7112)
		(drill 0.4064)
		(layers "F.Cu" "B.Cu")
		(net "GND")
	)
	(via
		(at 232.837482 -136.493758)
		(size 0.7112)
		(drill 0.4064)
		(layers "F.Cu" "B.Cu")
		(net "GND")
	)
	(via
		(at 75.192636 -21.336508)
		(size 0.7112)
		(drill 0.4064)
		(layers "F.Cu" "B.Cu")
		(net "GND")
	)
	(via
		(at 91.68892 -147.976844)
		(size 0.508)
		(drill 0.254)
		(layers "F.Cu" "B.Cu")
		(net "GND")
	)
	(via
		(at 81.491328 -93.339666)
		(size 0.508)
		(drill 0.254)
		(layers "F.Cu" "B.Cu")
		(net "GND")
	)
	(via
		(at 165.34765 -157.837378)
		(size 0.7112)
		(drill 0.4064)
		(layers "F.Cu" "B.Cu")
		(net "GND")
	)
	(via
		(at 64.568832 -153.41473)
		(size 0.508)
		(drill 0.254)
		(layers "F.Cu" "B.Cu")
		(net "GND")
	)
	(via
		(at 2.162556 -83.970622)
		(size 0.7112)
		(drill 0.4064)
		(layers "F.Cu" "B.Cu")
		(net "GND")
	)
	(via
		(at 232.837482 -89.503758)
		(size 0.7112)
		(drill 0.4064)
		(layers "F.Cu" "B.Cu")
		(net "GND")
	)
	(via
		(at 94.3356 -154.0256)
		(size 0.5588)
		(drill 0.3048)
		(layers "F.Cu" "B.Cu")
		(net "GND")
	)
	(via
		(at 232.837482 -125.063758)
		(size 0.7112)
		(drill 0.4064)
		(layers "F.Cu" "B.Cu")
		(net "GND")
	)
	(via
		(at 205.75651 -37.08019)
		(size 0.7112)
		(drill 0.4064)
		(layers "F.Cu" "B.Cu")
		(net "GND")
	)
	(via
		(at 75.192636 -11.176508)
		(size 0.7112)
		(drill 0.4064)
		(layers "F.Cu" "B.Cu")
		(net "GND")
	)
	(via
		(at 94.729554 -146.520154)
		(size 0.508)
		(drill 0.254)
		(layers "F.Cu" "B.Cu")
		(net "GND")
	)
	(via
		(at 232.837482 -43.783758)
		(size 0.7112)
		(drill 0.4064)
		(layers "F.Cu" "B.Cu")
		(net "GND")
	)
	(via
		(at 22.834346 -141.76121)
		(size 0.508)
		(drill 0.254)
		(layers "F.Cu" "B.Cu")
		(net "GND")
	)
	(via
		(at 146.462496 -51.61407)
		(size 0.7112)
		(drill 0.4064)
		(layers "F.Cu" "B.Cu")
		(net "GND")
	)
	(via
		(at 198.13651 -95.50019)
		(size 0.7112)
		(drill 0.4064)
		(layers "F.Cu" "B.Cu")
		(net "GND")
	)
	(via
		(at 2.162556 -165.250622)
		(size 0.7112)
		(drill 0.4064)
		(layers "F.Cu" "B.Cu")
		(net "GND")
	)
	(via
		(at 226.22891 -104.353614)
		(size 0.7112)
		(drill 0.4064)
		(layers "F.Cu" "B.Cu")
		(net "GND")
	)
	(via
		(at 95.0468 -164.051234)
		(size 0.508)
		(drill 0.254)
		(layers "F.Cu" "B.Cu")
		(net "GND")
	)
	(via
		(at 180.35651 -29.46019)
		(size 0.7112)
		(drill 0.4064)
		(layers "F.Cu" "B.Cu")
		(net "GND")
	)
	(via
		(at 187.97651 -59.94019)
		(size 0.7112)
		(drill 0.4064)
		(layers "F.Cu" "B.Cu")
		(net "GND")
	)
	(via
		(at 77.567028 -57.778396)
		(size 0.508)
		(drill 0.254)
		(layers "F.Cu" "B.Cu")
		(net "GND")
	)
	(via
		(at 193.05651 -24.38019)
		(size 0.7112)
		(drill 0.4064)
		(layers "F.Cu" "B.Cu")
		(net "GND")
	)
	(via
		(at 232.837482 -24.733758)
		(size 0.7112)
		(drill 0.4064)
		(layers "F.Cu" "B.Cu")
		(net "GND")
	)
	(via
		(at 81.643728 -80.48879)
		(size 0.508)
		(drill 0.254)
		(layers "F.Cu" "B.Cu")
		(net "GND")
	)
	(via
		(at 75.192636 -32.766508)
		(size 0.7112)
		(drill 0.4064)
		(layers "F.Cu" "B.Cu")
		(net "GND")
	)
	(via
		(at 22.0345 -144.16151)
		(size 0.508)
		(drill 0.254)
		(layers "F.Cu" "B.Cu")
		(net "GND")
	)
	(via
		(at 91.1352 -154.0002)
		(size 0.5588)
		(drill 0.3048)
		(layers "F.Cu" "B.Cu")
		(net "GND")
	)
	(via
		(at 182.89651 -59.94019)
		(size 0.7112)
		(drill 0.4064)
		(layers "F.Cu" "B.Cu")
		(net "GND")
	)
	(via
		(at 208.29651 -67.56019)
		(size 0.7112)
		(drill 0.4064)
		(layers "F.Cu" "B.Cu")
		(net "GND")
	)
	(via
		(at 169.887138 -6.885178)
		(size 0.7112)
		(drill 0.4064)
		(layers "F.Cu" "B.Cu")
		(net "GND")
	)
	(via
		(at 190.51651 -92.96019)
		(size 0.7112)
		(drill 0.4064)
		(layers "F.Cu" "B.Cu")
		(net "GND")
	)
	(via
		(at 146.462496 -63.04407)
		(size 0.7112)
		(drill 0.4064)
		(layers "F.Cu" "B.Cu")
		(net "GND")
	)
	(via
		(at 53.7718 -130.429)
		(size 0.508)
		(drill 0.254)
		(layers "F.Cu" "B.Cu")
		(net "GND")
	)
	(via
		(at 75.192636 -31.496508)
		(size 0.7112)
		(drill 0.4064)
		(layers "F.Cu" "B.Cu")
		(net "GND")
	)
	(via
		(at 182.940198 -56.699912)
		(size 0.7112)
		(drill 0.4064)
		(layers "F.Cu" "B.Cu")
		(net "GND")
	)
	(via
		(at 205.75651 -67.56019)
		(size 0.7112)
		(drill 0.4064)
		(layers "F.Cu" "B.Cu")
		(net "GND")
	)
	(via
		(at 157.923738 -16.079978)
		(size 0.7112)
		(drill 0.4064)
		(layers "F.Cu" "B.Cu")
		(net "GND")
	)
	(via
		(at 229.432358 -190.299848)
		(size 0.7112)
		(drill 0.4064)
		(layers "F.Cu" "B.Cu")
		(net "GND")
	)
	(via
		(at 62.611 -153.035)
		(size 0.508)
		(drill 0.254)
		(layers "F.Cu" "B.Cu")
		(net "GND")
	)
	(via
		(at 2.162556 -43.330622)
		(size 0.7112)
		(drill 0.4064)
		(layers "F.Cu" "B.Cu")
		(net "GND")
	)
	(via
		(at 231.13619 -186.892184)
		(size 0.7112)
		(drill 0.4064)
		(layers "F.Cu" "B.Cu")
		(net "GND")
	)
	(via
		(at 10.922 -15.113)
		(size 0.508)
		(drill 0.254)
		(layers "F.Cu" "B.Cu")
		(net "GND")
	)
	(via
		(at 168.529 -122.936)
		(size 0.7112)
		(drill 0.4064)
		(layers "F.Cu" "B.Cu")
		(net "GND")
	)
	(via
		(at 232.837482 -72.993758)
		(size 0.7112)
		(drill 0.4064)
		(layers "F.Cu" "B.Cu")
		(net "GND")
	)
	(via
		(at 176.668684 -2.162556)
		(size 0.7112)
		(drill 0.4064)
		(layers "F.Cu" "B.Cu")
		(net "GND")
	)
	(via
		(at 51.044602 -161.6964)
		(size 0.508)
		(drill 0.254)
		(layers "F.Cu" "B.Cu")
		(net "GND")
	)
	(via
		(at 34.294826 -182.65013)
		(size 0.5588)
		(drill 0.3048)
		(layers "F.Cu" "B.Cu")
		(net "GND")
	)
	(via
		(at 28.367482 -57.979564)
		(size 0.7112)
		(drill 0.4064)
		(layers "F.Cu" "B.Cu")
		(net "GND")
	)
	(via
		(at 28.367482 -69.409564)
		(size 0.7112)
		(drill 0.4064)
		(layers "F.Cu" "B.Cu")
		(net "GND")
	)
	(via
		(at 168.617138 -6.885178)
		(size 0.7112)
		(drill 0.4064)
		(layers "F.Cu" "B.Cu")
		(net "GND")
	)
	(via
		(at 217.162634 -172.037502)
		(size 0.7112)
		(drill 0.4064)
		(layers "F.Cu" "B.Cu")
		(net "GND")
	)
	(via
		(at 21.6916 -159.965136)
		(size 0.508)
		(drill 0.254)
		(layers "F.Cu" "B.Cu")
		(net "GND")
	)
	(via
		(at 38.38702 -178.67376)
		(size 0.508)
		(drill 0.254)
		(layers "F.Cu" "B.Cu")
		(net "GND")
	)
	(via
		(at 218.59748 -98.240088)
		(size 0.5588)
		(drill 0.3048)
		(layers "F.Cu" "B.Cu")
		(net "GND")
	)
	(via
		(at 2.162556 -87.780622)
		(size 0.7112)
		(drill 0.4064)
		(layers "F.Cu" "B.Cu")
		(net "GND")
	)
	(via
		(at 200.67651 -26.92019)
		(size 0.7112)
		(drill 0.4064)
		(layers "F.Cu" "B.Cu")
		(net "GND")
	)
	(via
		(at 116.099844 -45.600112)
		(size 0.6604)
		(drill 0.3556)
		(layers "F.Cu" "B.Cu")
		(net "GND")
	)
	(via
		(at 188.20765 -157.837378)
		(size 0.7112)
		(drill 0.4064)
		(layers "F.Cu" "B.Cu")
		(net "GND")
	)
	(via
		(at 74.2696 -162.687)
		(size 0.508)
		(drill 0.254)
		(layers "F.Cu" "B.Cu")
		(net "GND")
	)
	(via
		(at 92.456 -60.9854)
		(size 0.508)
		(drill 0.254)
		(layers "F.Cu" "B.Cu")
		(net "GND")
	)
	(via
		(at 183.328564 -62.488318)
		(size 0.7112)
		(drill 0.4064)
		(layers "F.Cu" "B.Cu")
		(net "GND")
	)
	(via
		(at 46.900084 -146.600164)
		(size 0.4572)
		(drill 0.2032)
		(layers "F.Cu" "B.Cu")
		(net "GND")
	)
	(via
		(at 177.81651 -34.54019)
		(size 0.7112)
		(drill 0.4064)
		(layers "F.Cu" "B.Cu")
		(net "GND")
	)
	(via
		(at 7.8994 -130.2258)
		(size 0.6096)
		(drill 0.3048)
		(layers "F.Cu" "B.Cu")
		(net "GND")
	)
	(via
		(at 97.166938 -13.4112)
		(size 0.508)
		(drill 0.254)
		(layers "F.Cu" "B.Cu")
		(net "GND")
	)
	(via
		(at 20.68449 -2.162556)
		(size 0.7112)
		(drill 0.4064)
		(layers "F.Cu" "B.Cu")
		(net "GND")
	)
	(via
		(at 213.60765 -157.837378)
		(size 0.7112)
		(drill 0.4064)
		(layers "F.Cu" "B.Cu")
		(net "GND")
	)
	(via
		(at 232.837482 -159.353758)
		(size 0.7112)
		(drill 0.4064)
		(layers "F.Cu" "B.Cu")
		(net "GND")
	)
	(via
		(at 217.162634 -169.497502)
		(size 0.7112)
		(drill 0.4064)
		(layers "F.Cu" "B.Cu")
		(net "GND")
	)
	(via
		(at 2.162556 -71.270622)
		(size 0.7112)
		(drill 0.4064)
		(layers "F.Cu" "B.Cu")
		(net "GND")
	)
	(via
		(at 34.469324 -157.781498)
		(size 0.508)
		(drill 0.254)
		(layers "F.Cu" "B.Cu")
		(net "GND")
	)
	(via
		(at 2.162556 -183.030622)
		(size 0.7112)
		(drill 0.4064)
		(layers "F.Cu" "B.Cu")
		(net "GND")
	)
	(via
		(at 2.162556 -127.150622)
		(size 0.7112)
		(drill 0.4064)
		(layers "F.Cu" "B.Cu")
		(net "GND")
	)
	(via
		(at 16.434054 -144.961864)
		(size 0.508)
		(drill 0.254)
		(layers "F.Cu" "B.Cu")
		(net "GND")
	)
	(via
		(at 232.837482 -22.193758)
		(size 0.7112)
		(drill 0.4064)
		(layers "F.Cu" "B.Cu")
		(net "GND")
	)
	(via
		(at 10.819638 -145.234406)
		(size 0.508)
		(drill 0.254)
		(layers "F.Cu" "B.Cu")
		(net "GND")
	)
	(via
		(at 2.162556 -25.550622)
		(size 0.7112)
		(drill 0.4064)
		(layers "F.Cu" "B.Cu")
		(net "GND")
	)
	(via
		(at 195.59651 -37.08019)
		(size 0.7112)
		(drill 0.4064)
		(layers "F.Cu" "B.Cu")
		(net "GND")
	)
	(via
		(at 204.665834 -131.760722)
		(size 0.7112)
		(drill 0.4064)
		(layers "F.Cu" "B.Cu")
		(net "GND")
	)
	(via
		(at 2.162556 -156.360622)
		(size 0.7112)
		(drill 0.4064)
		(layers "F.Cu" "B.Cu")
		(net "GND")
	)
	(via
		(at 232.837482 -135.223758)
		(size 0.7112)
		(drill 0.4064)
		(layers "F.Cu" "B.Cu")
		(net "GND")
	)
	(via
		(at 222.319088 -47.31131)
		(size 0.5588)
		(drill 0.3048)
		(layers "F.Cu" "B.Cu")
		(net "GND")
	)
	(via
		(at 193.05651 -90.42019)
		(size 0.7112)
		(drill 0.4064)
		(layers "F.Cu" "B.Cu")
		(net "GND")
	)
	(via
		(at 182.638446 -75.186794)
		(size 0.7112)
		(drill 0.4064)
		(layers "F.Cu" "B.Cu")
		(net "GND")
	)
	(via
		(at 200.67651 -39.62019)
		(size 0.7112)
		(drill 0.4064)
		(layers "F.Cu" "B.Cu")
		(net "GND")
	)
	(via
		(at 200.708514 -108.327444)
		(size 0.7112)
		(drill 0.4064)
		(layers "F.Cu" "B.Cu")
		(net "GND")
	)
	(via
		(at 232.837482 -93.313758)
		(size 0.7112)
		(drill 0.4064)
		(layers "F.Cu" "B.Cu")
		(net "GND")
	)
	(via
		(at 187.97651 -90.42019)
		(size 0.7112)
		(drill 0.4064)
		(layers "F.Cu" "B.Cu")
		(net "GND")
	)
	(via
		(at 93.4974 -130.3274)
		(size 0.508)
		(drill 0.254)
		(layers "F.Cu" "B.Cu")
		(net "GND")
	)
	(via
		(at 16.7386 -170.434)
		(size 0.5588)
		(drill 0.3048)
		(layers "F.Cu" "B.Cu")
		(net "GND")
	)
	(via
		(at 175.150018 -133.225794)
		(size 0.508)
		(drill 0.254)
		(layers "F.Cu" "B.Cu")
		(net "GND")
	)
	(via
		(at 206.149956 -136.25449)
		(size 0.508)
		(drill 0.254)
		(layers "F.Cu" "B.Cu")
		(net "GND")
	)
	(via
		(at 51.6509 -128.7018)
		(size 0.508)
		(drill 0.254)
		(layers "F.Cu" "B.Cu")
		(net "GND")
	)
	(via
		(at 91.096084 -151.499824)
		(size 0.508)
		(drill 0.254)
		(layers "F.Cu" "B.Cu")
		(net "GND")
	)
	(via
		(at 203.21651 -34.54019)
		(size 0.7112)
		(drill 0.4064)
		(layers "F.Cu" "B.Cu")
		(net "GND")
	)
	(via
		(at 222.618554 -103.619046)
		(size 0.7112)
		(drill 0.4064)
		(layers "F.Cu" "B.Cu")
		(net "GND")
	)
	(via
		(at 195.59651 -52.32019)
		(size 0.7112)
		(drill 0.4064)
		(layers "F.Cu" "B.Cu")
		(net "GND")
	)
	(via
		(at 53.299868 -148.199856)
		(size 0.4572)
		(drill 0.2032)
		(layers "F.Cu" "B.Cu")
		(net "GND")
	)
	(via
		(at 28.367482 -38.929564)
		(size 0.7112)
		(drill 0.4064)
		(layers "F.Cu" "B.Cu")
		(net "GND")
	)
	(via
		(at 193.05651 -59.94019)
		(size 0.7112)
		(drill 0.4064)
		(layers "F.Cu" "B.Cu")
		(net "GND")
	)
	(via
		(at 200.559416 -131.846828)
		(size 0.7112)
		(drill 0.4064)
		(layers "F.Cu" "B.Cu")
		(net "GND")
	)
	(via
		(at 2.162556 -67.460622)
		(size 0.7112)
		(drill 0.4064)
		(layers "F.Cu" "B.Cu")
		(net "GND")
	)
	(via
		(at 208.29651 -77.72019)
		(size 0.7112)
		(drill 0.4064)
		(layers "F.Cu" "B.Cu")
		(net "GND")
	)
	(via
		(at 76.33208 -180.34508)
		(size 0.5588)
		(drill 0.3048)
		(layers "F.Cu" "B.Cu")
		(net "GND")
	)
	(via
		(at 218.661488 -48.58131)
		(size 0.5588)
		(drill 0.3048)
		(layers "F.Cu" "B.Cu")
		(net "GND")
	)
	(via
		(at 28.367482 -102.429564)
		(size 0.7112)
		(drill 0.4064)
		(layers "F.Cu" "B.Cu")
		(net "GND")
	)
	(via
		(at 232.837482 -112.363758)
		(size 0.7112)
		(drill 0.4064)
		(layers "F.Cu" "B.Cu")
		(net "GND")
	)
	(via
		(at 16.87449 -2.162556)
		(size 0.7112)
		(drill 0.4064)
		(layers "F.Cu" "B.Cu")
		(net "GND")
	)
	(via
		(at 185.43651 -85.34019)
		(size 0.7112)
		(drill 0.4064)
		(layers "F.Cu" "B.Cu")
		(net "GND")
	)
	(via
		(at 213.649814 -136.25449)
		(size 0.508)
		(drill 0.254)
		(layers "F.Cu" "B.Cu")
		(net "GND")
	)
	(via
		(at 205.75651 -59.94019)
		(size 0.7112)
		(drill 0.4064)
		(layers "F.Cu" "B.Cu")
		(net "GND")
	)
	(via
		(at 232.837482 -53.943758)
		(size 0.7112)
		(drill 0.4064)
		(layers "F.Cu" "B.Cu")
		(net "GND")
	)
	(via
		(at 25.76449 -2.162556)
		(size 0.7112)
		(drill 0.4064)
		(layers "F.Cu" "B.Cu")
		(net "GND")
	)
	(via
		(at 174.23765 -157.837378)
		(size 0.7112)
		(drill 0.4064)
		(layers "F.Cu" "B.Cu")
		(net "GND")
	)
	(via
		(at 169.3672 -131.953)
		(size 0.508)
		(drill 0.254)
		(layers "F.Cu" "B.Cu")
		(net "GND")
	)
	(via
		(at 2.162556 -16.660622)
		(size 0.7112)
		(drill 0.4064)
		(layers "F.Cu" "B.Cu")
		(net "GND")
	)
	(via
		(at 177.81651 -100.58019)
		(size 0.7112)
		(drill 0.4064)
		(layers "F.Cu" "B.Cu")
		(net "GND")
	)
	(via
		(at 2.162556 -58.570622)
		(size 0.7112)
		(drill 0.4064)
		(layers "F.Cu" "B.Cu")
		(net "GND")
	)
	(via
		(at 17.234662 -141.761718)
		(size 0.508)
		(drill 0.254)
		(layers "F.Cu" "B.Cu")
		(net "GND")
	)
	(via
		(at 195.59651 -77.72019)
		(size 0.7112)
		(drill 0.4064)
		(layers "F.Cu" "B.Cu")
		(net "GND")
	)
	(via
		(at 34.798 -154.3939)
		(size 0.508)
		(drill 0.254)
		(layers "F.Cu" "B.Cu")
		(net "GND")
	)
	(via
		(at 75.192636 -17.526508)
		(size 0.7112)
		(drill 0.4064)
		(layers "F.Cu" "B.Cu")
		(net "GND")
	)
	(via
		(at 58.77433 -191.837564)
		(size 0.7112)
		(drill 0.4064)
		(layers "F.Cu" "B.Cu")
		(net "GND")
	)
	(via
		(at 232.837482 -140.303758)
		(size 0.7112)
		(drill 0.4064)
		(layers "F.Cu" "B.Cu")
		(net "GND")
	)
	(via
		(at 31.477712 -189.17285)
		(size 0.7112)
		(drill 0.4064)
		(layers "F.Cu" "B.Cu")
		(net "GND")
	)
	(via
		(at 227.538026 -80.357218)
		(size 0.7112)
		(drill 0.4064)
		(layers "F.Cu" "B.Cu")
		(net "GND")
	)
	(via
		(at 200.67651 -105.66019)
		(size 0.7112)
		(drill 0.4064)
		(layers "F.Cu" "B.Cu")
		(net "GND")
	)
	(via
		(at 28.367482 -63.059564)
		(size 0.7112)
		(drill 0.4064)
		(layers "F.Cu" "B.Cu")
		(net "GND")
	)
	(via
		(at 207.649826 -136.25449)
		(size 0.508)
		(drill 0.254)
		(layers "F.Cu" "B.Cu")
		(net "GND")
	)
	(via
		(at 24.873204 -127.5842)
		(size 0.508)
		(drill 0.254)
		(layers "F.Cu" "B.Cu")
		(net "GND")
	)
	(via
		(at 180.35651 -80.26019)
		(size 0.7112)
		(drill 0.4064)
		(layers "F.Cu" "B.Cu")
		(net "GND")
	)
	(via
		(at 59.600592 -137.275062)
		(size 0.508)
		(drill 0.254)
		(layers "F.Cu" "B.Cu")
		(net "GND")
	)
	(via
		(at 213.498684 -2.162556)
		(size 0.7112)
		(drill 0.4064)
		(layers "F.Cu" "B.Cu")
		(net "GND")
	)
	(via
		(at 130.398266 -26.24455)
		(size 0.508)
		(drill 0.254)
		(layers "F.Cu" "B.Cu")
		(net "GND")
	)
	(via
		(at 229.311962 -55.291736)
		(size 0.7112)
		(drill 0.4064)
		(layers "F.Cu" "B.Cu")
		(net "GND")
	)
	(via
		(at 51.689 -130.429)
		(size 0.508)
		(drill 0.254)
		(layers "F.Cu" "B.Cu")
		(net "GND")
	)
	(via
		(at 200.105518 -70.073266)
		(size 0.7112)
		(drill 0.4064)
		(layers "F.Cu" "B.Cu")
		(net "GND")
	)
	(via
		(at 180.35651 -115.82019)
		(size 0.7112)
		(drill 0.4064)
		(layers "F.Cu" "B.Cu")
		(net "GND")
	)
	(via
		(at 2.162556 -38.250622)
		(size 0.7112)
		(drill 0.4064)
		(layers "F.Cu" "B.Cu")
		(net "GND")
	)
	(via
		(at 2.162556 -75.080622)
		(size 0.7112)
		(drill 0.4064)
		(layers "F.Cu" "B.Cu")
		(net "GND")
	)
	(via
		(at 232.837482 -128.873758)
		(size 0.7112)
		(drill 0.4064)
		(layers "F.Cu" "B.Cu")
		(net "GND")
	)
	(via
		(at 75.192636 -27.686508)
		(size 0.7112)
		(drill 0.4064)
		(layers "F.Cu" "B.Cu")
		(net "GND")
	)
	(via
		(at 77.5589 -130.6322)
		(size 0.508)
		(drill 0.254)
		(layers "F.Cu" "B.Cu")
		(net "GND")
	)
	(via
		(at 146.462496 -137.97407)
		(size 0.7112)
		(drill 0.4064)
		(layers "F.Cu" "B.Cu")
		(net "GND")
	)
	(via
		(at 23.996142 -138.961622)
		(size 0.508)
		(drill 0.254)
		(layers "F.Cu" "B.Cu")
		(net "GND")
	)
	(via
		(at 173.581568 -132.202428)
		(size 0.7112)
		(drill 0.4064)
		(layers "F.Cu" "B.Cu")
		(net "GND")
	)
	(via
		(at 203.21651 -118.36019)
		(size 0.7112)
		(drill 0.4064)
		(layers "F.Cu" "B.Cu")
		(net "GND")
	)
	(via
		(at 192.662048 -135.74522)
		(size 0.7112)
		(drill 0.4064)
		(layers "F.Cu" "B.Cu")
		(net "GND")
	)
	(via
		(at 2.162556 -3.960622)
		(size 0.7112)
		(drill 0.4064)
		(layers "F.Cu" "B.Cu")
		(net "GND")
	)
	(via
		(at 72.74433 -191.837564)
		(size 0.7112)
		(drill 0.4064)
		(layers "F.Cu" "B.Cu")
		(net "GND")
	)
	(via
		(at 5.364988 -189.894718)
		(size 0.7112)
		(drill 0.4064)
		(layers "F.Cu" "B.Cu")
		(net "GND")
	)
	(via
		(at 23.634192 -146.561556)
		(size 0.508)
		(drill 0.254)
		(layers "F.Cu" "B.Cu")
		(net "GND")
	)
	(via
		(at 52.705 -127.612648)
		(size 0.508)
		(drill 0.254)
		(layers "F.Cu" "B.Cu")
		(net "GND")
	)
	(via
		(at 146.462496 -104.95407)
		(size 0.7112)
		(drill 0.4064)
		(layers "F.Cu" "B.Cu")
		(net "GND")
	)
	(via
		(at 232.837482 -47.593758)
		(size 0.7112)
		(drill 0.4064)
		(layers "F.Cu" "B.Cu")
		(net "GND")
	)
	(via
		(at 197.149974 -136.25449)
		(size 0.508)
		(drill 0.254)
		(layers "F.Cu" "B.Cu")
		(net "GND")
	)
	(via
		(at 146.462496 -126.54407)
		(size 0.7112)
		(drill 0.4064)
		(layers "F.Cu" "B.Cu")
		(net "GND")
	)
	(via
		(at 71.501 -151.998426)
		(size 0.508)
		(drill 0.254)
		(layers "F.Cu" "B.Cu")
		(net "GND")
	)
	(via
		(at 2.162556 -130.960622)
		(size 0.7112)
		(drill 0.4064)
		(layers "F.Cu" "B.Cu")
		(net "GND")
	)
	(via
		(at 74.2188 -137.788142)
		(size 0.508)
		(drill 0.254)
		(layers "F.Cu" "B.Cu")
		(net "GND")
	)
	(via
		(at 146.462496 -66.85407)
		(size 0.7112)
		(drill 0.4064)
		(layers "F.Cu" "B.Cu")
		(net "GND")
	)
	(via
		(at 22.021546 -127.5842)
		(size 0.508)
		(drill 0.254)
		(layers "F.Cu" "B.Cu")
		(net "GND")
	)
	(via
		(at 232.837482 -59.023758)
		(size 0.7112)
		(drill 0.4064)
		(layers "F.Cu" "B.Cu")
		(net "GND")
	)
	(via
		(at 196.461126 -70.358254)
		(size 0.7112)
		(drill 0.4064)
		(layers "F.Cu" "B.Cu")
		(net "GND")
	)
	(via
		(at 195.59651 -80.26019)
		(size 0.7112)
		(drill 0.4064)
		(layers "F.Cu" "B.Cu")
		(net "GND")
	)
	(via
		(at 85.09 -157.7848)
		(size 0.7112)
		(drill 0.4064)
		(layers "F.Cu" "B.Cu")
		(net "GND")
	)
	(via
		(at 217.162634 -163.147502)
		(size 0.7112)
		(drill 0.4064)
		(layers "F.Cu" "B.Cu")
		(net "GND")
	)
	(via
		(at 200.149968 -136.25449)
		(size 0.508)
		(drill 0.254)
		(layers "F.Cu" "B.Cu")
		(net "GND")
	)
	(via
		(at 177.81651 -98.04019)
		(size 0.7112)
		(drill 0.4064)
		(layers "F.Cu" "B.Cu")
		(net "GND")
	)
	(via
		(at 2.162556 -44.600622)
		(size 0.7112)
		(drill 0.4064)
		(layers "F.Cu" "B.Cu")
		(net "GND")
	)
	(via
		(at 44.499784 -149.800056)
		(size 0.4572)
		(drill 0.2032)
		(layers "F.Cu" "B.Cu")
		(net "GND")
	)
	(via
		(at 24.48433 -191.837564)
		(size 0.7112)
		(drill 0.4064)
		(layers "F.Cu" "B.Cu")
		(net "GND")
	)
	(via
		(at 219.51188 -97.325688)
		(size 0.5588)
		(drill 0.3048)
		(layers "F.Cu" "B.Cu")
		(net "GND")
	)
	(via
		(at 182.89651 -67.56019)
		(size 0.7112)
		(drill 0.4064)
		(layers "F.Cu" "B.Cu")
		(net "GND")
	)
	(via
		(at 232.837482 -65.373758)
		(size 0.7112)
		(drill 0.4064)
		(layers "F.Cu" "B.Cu")
		(net "GND")
	)
	(via
		(at 49.299622 -141.00048)
		(size 0.4572)
		(drill 0.2032)
		(layers "F.Cu" "B.Cu")
		(net "GND")
	)
	(via
		(at 55.0418 -179.06619)
		(size 0.7112)
		(drill 0.4064)
		(layers "F.Cu" "B.Cu")
		(net "GND")
	)
	(via
		(at 164.07765 -157.837378)
		(size 0.7112)
		(drill 0.4064)
		(layers "F.Cu" "B.Cu")
		(net "GND")
	)
	(via
		(at 121.520204 -5.188458)
		(size 0.508)
		(drill 0.254)
		(layers "F.Cu" "B.Cu")
		(net "GND")
	)
	(via
		(at 47.687484 -144.187926)
		(size 0.4572)
		(drill 0.2032)
		(layers "F.Cu" "B.Cu")
		(net "GND")
	)
	(via
		(at 190.51651 -26.92019)
		(size 0.7112)
		(drill 0.4064)
		(layers "F.Cu" "B.Cu")
		(net "GND")
	)
	(via
		(at 19.100038 -145.398998)
		(size 0.508)
		(drill 0.254)
		(layers "F.Cu" "B.Cu")
		(net "GND")
	)
	(via
		(at 190.51651 -21.84019)
		(size 0.7112)
		(drill 0.4064)
		(layers "F.Cu" "B.Cu")
		(net "GND")
	)
	(via
		(at 185.868564 -62.488318)
		(size 0.7112)
		(drill 0.4064)
		(layers "F.Cu" "B.Cu")
		(net "GND")
	)
	(via
		(at 16.364458 -136.864344)
		(size 0.508)
		(drill 0.254)
		(layers "F.Cu" "B.Cu")
		(net "GND")
	)
	(via
		(at 32.2834 -164.338)
		(size 0.508)
		(drill 0.254)
		(layers "F.Cu" "B.Cu")
		(net "GND")
	)
	(via
		(at 188.214 -72.644)
		(size 0.7112)
		(drill 0.4064)
		(layers "F.Cu" "B.Cu")
		(net "GND")
	)
	(via
		(at 39.72433 -191.837564)
		(size 0.7112)
		(drill 0.4064)
		(layers "F.Cu" "B.Cu")
		(net "GND")
	)
	(via
		(at 198.13651 -118.36019)
		(size 0.7112)
		(drill 0.4064)
		(layers "F.Cu" "B.Cu")
		(net "GND")
	)
	(via
		(at 185.43651 -100.58019)
		(size 0.7112)
		(drill 0.4064)
		(layers "F.Cu" "B.Cu")
		(net "GND")
	)
	(via
		(at 193.05651 -80.26019)
		(size 0.7112)
		(drill 0.4064)
		(layers "F.Cu" "B.Cu")
		(net "GND")
	)
	(via
		(at 232.837482 -75.533758)
		(size 0.7112)
		(drill 0.4064)
		(layers "F.Cu" "B.Cu")
		(net "GND")
	)
	(via
		(at 177.81651 -67.56019)
		(size 0.7112)
		(drill 0.4064)
		(layers "F.Cu" "B.Cu")
		(net "GND")
	)
	(via
		(at 47.9044 -135.001)
		(size 0.508)
		(drill 0.254)
		(layers "F.Cu" "B.Cu")
		(net "GND")
	)
	(via
		(at 205.74 -79.756)
		(size 0.7112)
		(drill 0.4064)
		(layers "F.Cu" "B.Cu")
		(net "GND")
	)
	(via
		(at 200.67651 -65.02019)
		(size 0.7112)
		(drill 0.4064)
		(layers "F.Cu" "B.Cu")
		(net "GND")
	)
	(via
		(at 195.59651 -39.62019)
		(size 0.7112)
		(drill 0.4064)
		(layers "F.Cu" "B.Cu")
		(net "GND")
	)
	(via
		(at 76.338684 -2.162556)
		(size 0.7112)
		(drill 0.4064)
		(layers "F.Cu" "B.Cu")
		(net "GND")
	)
	(via
		(at 28.367482 -92.269564)
		(size 0.7112)
		(drill 0.4064)
		(layers "F.Cu" "B.Cu")
		(net "GND")
	)
	(via
		(at 208.29651 -39.62019)
		(size 0.7112)
		(drill 0.4064)
		(layers "F.Cu" "B.Cu")
		(net "GND")
	)
	(via
		(at 28.367482 -65.599564)
		(size 0.7112)
		(drill 0.4064)
		(layers "F.Cu" "B.Cu")
		(net "GND")
	)
	(via
		(at 4.2291 -187.622688)
		(size 0.7112)
		(drill 0.4064)
		(layers "F.Cu" "B.Cu")
		(net "GND")
	)
	(via
		(at 30.83433 -191.837564)
		(size 0.7112)
		(drill 0.4064)
		(layers "F.Cu" "B.Cu")
		(net "GND")
	)
	(via
		(at 62.58433 -191.837564)
		(size 0.7112)
		(drill 0.4064)
		(layers "F.Cu" "B.Cu")
		(net "GND")
	)
	(via
		(at 198.13651 -54.86019)
		(size 0.7112)
		(drill 0.4064)
		(layers "F.Cu" "B.Cu")
		(net "GND")
	)
	(via
		(at 185.66765 -157.837378)
		(size 0.7112)
		(drill 0.4064)
		(layers "F.Cu" "B.Cu")
		(net "GND")
	)
	(via
		(at 2.162556 -124.610622)
		(size 0.7112)
		(drill 0.4064)
		(layers "F.Cu" "B.Cu")
		(net "GND")
	)
	(via
		(at 87.5284 -129.9972)
		(size 0.508)
		(drill 0.254)
		(layers "F.Cu" "B.Cu")
		(net "GND")
	)
	(via
		(at 89.6112 -178.55184)
		(size 0.508)
		(drill 0.254)
		(layers "F.Cu" "B.Cu")
		(net "GND")
	)
	(via
		(at 98.034856 -20.342606)
		(size 0.508)
		(drill 0.254)
		(layers "F.Cu" "B.Cu")
		(net "GND")
	)
	(via
		(at 81.643728 -70.88886)
		(size 0.508)
		(drill 0.254)
		(layers "F.Cu" "B.Cu")
		(net "GND")
	)
	(via
		(at 232.837482 -52.673758)
		(size 0.7112)
		(drill 0.4064)
		(layers "F.Cu" "B.Cu")
		(net "GND")
	)
	(via
		(at 49.8094 -122.4788)
		(size 0.508)
		(drill 0.254)
		(layers "F.Cu" "B.Cu")
		(net "GND")
	)
	(via
		(at 69.7992 -154.305)
		(size 0.508)
		(drill 0.254)
		(layers "F.Cu" "B.Cu")
		(net "GND")
	)
	(via
		(at 190.51651 -70.10019)
		(size 0.7112)
		(drill 0.4064)
		(layers "F.Cu" "B.Cu")
		(net "GND")
	)
	(via
		(at 28.367482 -73.219564)
		(size 0.7112)
		(drill 0.4064)
		(layers "F.Cu" "B.Cu")
		(net "GND")
	)
	(via
		(at 221.34068 -96.411288)
		(size 0.5588)
		(drill 0.3048)
		(layers "F.Cu" "B.Cu")
		(net "GND")
	)
	(via
		(at 33.024826 -179.34813)
		(size 0.5588)
		(drill 0.3048)
		(layers "F.Cu" "B.Cu")
		(net "GND")
	)
	(via
		(at 200.67651 -59.94019)
		(size 0.7112)
		(drill 0.4064)
		(layers "F.Cu" "B.Cu")
		(net "GND")
	)
	(via
		(at 198.13651 -103.12019)
		(size 0.7112)
		(drill 0.4064)
		(layers "F.Cu" "B.Cu")
		(net "GND")
	)
	(via
		(at 28.367482 -18.609564)
		(size 0.7112)
		(drill 0.4064)
		(layers "F.Cu" "B.Cu")
		(net "GND")
	)
	(via
		(at 2.162556 -134.770622)
		(size 0.7112)
		(drill 0.4064)
		(layers "F.Cu" "B.Cu")
		(net "GND")
	)
	(via
		(at 34.293048 -129.5908)
		(size 0.508)
		(drill 0.254)
		(layers "F.Cu" "B.Cu")
		(net "GND")
	)
	(via
		(at 190.51651 -77.72019)
		(size 0.7112)
		(drill 0.4064)
		(layers "F.Cu" "B.Cu")
		(net "GND")
	)
	(via
		(at 2.162556 -85.240622)
		(size 0.7112)
		(drill 0.4064)
		(layers "F.Cu" "B.Cu")
		(net "GND")
	)
	(via
		(at 34.64433 -191.837564)
		(size 0.7112)
		(drill 0.4064)
		(layers "F.Cu" "B.Cu")
		(net "GND")
	)
	(via
		(at 57.6834 -124.5362)
		(size 0.508)
		(drill 0.254)
		(layers "F.Cu" "B.Cu")
		(net "GND")
	)
	(via
		(at 232.837482 -60.293758)
		(size 0.7112)
		(drill 0.4064)
		(layers "F.Cu" "B.Cu")
		(net "GND")
	)
	(via
		(at 21.7424 -169.545)
		(size 0.7112)
		(drill 0.4064)
		(layers "F.Cu" "B.Cu")
		(net "GND")
	)
	(via
		(at 146.462496 -93.52407)
		(size 0.7112)
		(drill 0.4064)
		(layers "F.Cu" "B.Cu")
		(net "GND")
	)
	(via
		(at 2.162556 -180.490622)
		(size 0.7112)
		(drill 0.4064)
		(layers "F.Cu" "B.Cu")
		(net "GND")
	)
	(via
		(at 130.499866 -45.600112)
		(size 0.6604)
		(drill 0.3556)
		(layers "F.Cu" "B.Cu")
		(net "GND")
	)
	(via
		(at 43.40098 -125.03658)
		(size 0.508)
		(drill 0.254)
		(layers "F.Cu" "B.Cu")
		(net "GND")
	)
	(via
		(at 155.964128 -8.459978)
		(size 0.7112)
		(drill 0.4064)
		(layers "F.Cu" "B.Cu")
		(net "GND")
	)
	(via
		(at 91.186 -161.4424)
		(size 0.508)
		(drill 0.254)
		(layers "F.Cu" "B.Cu")
		(net "GND")
	)
	(via
		(at 2.162556 -78.890622)
		(size 0.7112)
		(drill 0.4064)
		(layers "F.Cu" "B.Cu")
		(net "GND")
	)
	(via
		(at 216.77249 -24.14524)
		(size 0.7112)
		(drill 0.4064)
		(layers "F.Cu" "B.Cu")
		(net "GND")
	)
	(via
		(at 232.837482 -179.673758)
		(size 0.7112)
		(drill 0.4064)
		(layers "F.Cu" "B.Cu")
		(net "GND")
	)
	(via
		(at 232.837482 -41.243758)
		(size 0.7112)
		(drill 0.4064)
		(layers "F.Cu" "B.Cu")
		(net "GND")
	)
	(via
		(at 49.299876 -136.99998)
		(size 0.4572)
		(drill 0.2032)
		(layers "F.Cu" "B.Cu")
		(net "GND")
	)
	(via
		(at 187.97651 -62.48019)
		(size 0.7112)
		(drill 0.4064)
		(layers "F.Cu" "B.Cu")
		(net "GND")
	)
	(via
		(at 76.38288 -179.04968)
		(size 0.5588)
		(drill 0.3048)
		(layers "F.Cu" "B.Cu")
		(net "GND")
	)
	(via
		(at 2.162556 -139.850622)
		(size 0.7112)
		(drill 0.4064)
		(layers "F.Cu" "B.Cu")
		(net "GND")
	)
	(via
		(at 2.162556 -176.680622)
		(size 0.7112)
		(drill 0.4064)
		(layers "F.Cu" "B.Cu")
		(net "GND")
	)
	(via
		(at 187.97651 -32.00019)
		(size 0.7112)
		(drill 0.4064)
		(layers "F.Cu" "B.Cu")
		(net "GND")
	)
	(via
		(at 66.71183 -180.88737)
		(size 0.508)
		(drill 0.254)
		(layers "F.Cu" "B.Cu")
		(net "GND")
	)
	(via
		(at 199.528684 -2.162556)
		(size 0.7112)
		(drill 0.4064)
		(layers "F.Cu" "B.Cu")
		(net "GND")
	)
	(via
		(at 195.59651 -105.66019)
		(size 0.7112)
		(drill 0.4064)
		(layers "F.Cu" "B.Cu")
		(net "GND")
	)
	(via
		(at 146.462496 -56.69407)
		(size 0.7112)
		(drill 0.4064)
		(layers "F.Cu" "B.Cu")
		(net "GND")
	)
	(via
		(at 190.51651 -103.12019)
		(size 0.7112)
		(drill 0.4064)
		(layers "F.Cu" "B.Cu")
		(net "GND")
	)
	(via
		(at 2.162556 -82.700622)
		(size 0.7112)
		(drill 0.4064)
		(layers "F.Cu" "B.Cu")
		(net "GND")
	)
	(via
		(at 28.367482 -41.469564)
		(size 0.7112)
		(drill 0.4064)
		(layers "F.Cu" "B.Cu")
		(net "GND")
	)
	(via
		(at 19.41449 -2.162556)
		(size 0.7112)
		(drill 0.4064)
		(layers "F.Cu" "B.Cu")
		(net "GND")
	)
	(via
		(at 195.59651 -115.82019)
		(size 0.7112)
		(drill 0.4064)
		(layers "F.Cu" "B.Cu")
		(net "GND")
	)
	(via
		(at 55.5752 -161.4424)
		(size 0.508)
		(drill 0.254)
		(layers "F.Cu" "B.Cu")
		(net "GND")
	)
	(via
		(at 28.367482 -96.079564)
		(size 0.7112)
		(drill 0.4064)
		(layers "F.Cu" "B.Cu")
		(net "GND")
	)
	(via
		(at 15.60449 -2.162556)
		(size 0.7112)
		(drill 0.4064)
		(layers "F.Cu" "B.Cu")
		(net "GND")
	)
	(via
		(at 195.59651 -14.22019)
		(size 0.7112)
		(drill 0.4064)
		(layers "F.Cu" "B.Cu")
		(net "GND")
	)
	(via
		(at 185.43651 -90.42019)
		(size 0.7112)
		(drill 0.4064)
		(layers "F.Cu" "B.Cu")
		(net "GND")
	)
	(via
		(at 66.2559 -153.298398)
		(size 0.508)
		(drill 0.254)
		(layers "F.Cu" "B.Cu")
		(net "GND")
	)
	(via
		(at 183.1594 -112.2934)
		(size 0.508)
		(drill 0.254)
		(layers "F.Cu" "B.Cu")
		(net "GND")
	)
	(via
		(at 208.29651 -75.18019)
		(size 0.7112)
		(drill 0.4064)
		(layers "F.Cu" "B.Cu")
		(net "GND")
	)
	(via
		(at 177.81651 -32.00019)
		(size 0.7112)
		(drill 0.4064)
		(layers "F.Cu" "B.Cu")
		(net "GND")
	)
	(via
		(at 195.59651 -19.30019)
		(size 0.7112)
		(drill 0.4064)
		(layers "F.Cu" "B.Cu")
		(net "GND")
	)
	(via
		(at 86.66734 -153.01468)
		(size 0.508)
		(drill 0.254)
		(layers "F.Cu" "B.Cu")
		(net "GND")
	)
	(via
		(at 199.63765 -157.837378)
		(size 0.7112)
		(drill 0.4064)
		(layers "F.Cu" "B.Cu")
		(net "GND")
	)
	(via
		(at 2.162556 -89.050622)
		(size 0.7112)
		(drill 0.4064)
		(layers "F.Cu" "B.Cu")
		(net "GND")
	)
	(via
		(at 2.162556 -103.020622)
		(size 0.7112)
		(drill 0.4064)
		(layers "F.Cu" "B.Cu")
		(net "GND")
	)
	(via
		(at 47.712376 -145.81251)
		(size 0.4572)
		(drill 0.2032)
		(layers "F.Cu" "B.Cu")
		(net "GND")
	)
	(via
		(at 193.720466 -136.026398)
		(size 0.508)
		(drill 0.254)
		(layers "F.Cu" "B.Cu")
		(net "GND")
	)
	(via
		(at 205.75651 -65.02019)
		(size 0.7112)
		(drill 0.4064)
		(layers "F.Cu" "B.Cu")
		(net "GND")
	)
	(via
		(at 2.162556 -137.310622)
		(size 0.7112)
		(drill 0.4064)
		(layers "F.Cu" "B.Cu")
		(net "GND")
	)
	(via
		(at 187.97651 -65.02019)
		(size 0.7112)
		(drill 0.4064)
		(layers "F.Cu" "B.Cu")
		(net "GND")
	)
	(via
		(at 232.837482 -165.703758)
		(size 0.7112)
		(drill 0.4064)
		(layers "F.Cu" "B.Cu")
		(net "GND")
	)
	(via
		(at 84.537296 -173.80458)
		(size 0.508)
		(drill 0.254)
		(layers "F.Cu" "B.Cu")
		(net "GND")
	)
	(via
		(at 96.647 -8.509)
		(size 0.508)
		(drill 0.254)
		(layers "F.Cu" "B.Cu")
		(net "GND")
	)
	(via
		(at 77.84338 -188.86678)
		(size 0.508)
		(drill 0.254)
		(layers "F.Cu" "B.Cu")
		(net "GND")
	)
	(via
		(at 180.35651 -87.88019)
		(size 0.7112)
		(drill 0.4064)
		(layers "F.Cu" "B.Cu")
		(net "GND")
	)
	(via
		(at 196.8754 -137.16)
		(size 0.6096)
		(drill 0.3048)
		(layers "F.Cu" "B.Cu")
		(net "GND")
	)
	(via
		(at 195.59651 -113.28019)
		(size 0.7112)
		(drill 0.4064)
		(layers "F.Cu" "B.Cu")
		(net "GND")
	)
	(via
		(at 2.162556 -81.430622)
		(size 0.7112)
		(drill 0.4064)
		(layers "F.Cu" "B.Cu")
		(net "GND")
	)
	(via
		(at 195.59651 -49.78019)
		(size 0.7112)
		(drill 0.4064)
		(layers "F.Cu" "B.Cu")
		(net "GND")
	)
	(via
		(at 223.754188 -16.183356)
		(size 0.7112)
		(drill 0.4064)
		(layers "F.Cu" "B.Cu")
		(net "GND")
	)
	(via
		(at 58.1406 -161.4932)
		(size 0.508)
		(drill 0.254)
		(layers "F.Cu" "B.Cu")
		(net "GND")
	)
	(via
		(at 232.837482 -137.763758)
		(size 0.7112)
		(drill 0.4064)
		(layers "F.Cu" "B.Cu")
		(net "GND")
	)
	(via
		(at 28.367482 -54.169564)
		(size 0.7112)
		(drill 0.4064)
		(layers "F.Cu" "B.Cu")
		(net "GND")
	)
	(via
		(at 49.299622 -145.800064)
		(size 0.4572)
		(drill 0.2032)
		(layers "F.Cu" "B.Cu")
		(net "GND")
	)
	(via
		(at 2.162556 -122.070622)
		(size 0.7112)
		(drill 0.4064)
		(layers "F.Cu" "B.Cu")
		(net "GND")
	)
	(via
		(at 94.3102 -157.1752)
		(size 0.5588)
		(drill 0.3048)
		(layers "F.Cu" "B.Cu")
		(net "GND")
	)
	(via
		(at 18.737072 -17.69237)
		(size 0.508)
		(drill 0.254)
		(layers "F.Cu" "B.Cu")
		(net "GND")
	)
	(via
		(at 56.28005 -176.6316)
		(size 0.508)
		(drill 0.254)
		(layers "F.Cu" "B.Cu")
		(net "GND")
	)
	(via
		(at 29.56433 -191.837564)
		(size 0.7112)
		(drill 0.4064)
		(layers "F.Cu" "B.Cu")
		(net "GND")
	)
	(via
		(at 193.05651 -85.34019)
		(size 0.7112)
		(drill 0.4064)
		(layers "F.Cu" "B.Cu")
		(net "GND")
	)
	(via
		(at 64.526922 -151.983186)
		(size 0.508)
		(drill 0.254)
		(layers "F.Cu" "B.Cu")
		(net "GND")
	)
	(via
		(at 190.51651 -113.28019)
		(size 0.7112)
		(drill 0.4064)
		(layers "F.Cu" "B.Cu")
		(net "GND")
	)
	(via
		(at 101.537516 -180.612034)
		(size 0.7112)
		(drill 0.4064)
		(layers "F.Cu" "B.Cu")
		(net "GND")
	)
	(via
		(at 232.837482 -66.643758)
		(size 0.7112)
		(drill 0.4064)
		(layers "F.Cu" "B.Cu")
		(net "GND")
	)
	(via
		(at 75.192636 -4.826508)
		(size 0.7112)
		(drill 0.4064)
		(layers "F.Cu" "B.Cu")
		(net "GND")
	)
	(via
		(at 205.75651 -34.54019)
		(size 0.7112)
		(drill 0.4064)
		(layers "F.Cu" "B.Cu")
		(net "GND")
	)
	(via
		(at 81.758028 -74.135996)
		(size 0.508)
		(drill 0.254)
		(layers "F.Cu" "B.Cu")
		(net "GND")
	)
	(via
		(at 199.0852 -107.3912)
		(size 0.508)
		(drill 0.254)
		(layers "F.Cu" "B.Cu")
		(net "GND")
	)
	(via
		(at 200.90765 -157.837378)
		(size 0.7112)
		(drill 0.4064)
		(layers "F.Cu" "B.Cu")
		(net "GND")
	)
	(via
		(at 101.537516 -181.882034)
		(size 0.7112)
		(drill 0.4064)
		(layers "F.Cu" "B.Cu")
		(net "GND")
	)
	(via
		(at 4.797044 -188.758576)
		(size 0.7112)
		(drill 0.4064)
		(layers "F.Cu" "B.Cu")
		(net "GND")
	)
	(via
		(at 2.162556 -115.720622)
		(size 0.7112)
		(drill 0.4064)
		(layers "F.Cu" "B.Cu")
		(net "GND")
	)
	(via
		(at 2.162556 -101.750622)
		(size 0.7112)
		(drill 0.4064)
		(layers "F.Cu" "B.Cu")
		(net "GND")
	)
	(via
		(at 90.805 -26.4668)
		(size 0.508)
		(drill 0.254)
		(layers "F.Cu" "B.Cu")
		(net "GND")
	)
	(via
		(at 226.192588 -16.183356)
		(size 0.7112)
		(drill 0.4064)
		(layers "F.Cu" "B.Cu")
		(net "GND")
	)
	(via
		(at 203.21651 -32.00019)
		(size 0.7112)
		(drill 0.4064)
		(layers "F.Cu" "B.Cu")
		(net "GND")
	)
	(via
		(at 185.43651 -80.26019)
		(size 0.7112)
		(drill 0.4064)
		(layers "F.Cu" "B.Cu")
		(net "GND")
	)
	(via
		(at 84.0232 -153.06294)
		(size 0.508)
		(drill 0.254)
		(layers "F.Cu" "B.Cu")
		(net "GND")
	)
	(via
		(at 35.538664 -180.193188)
		(size 0.5588)
		(drill 0.3048)
		(layers "F.Cu" "B.Cu")
		(net "GND")
	)
	(via
		(at 77.608684 -2.162556)
		(size 0.7112)
		(drill 0.4064)
		(layers "F.Cu" "B.Cu")
		(net "GND")
	)
	(via
		(at 183.12765 -157.837378)
		(size 0.7112)
		(drill 0.4064)
		(layers "F.Cu" "B.Cu")
		(net "GND")
	)
	(via
		(at 2.162556 -48.410622)
		(size 0.7112)
		(drill 0.4064)
		(layers "F.Cu" "B.Cu")
		(net "GND")
	)
	(via
		(at 90.3478 -129.54)
		(size 0.508)
		(drill 0.254)
		(layers "F.Cu" "B.Cu")
		(net "GND")
	)
	(via
		(at 198.13651 -75.18019)
		(size 0.7112)
		(drill 0.4064)
		(layers "F.Cu" "B.Cu")
		(net "GND")
	)
	(via
		(at 85.09 -154.9908)
		(size 0.7112)
		(drill 0.4064)
		(layers "F.Cu" "B.Cu")
		(net "GND")
	)
	(via
		(at 195.59651 -62.48019)
		(size 0.7112)
		(drill 0.4064)
		(layers "F.Cu" "B.Cu")
		(net "GND")
	)
	(via
		(at 77.847444 -163.5125)
		(size 0.5588)
		(drill 0.3048)
		(layers "F.Cu" "B.Cu")
		(net "GND")
	)
	(via
		(at 177.81651 -62.48019)
		(size 0.7112)
		(drill 0.4064)
		(layers "F.Cu" "B.Cu")
		(net "GND")
	)
	(via
		(at 232.837482 -29.813758)
		(size 0.7112)
		(drill 0.4064)
		(layers "F.Cu" "B.Cu")
		(net "GND")
	)
	(via
		(at 97.188274 -12.2428)
		(size 0.508)
		(drill 0.254)
		(layers "F.Cu" "B.Cu")
		(net "GND")
	)
	(via
		(at 44.80433 -191.837564)
		(size 0.7112)
		(drill 0.4064)
		(layers "F.Cu" "B.Cu")
		(net "GND")
	)
	(via
		(at 87.99576 -133.985)
		(size 0.508)
		(drill 0.254)
		(layers "F.Cu" "B.Cu")
		(net "GND")
	)
	(via
		(at 7.406132 -138.13917)
		(size 0.508)
		(drill 0.254)
		(layers "F.Cu" "B.Cu")
		(net "GND")
	)
	(via
		(at 168.529 -124.206)
		(size 0.7112)
		(drill 0.4064)
		(layers "F.Cu" "B.Cu")
		(net "GND")
	)
	(via
		(at 221.34068 -98.240088)
		(size 0.5588)
		(drill 0.3048)
		(layers "F.Cu" "B.Cu")
		(net "GND")
	)
	(via
		(at 195.59651 -85.34019)
		(size 0.7112)
		(drill 0.4064)
		(layers "F.Cu" "B.Cu")
		(net "GND")
	)
	(via
		(at 2.162556 -31.900622)
		(size 0.7112)
		(drill 0.4064)
		(layers "F.Cu" "B.Cu")
		(net "GND")
	)
	(via
		(at 177.81651 -103.12019)
		(size 0.7112)
		(drill 0.4064)
		(layers "F.Cu" "B.Cu")
		(net "GND")
	)
	(via
		(at 190.51651 -82.80019)
		(size 0.7112)
		(drill 0.4064)
		(layers "F.Cu" "B.Cu")
		(net "GND")
	)
	(via
		(at 232.837482 -70.453758)
		(size 0.7112)
		(drill 0.4064)
		(layers "F.Cu" "B.Cu")
		(net "GND")
	)
	(via
		(at 195.59651 -75.18019)
		(size 0.7112)
		(drill 0.4064)
		(layers "F.Cu" "B.Cu")
		(net "GND")
	)
	(via
		(at 51.15433 -191.837564)
		(size 0.7112)
		(drill 0.4064)
		(layers "F.Cu" "B.Cu")
		(net "GND")
	)
	(via
		(at 195.59651 -47.24019)
		(size 0.7112)
		(drill 0.4064)
		(layers "F.Cu" "B.Cu")
		(net "GND")
	)
	(via
		(at 2.162556 -170.330622)
		(size 0.7112)
		(drill 0.4064)
		(layers "F.Cu" "B.Cu")
		(net "GND")
	)
	(via
		(at 16.691356 -169.1259)
		(size 0.5588)
		(drill 0.3048)
		(layers "F.Cu" "B.Cu")
		(net "GND")
	)
	(via
		(at 49.9618 -179.06619)
		(size 0.7112)
		(drill 0.4064)
		(layers "F.Cu" "B.Cu")
		(net "GND")
	)
	(via
		(at 74.01433 -191.837564)
		(size 0.7112)
		(drill 0.4064)
		(layers "F.Cu" "B.Cu")
		(net "GND")
	)
	(via
		(at 2.162556 -167.790622)
		(size 0.7112)
		(drill 0.4064)
		(layers "F.Cu" "B.Cu")
		(net "GND")
	)
	(via
		(at 42.900092 -149.800056)
		(size 0.4572)
		(drill 0.2032)
		(layers "F.Cu" "B.Cu")
		(net "GND")
	)
	(via
		(at 2.162556 -108.100622)
		(size 0.7112)
		(drill 0.4064)
		(layers "F.Cu" "B.Cu")
		(net "GND")
	)
	(via
		(at 31.2674 -164.338)
		(size 0.508)
		(drill 0.254)
		(layers "F.Cu" "B.Cu")
		(net "GND")
	)
	(via
		(at 190.51651 -85.34019)
		(size 0.7112)
		(drill 0.4064)
		(layers "F.Cu" "B.Cu")
		(net "GND")
	)
	(via
		(at 221.34068 -97.325688)
		(size 0.5588)
		(drill 0.3048)
		(layers "F.Cu" "B.Cu")
		(net "GND")
	)
	(via
		(at 232.837482 -37.433758)
		(size 0.7112)
		(drill 0.4064)
		(layers "F.Cu" "B.Cu")
		(net "GND")
	)
	(via
		(at 209.79765 -157.837378)
		(size 0.7112)
		(drill 0.4064)
		(layers "F.Cu" "B.Cu")
		(net "GND")
	)
	(via
		(at 180.24475 -70.101714)
		(size 0.7112)
		(drill 0.4064)
		(layers "F.Cu" "B.Cu")
		(net "GND")
	)
	(via
		(at 219.51188 -96.411288)
		(size 0.5588)
		(drill 0.3048)
		(layers "F.Cu" "B.Cu")
		(net "GND")
	)
	(via
		(at 153.401522 -11.939524)
		(size 0.5588)
		(drill 0.3048)
		(layers "F.Cu" "B.Cu")
		(net "GND")
	)
	(via
		(at 195.59651 -110.74019)
		(size 0.7112)
		(drill 0.4064)
		(layers "F.Cu" "B.Cu")
		(net "GND")
	)
	(via
		(at 216.772744 -28.884118)
		(size 0.7112)
		(drill 0.4064)
		(layers "F.Cu" "B.Cu")
		(net "GND")
	)
	(via
		(at 146.462496 -103.68407)
		(size 0.7112)
		(drill 0.4064)
		(layers "F.Cu" "B.Cu")
		(net "GND")
	)
	(via
		(at 185.43651 -39.62019)
		(size 0.7112)
		(drill 0.4064)
		(layers "F.Cu" "B.Cu")
		(net "GND")
	)
	(via
		(at 80.36433 -191.837564)
		(size 0.7112)
		(drill 0.4064)
		(layers "F.Cu" "B.Cu")
		(net "GND")
	)
	(via
		(at 193.05651 -98.04019)
		(size 0.7112)
		(drill 0.4064)
		(layers "F.Cu" "B.Cu")
		(net "GND")
	)
	(via
		(at 42.099992 -141.800072)
		(size 0.4572)
		(drill 0.2032)
		(layers "F.Cu" "B.Cu")
		(net "GND")
	)
	(via
		(at 28.367482 -59.249564)
		(size 0.7112)
		(drill 0.4064)
		(layers "F.Cu" "B.Cu")
		(net "GND")
	)
	(via
		(at 190.51651 -90.42019)
		(size 0.7112)
		(drill 0.4064)
		(layers "F.Cu" "B.Cu")
		(net "GND")
	)
	(via
		(at 53.7718 -179.06619)
		(size 0.7112)
		(drill 0.4064)
		(layers "F.Cu" "B.Cu")
		(net "GND")
	)
	(via
		(at 59.436 -159.6136)
		(size 0.508)
		(drill 0.254)
		(layers "F.Cu" "B.Cu")
		(net "GND")
	)
	(via
		(at 232.837482 -173.323758)
		(size 0.7112)
		(drill 0.4064)
		(layers "F.Cu" "B.Cu")
		(net "GND")
	)
	(via
		(at 200.67651 -118.36019)
		(size 0.7112)
		(drill 0.4064)
		(layers "F.Cu" "B.Cu")
		(net "GND")
	)
	(via
		(at 146.462496 -139.24407)
		(size 0.7112)
		(drill 0.4064)
		(layers "F.Cu" "B.Cu")
		(net "GND")
	)
	(via
		(at 35.538664 -183.850788)
		(size 0.5588)
		(drill 0.3048)
		(layers "F.Cu" "B.Cu")
		(net "GND")
	)
	(via
		(at 226.776788 -15.040356)
		(size 0.7112)
		(drill 0.4064)
		(layers "F.Cu" "B.Cu")
		(net "GND")
	)
	(via
		(at 2.162556 -42.060622)
		(size 0.7112)
		(drill 0.4064)
		(layers "F.Cu" "B.Cu")
		(net "GND")
	)
	(via
		(at 181.8894 -112.2934)
		(size 0.508)
		(drill 0.254)
		(layers "F.Cu" "B.Cu")
		(net "GND")
	)
	(via
		(at 169.15765 -157.837378)
		(size 0.7112)
		(drill 0.4064)
		(layers "F.Cu" "B.Cu")
		(net "GND")
	)
	(via
		(at 17.9832 -167.8178)
		(size 0.5588)
		(drill 0.3048)
		(layers "F.Cu" "B.Cu")
		(net "GND")
	)
	(via
		(at 101.6 -40.4368)
		(size 0.508)
		(drill 0.254)
		(layers "F.Cu" "B.Cu")
		(net "GND")
	)
	(via
		(at 232.837482 -71.723758)
		(size 0.7112)
		(drill 0.4064)
		(layers "F.Cu" "B.Cu")
		(net "GND")
	)
	(via
		(at 146.462496 -112.57407)
		(size 0.7112)
		(drill 0.4064)
		(layers "F.Cu" "B.Cu")
		(net "GND")
	)
	(via
		(at 53.69433 -191.837564)
		(size 0.7112)
		(drill 0.4064)
		(layers "F.Cu" "B.Cu")
		(net "GND")
	)
	(via
		(at 28.367482 -17.339564)
		(size 0.7112)
		(drill 0.4064)
		(layers "F.Cu" "B.Cu")
		(net "GND")
	)
	(via
		(at 13.06449 -2.162556)
		(size 0.7112)
		(drill 0.4064)
		(layers "F.Cu" "B.Cu")
		(net "GND")
	)
	(via
		(at 181.748684 -2.162556)
		(size 0.7112)
		(drill 0.4064)
		(layers "F.Cu" "B.Cu")
		(net "GND")
	)
	(via
		(at 200.67651 -103.12019)
		(size 0.7112)
		(drill 0.4064)
		(layers "F.Cu" "B.Cu")
		(net "GND")
	)
	(via
		(at 112.499902 -45.600112)
		(size 0.6604)
		(drill 0.3556)
		(layers "F.Cu" "B.Cu")
		(net "GND")
	)
	(via
		(at 33.024826 -183.92013)
		(size 0.5588)
		(drill 0.3048)
		(layers "F.Cu" "B.Cu")
		(net "GND")
	)
	(via
		(at 187.97651 -100.58019)
		(size 0.7112)
		(drill 0.4064)
		(layers "F.Cu" "B.Cu")
		(net "GND")
	)
	(via
		(at 187.97651 -52.32019)
		(size 0.7112)
		(drill 0.4064)
		(layers "F.Cu" "B.Cu")
		(net "GND")
	)
	(via
		(at 2.162556 -169.060622)
		(size 0.7112)
		(drill 0.4064)
		(layers "F.Cu" "B.Cu")
		(net "GND")
	)
	(via
		(at 192.01765 -157.837378)
		(size 0.7112)
		(drill 0.4064)
		(layers "F.Cu" "B.Cu")
		(net "GND")
	)
	(via
		(at 201.041 -85.344)
		(size 0.7112)
		(drill 0.4064)
		(layers "F.Cu" "B.Cu")
		(net "GND")
	)
	(via
		(at 62.92215 -166.71925)
		(size 0.508)
		(drill 0.254)
		(layers "F.Cu" "B.Cu")
		(net "GND")
	)
	(via
		(at 85.070442 -147.307046)
		(size 0.508)
		(drill 0.254)
		(layers "F.Cu" "B.Cu")
		(net "GND")
	)
	(via
		(at 17.9578 -170.434)
		(size 0.5588)
		(drill 0.3048)
		(layers "F.Cu" "B.Cu")
		(net "GND")
	)
	(via
		(at 187.97651 -26.92019)
		(size 0.7112)
		(drill 0.4064)
		(layers "F.Cu" "B.Cu")
		(net "GND")
	)
	(via
		(at 187.97651 -105.66019)
		(size 0.7112)
		(drill 0.4064)
		(layers "F.Cu" "B.Cu")
		(net "GND")
	)
	(via
		(at 185.43651 -77.72019)
		(size 0.7112)
		(drill 0.4064)
		(layers "F.Cu" "B.Cu")
		(net "GND")
	)
	(via
		(at 64.724534 -159.258)
		(size 0.508)
		(drill 0.254)
		(layers "F.Cu" "B.Cu")
		(net "GND")
	)
	(via
		(at 146.462496 -87.17407)
		(size 0.7112)
		(drill 0.4064)
		(layers "F.Cu" "B.Cu")
		(net "GND")
	)
	(via
		(at 201.649838 -136.25449)
		(size 0.508)
		(drill 0.254)
		(layers "F.Cu" "B.Cu")
		(net "GND")
	)
	(via
		(at 21.95449 -2.162556)
		(size 0.7112)
		(drill 0.4064)
		(layers "F.Cu" "B.Cu")
		(net "GND")
	)
	(via
		(at 82.255868 -55.698136)
		(size 0.508)
		(drill 0.254)
		(layers "F.Cu" "B.Cu")
		(net "GND")
	)
	(via
		(at 2.162556 -111.910622)
		(size 0.7112)
		(drill 0.4064)
		(layers "F.Cu" "B.Cu")
		(net "GND")
	)
	(via
		(at 100.552504 -185.459624)
		(size 0.7112)
		(drill 0.4064)
		(layers "F.Cu" "B.Cu")
		(net "GND")
	)
	(via
		(at 195.59651 -16.76019)
		(size 0.7112)
		(drill 0.4064)
		(layers "F.Cu" "B.Cu")
		(net "GND")
	)
	(via
		(at 146.462496 -68.12407)
		(size 0.7112)
		(drill 0.4064)
		(layers "F.Cu" "B.Cu")
		(net "GND")
	)
	(via
		(at 33.3248 -157.6324)
		(size 0.508)
		(drill 0.254)
		(layers "F.Cu" "B.Cu")
		(net "GND")
	)
	(via
		(at 3.093212 -185.350912)
		(size 0.7112)
		(drill 0.4064)
		(layers "F.Cu" "B.Cu")
		(net "GND")
	)
	(via
		(at 42.291 -162.6362)
		(size 0.508)
		(drill 0.254)
		(layers "F.Cu" "B.Cu")
		(net "GND")
	)
	(via
		(at 232.837482 -139.033758)
		(size 0.7112)
		(drill 0.4064)
		(layers "F.Cu" "B.Cu")
		(net "GND")
	)
	(via
		(at 231.278684 -2.162556)
		(size 0.7112)
		(drill 0.4064)
		(layers "F.Cu" "B.Cu")
		(net "GND")
	)
	(via
		(at 190.51651 -62.48019)
		(size 0.7112)
		(drill 0.4064)
		(layers "F.Cu" "B.Cu")
		(net "GND")
	)
	(via
		(at 26.993088 -139.03198)
		(size 0.508)
		(drill 0.254)
		(layers "F.Cu" "B.Cu")
		(net "GND")
	)
	(via
		(at 180.35651 -85.34019)
		(size 0.7112)
		(drill 0.4064)
		(layers "F.Cu" "B.Cu")
		(net "GND")
	)
	(via
		(at 70.20433 -191.837564)
		(size 0.7112)
		(drill 0.4064)
		(layers "F.Cu" "B.Cu")
		(net "GND")
	)
	(via
		(at 232.837482 -90.773758)
		(size 0.7112)
		(drill 0.4064)
		(layers "F.Cu" "B.Cu")
		(net "GND")
	)
	(via
		(at 53.0098 -134.3914)
		(size 0.508)
		(drill 0.254)
		(layers "F.Cu" "B.Cu")
		(net "GND")
	)
	(via
		(at 187.97651 -44.70019)
		(size 0.7112)
		(drill 0.4064)
		(layers "F.Cu" "B.Cu")
		(net "GND")
	)
	(via
		(at 232.837482 -119.983758)
		(size 0.7112)
		(drill 0.4064)
		(layers "F.Cu" "B.Cu")
		(net "GND")
	)
	(via
		(at 187.97651 -113.28019)
		(size 0.7112)
		(drill 0.4064)
		(layers "F.Cu" "B.Cu")
		(net "GND")
	)
	(via
		(at 185.43651 -37.08019)
		(size 0.7112)
		(drill 0.4064)
		(layers "F.Cu" "B.Cu")
		(net "GND")
	)
	(via
		(at 146.462496 -127.81407)
		(size 0.7112)
		(drill 0.4064)
		(layers "F.Cu" "B.Cu")
		(net "GND")
	)
	(via
		(at 2.162556 -73.810622)
		(size 0.7112)
		(drill 0.4064)
		(layers "F.Cu" "B.Cu")
		(net "GND")
	)
	(via
		(at 25.231598 -172.404024)
		(size 0.7112)
		(drill 0.4064)
		(layers "F.Cu" "B.Cu")
		(net "GND")
	)
	(via
		(at 63.85433 -191.837564)
		(size 0.7112)
		(drill 0.4064)
		(layers "F.Cu" "B.Cu")
		(net "GND")
	)
	(via
		(at 146.462496 -107.49407)
		(size 0.7112)
		(drill 0.4064)
		(layers "F.Cu" "B.Cu")
		(net "GND")
	)
	(via
		(at 203.21651 -39.62019)
		(size 0.7112)
		(drill 0.4064)
		(layers "F.Cu" "B.Cu")
		(net "GND")
	)
	(via
		(at 232.837482 -14.573758)
		(size 0.7112)
		(drill 0.4064)
		(layers "F.Cu" "B.Cu")
		(net "GND")
	)
	(via
		(at 180.739796 -72.64019)
		(size 0.7112)
		(drill 0.4064)
		(layers "F.Cu" "B.Cu")
		(net "GND")
	)
	(via
		(at 232.837482 -45.053758)
		(size 0.7112)
		(drill 0.4064)
		(layers "F.Cu" "B.Cu")
		(net "GND")
	)
	(via
		(at 198.13651 -39.62019)
		(size 0.7112)
		(drill 0.4064)
		(layers "F.Cu" "B.Cu")
		(net "GND")
	)
	(via
		(at 195.59651 -82.80019)
		(size 0.7112)
		(drill 0.4064)
		(layers "F.Cu" "B.Cu")
		(net "GND")
	)
	(via
		(at 28.2702 -179.197)
		(size 0.508)
		(drill 0.254)
		(layers "F.Cu" "B.Cu")
		(net "GND")
	)
	(via
		(at 227.49891 -104.353614)
		(size 0.7112)
		(drill 0.4064)
		(layers "F.Cu" "B.Cu")
		(net "GND")
	)
	(via
		(at 189.368684 -2.162556)
		(size 0.7112)
		(drill 0.4064)
		(layers "F.Cu" "B.Cu")
		(net "GND")
	)
	(via
		(at 28.367482 -5.909564)
		(size 0.7112)
		(drill 0.4064)
		(layers "F.Cu" "B.Cu")
		(net "GND")
	)
	(via
		(at 185.43651 -67.56019)
		(size 0.7112)
		(drill 0.4064)
		(layers "F.Cu" "B.Cu")
		(net "GND")
	)
	(via
		(at 228.85273 -73.840848)
		(size 0.7112)
		(drill 0.4064)
		(layers "F.Cu" "B.Cu")
		(net "GND")
	)
	(via
		(at 2.162556 -72.540622)
		(size 0.7112)
		(drill 0.4064)
		(layers "F.Cu" "B.Cu")
		(net "GND")
	)
	(via
		(at 81.605374 -67.687444)
		(size 0.508)
		(drill 0.254)
		(layers "F.Cu" "B.Cu")
		(net "GND")
	)
	(via
		(at 232.837482 -99.663758)
		(size 0.7112)
		(drill 0.4064)
		(layers "F.Cu" "B.Cu")
		(net "GND")
	)
	(via
		(at 180.58765 -157.837378)
		(size 0.7112)
		(drill 0.4064)
		(layers "F.Cu" "B.Cu")
		(net "GND")
	)
	(via
		(at 203.21651 -70.10019)
		(size 0.7112)
		(drill 0.4064)
		(layers "F.Cu" "B.Cu")
		(net "GND")
	)
	(via
		(at 146.462496 -111.30407)
		(size 0.7112)
		(drill 0.4064)
		(layers "F.Cu" "B.Cu")
		(net "GND")
	)
	(via
		(at 59.7154 -172.699934)
		(size 0.508)
		(drill 0.254)
		(layers "F.Cu" "B.Cu")
		(net "GND")
	)
	(via
		(at 200.67651 -37.08019)
		(size 0.7112)
		(drill 0.4064)
		(layers "F.Cu" "B.Cu")
		(net "GND")
	)
	(via
		(at 217.162634 -174.577502)
		(size 0.7112)
		(drill 0.4064)
		(layers "F.Cu" "B.Cu")
		(net "GND")
	)
	(via
		(at 2.162556 -10.310622)
		(size 0.7112)
		(drill 0.4064)
		(layers "F.Cu" "B.Cu")
		(net "GND")
	)
	(via
		(at 26.7589 -130.0099)
		(size 0.508)
		(drill 0.254)
		(layers "F.Cu" "B.Cu")
		(net "GND")
	)
	(via
		(at 217.162634 -168.227502)
		(size 0.7112)
		(drill 0.4064)
		(layers "F.Cu" "B.Cu")
		(net "GND")
	)
	(via
		(at 28.367482 -89.729564)
		(size 0.7112)
		(drill 0.4064)
		(layers "F.Cu" "B.Cu")
		(net "GND")
	)
	(via
		(at 95.3262 -18.3007)
		(size 0.508)
		(drill 0.254)
		(layers "F.Cu" "B.Cu")
		(net "GND")
	)
	(via
		(at 198.13651 -24.38019)
		(size 0.7112)
		(drill 0.4064)
		(layers "F.Cu" "B.Cu")
		(net "GND")
	)
	(via
		(at 28.367482 -74.489564)
		(size 0.7112)
		(drill 0.4064)
		(layers "F.Cu" "B.Cu")
		(net "GND")
	)
	(via
		(at 202.17765 -157.837378)
		(size 0.7112)
		(drill 0.4064)
		(layers "F.Cu" "B.Cu")
		(net "GND")
	)
	(via
		(at 195.59651 -21.84019)
		(size 0.7112)
		(drill 0.4064)
		(layers "F.Cu" "B.Cu")
		(net "GND")
	)
	(via
		(at 28.367482 -55.439564)
		(size 0.7112)
		(drill 0.4064)
		(layers "F.Cu" "B.Cu")
		(net "GND")
	)
	(via
		(at 2.162556 -20.470622)
		(size 0.7112)
		(drill 0.4064)
		(layers "F.Cu" "B.Cu")
		(net "GND")
	)
	(via
		(at 182.89651 -29.46019)
		(size 0.7112)
		(drill 0.4064)
		(layers "F.Cu" "B.Cu")
		(net "GND")
	)
	(via
		(at 28.367482 -45.279564)
		(size 0.7112)
		(drill 0.4064)
		(layers "F.Cu" "B.Cu")
		(net "GND")
	)
	(via
		(at 229.15753 -70.024752)
		(size 0.7112)
		(drill 0.4064)
		(layers "F.Cu" "B.Cu")
		(net "GND")
	)
	(via
		(at 196.988684 -2.162556)
		(size 0.7112)
		(drill 0.4064)
		(layers "F.Cu" "B.Cu")
		(net "GND")
	)
	(via
		(at 81.418684 -2.162556)
		(size 0.7112)
		(drill 0.4064)
		(layers "F.Cu" "B.Cu")
		(net "GND")
	)
	(via
		(at 205.75651 -82.80019)
		(size 0.7112)
		(drill 0.4064)
		(layers "F.Cu" "B.Cu")
		(net "GND")
	)
	(via
		(at 178.150012 -133.225794)
		(size 0.508)
		(drill 0.254)
		(layers "F.Cu" "B.Cu")
		(net "GND")
	)
	(via
		(at 162.80765 -157.837378)
		(size 0.7112)
		(drill 0.4064)
		(layers "F.Cu" "B.Cu")
		(net "GND")
	)
	(via
		(at 2.162556 -90.320622)
		(size 0.7112)
		(drill 0.4064)
		(layers "F.Cu" "B.Cu")
		(net "GND")
	)
	(via
		(at 77.2414 -169.291)
		(size 0.508)
		(drill 0.254)
		(layers "F.Cu" "B.Cu")
		(net "GND")
	)
	(via
		(at 2.162556 -125.880622)
		(size 0.7112)
		(drill 0.4064)
		(layers "F.Cu" "B.Cu")
		(net "GND")
	)
	(via
		(at 195.59651 -118.36019)
		(size 0.7112)
		(drill 0.4064)
		(layers "F.Cu" "B.Cu")
		(net "GND")
	)
	(via
		(at 2.162556 -29.360622)
		(size 0.7112)
		(drill 0.4064)
		(layers "F.Cu" "B.Cu")
		(net "GND")
	)
	(via
		(at 232.837482 -104.743758)
		(size 0.7112)
		(drill 0.4064)
		(layers "F.Cu" "B.Cu")
		(net "GND")
	)
	(via
		(at 182.89651 -90.42019)
		(size 0.7112)
		(drill 0.4064)
		(layers "F.Cu" "B.Cu")
		(net "GND")
	)
	(via
		(at 189.47765 -157.837378)
		(size 0.7112)
		(drill 0.4064)
		(layers "F.Cu" "B.Cu")
		(net "GND")
	)
	(via
		(at 57.50433 -191.837564)
		(size 0.7112)
		(drill 0.4064)
		(layers "F.Cu" "B.Cu")
		(net "GND")
	)
	(via
		(at 2.162556 -99.210622)
		(size 0.7112)
		(drill 0.4064)
		(layers "F.Cu" "B.Cu")
		(net "GND")
	)
	(via
		(at 2.162556 -147.470622)
		(size 0.7112)
		(drill 0.4064)
		(layers "F.Cu" "B.Cu")
		(net "GND")
	)
	(via
		(at 28.367482 -50.359564)
		(size 0.7112)
		(drill 0.4064)
		(layers "F.Cu" "B.Cu")
		(net "GND")
	)
	(via
		(at 182.89651 -87.88019)
		(size 0.7112)
		(drill 0.4064)
		(layers "F.Cu" "B.Cu")
		(net "GND")
	)
	(via
		(at 192.98666 -66.884804)
		(size 0.7112)
		(drill 0.4064)
		(layers "F.Cu" "B.Cu")
		(net "GND")
	)
	(via
		(at 75.192636 -18.796508)
		(size 0.7112)
		(drill 0.4064)
		(layers "F.Cu" "B.Cu")
		(net "GND")
	)
	(via
		(at 45.466 -126.9492)
		(size 0.508)
		(drill 0.254)
		(layers "F.Cu" "B.Cu")
		(net "GND")
	)
	(via
		(at 216.77249 -22.92604)
		(size 0.7112)
		(drill 0.4064)
		(layers "F.Cu" "B.Cu")
		(net "GND")
	)
	(via
		(at 232.837482 -33.623758)
		(size 0.7112)
		(drill 0.4064)
		(layers "F.Cu" "B.Cu")
		(net "GND")
	)
	(via
		(at 232.837482 -113.633758)
		(size 0.7112)
		(drill 0.4064)
		(layers "F.Cu" "B.Cu")
		(net "GND")
	)
	(via
		(at 28.367482 -104.969564)
		(size 0.7112)
		(drill 0.4064)
		(layers "F.Cu" "B.Cu")
		(net "GND")
	)
	(via
		(at 2.162556 -14.120622)
		(size 0.7112)
		(drill 0.4064)
		(layers "F.Cu" "B.Cu")
		(net "GND")
	)
	(via
		(at 190.51651 -98.04019)
		(size 0.7112)
		(drill 0.4064)
		(layers "F.Cu" "B.Cu")
		(net "GND")
	)
	(via
		(at 227.411788 -16.183356)
		(size 0.7112)
		(drill 0.4064)
		(layers "F.Cu" "B.Cu")
		(net "GND")
	)
	(via
		(at 47.69993 -150.600156)
		(size 0.4572)
		(drill 0.2032)
		(layers "F.Cu" "B.Cu")
		(net "GND")
	)
	(via
		(at 60.04433 -191.837564)
		(size 0.7112)
		(drill 0.4064)
		(layers "F.Cu" "B.Cu")
		(net "GND")
	)
	(via
		(at 28.367482 -70.679564)
		(size 0.7112)
		(drill 0.4064)
		(layers "F.Cu" "B.Cu")
		(net "GND")
	)
	(via
		(at 28.367482 -90.999564)
		(size 0.7112)
		(drill 0.4064)
		(layers "F.Cu" "B.Cu")
		(net "GND")
	)
	(via
		(at 50.899822 -149.800056)
		(size 0.4572)
		(drill 0.2032)
		(layers "F.Cu" "B.Cu")
		(net "GND")
	)
	(via
		(at 203.21651 -75.18019)
		(size 0.7112)
		(drill 0.4064)
		(layers "F.Cu" "B.Cu")
		(net "GND")
	)
	(via
		(at 62.3316 -147.7772)
		(size 0.508)
		(drill 0.254)
		(layers "F.Cu" "B.Cu")
		(net "GND")
	)
	(via
		(at 146.462496 -50.34407)
		(size 0.7112)
		(drill 0.4064)
		(layers "F.Cu" "B.Cu")
		(net "GND")
	)
	(via
		(at 28.367482 -14.799564)
		(size 0.7112)
		(drill 0.4064)
		(layers "F.Cu" "B.Cu")
		(net "GND")
	)
	(via
		(at 26.416 -120.777)
		(size 0.508)
		(drill 0.254)
		(layers "F.Cu" "B.Cu")
		(net "GND")
	)
	(via
		(at 2.162556 -179.220622)
		(size 0.7112)
		(drill 0.4064)
		(layers "F.Cu" "B.Cu")
		(net "GND")
	)
	(via
		(at 232.837482 -180.943758)
		(size 0.7112)
		(drill 0.4064)
		(layers "F.Cu" "B.Cu")
		(net "GND")
	)
	(via
		(at 182.89651 -65.02019)
		(size 0.7112)
		(drill 0.4064)
		(layers "F.Cu" "B.Cu")
		(net "GND")
	)
	(via
		(at 47.7266 -149.8092)
		(size 0.4572)
		(drill 0.2032)
		(layers "F.Cu" "B.Cu")
		(net "GND")
	)
	(via
		(at 35.6616 -154.3939)
		(size 0.508)
		(drill 0.254)
		(layers "F.Cu" "B.Cu")
		(net "GND")
	)
	(via
		(at 217.162634 -179.657502)
		(size 0.7112)
		(drill 0.4064)
		(layers "F.Cu" "B.Cu")
		(net "GND")
	)
	(via
		(at 154.647138 -8.790178)
		(size 0.7112)
		(drill 0.4064)
		(layers "F.Cu" "B.Cu")
		(net "GND")
	)
	(via
		(at 195.59651 -42.16019)
		(size 0.7112)
		(drill 0.4064)
		(layers "F.Cu" "B.Cu")
		(net "GND")
	)
	(via
		(at 146.462496 -106.22407)
		(size 0.7112)
		(drill 0.4064)
		(layers "F.Cu" "B.Cu")
		(net "GND")
	)
	(via
		(at 2.162556 -177.950622)
		(size 0.7112)
		(drill 0.4064)
		(layers "F.Cu" "B.Cu")
		(net "GND")
	)
	(via
		(at 232.837482 -13.303758)
		(size 0.7112)
		(drill 0.4064)
		(layers "F.Cu" "B.Cu")
		(net "GND")
	)
	(via
		(at 75.192636 -14.986508)
		(size 0.7112)
		(drill 0.4064)
		(layers "F.Cu" "B.Cu")
		(net "GND")
	)
	(via
		(at 195.59651 -65.02019)
		(size 0.7112)
		(drill 0.4064)
		(layers "F.Cu" "B.Cu")
		(net "GND")
	)
	(via
		(at 61.31433 -191.837564)
		(size 0.7112)
		(drill 0.4064)
		(layers "F.Cu" "B.Cu")
		(net "GND")
	)
	(via
		(at 204.649832 -136.25449)
		(size 0.508)
		(drill 0.254)
		(layers "F.Cu" "B.Cu")
		(net "GND")
	)
	(via
		(at 56.515 -136.184894)
		(size 0.508)
		(drill 0.254)
		(layers "F.Cu" "B.Cu")
		(net "GND")
	)
	(via
		(at 49.299622 -144.200372)
		(size 0.4572)
		(drill 0.2032)
		(layers "F.Cu" "B.Cu")
		(net "GND")
	)
	(via
		(at 86.8045 -160.22066)
		(size 0.508)
		(drill 0.254)
		(layers "F.Cu" "B.Cu")
		(net "GND")
	)
	(via
		(at 232.837482 -100.933758)
		(size 0.7112)
		(drill 0.4064)
		(layers "F.Cu" "B.Cu")
		(net "GND")
	)
	(via
		(at 228.864414 -191.435736)
		(size 0.7112)
		(drill 0.4064)
		(layers "F.Cu" "B.Cu")
		(net "GND")
	)
	(via
		(at 217.162634 -165.687502)
		(size 0.7112)
		(drill 0.4064)
		(layers "F.Cu" "B.Cu")
		(net "GND")
	)
	(via
		(at 232.837482 -17.113758)
		(size 0.7112)
		(drill 0.4064)
		(layers "F.Cu" "B.Cu")
		(net "GND")
	)
	(via
		(at 198.13651 -80.26019)
		(size 0.7112)
		(drill 0.4064)
		(layers "F.Cu" "B.Cu")
		(net "GND")
	)
	(via
		(at 2.162556 -40.790622)
		(size 0.7112)
		(drill 0.4064)
		(layers "F.Cu" "B.Cu")
		(net "GND")
	)
	(via
		(at 232.837482 -88.233758)
		(size 0.7112)
		(drill 0.4064)
		(layers "F.Cu" "B.Cu")
		(net "GND")
	)
	(via
		(at 232.837482 -23.463758)
		(size 0.7112)
		(drill 0.4064)
		(layers "F.Cu" "B.Cu")
		(net "GND")
	)
	(via
		(at 208.359502 -70.151752)
		(size 0.7112)
		(drill 0.4064)
		(layers "F.Cu" "B.Cu")
		(net "GND")
	)
	(via
		(at 2.162556 -12.850622)
		(size 0.7112)
		(drill 0.4064)
		(layers "F.Cu" "B.Cu")
		(net "GND")
	)
	(via
		(at 200.67651 -34.54019)
		(size 0.7112)
		(drill 0.4064)
		(layers "F.Cu" "B.Cu")
		(net "GND")
	)
	(via
		(at 212.33765 -157.837378)
		(size 0.7112)
		(drill 0.4064)
		(layers "F.Cu" "B.Cu")
		(net "GND")
	)
	(via
		(at 211.06765 -157.837378)
		(size 0.7112)
		(drill 0.4064)
		(layers "F.Cu" "B.Cu")
		(net "GND")
	)
	(via
		(at 67.66433 -191.837564)
		(size 0.7112)
		(drill 0.4064)
		(layers "F.Cu" "B.Cu")
		(net "GND")
	)
	(via
		(at 39.699946 -144.999964)
		(size 0.4572)
		(drill 0.2032)
		(layers "F.Cu" "B.Cu")
		(net "GND")
	)
	(via
		(at 190.51651 -105.66019)
		(size 0.7112)
		(drill 0.4064)
		(layers "F.Cu" "B.Cu")
		(net "GND")
	)
	(via
		(at 95.060008 -162.821366)
		(size 0.508)
		(drill 0.254)
		(layers "F.Cu" "B.Cu")
		(net "GND")
	)
	(via
		(at 193.05651 -100.58019)
		(size 0.7112)
		(drill 0.4064)
		(layers "F.Cu" "B.Cu")
		(net "GND")
	)
	(via
		(at 30.607 -128.1684)
		(size 0.508)
		(drill 0.254)
		(layers "F.Cu" "B.Cu")
		(net "GND")
	)
	(via
		(at 81.643728 -83.688936)
		(size 0.508)
		(drill 0.254)
		(layers "F.Cu" "B.Cu")
		(net "GND")
	)
	(via
		(at 28.367482 -49.089564)
		(size 0.7112)
		(drill 0.4064)
		(layers "F.Cu" "B.Cu")
		(net "GND")
	)
	(via
		(at 193.05651 -82.80019)
		(size 0.7112)
		(drill 0.4064)
		(layers "F.Cu" "B.Cu")
		(net "GND")
	)
	(via
		(at 47.308516 -117.795294)
		(size 0.508)
		(drill 0.254)
		(layers "F.Cu" "B.Cu")
		(net "GND")
	)
	(via
		(at 93.1926 -126.985268)
		(size 0.508)
		(drill 0.254)
		(layers "F.Cu" "B.Cu")
		(net "GND")
	)
	(via
		(at 146.462496 -113.84407)
		(size 0.7112)
		(drill 0.4064)
		(layers "F.Cu" "B.Cu")
		(net "GND")
	)
	(via
		(at 146.462496 -148.13407)
		(size 0.7112)
		(drill 0.4064)
		(layers "F.Cu" "B.Cu")
		(net "GND")
	)
	(via
		(at 126.084076 -7.62)
		(size 0.508)
		(drill 0.254)
		(layers "F.Cu" "B.Cu")
		(net "GND")
	)
	(via
		(at 56.23433 -191.837564)
		(size 0.7112)
		(drill 0.4064)
		(layers "F.Cu" "B.Cu")
		(net "GND")
	)
	(via
		(at 223.233488 -49.85131)
		(size 0.5588)
		(drill 0.3048)
		(layers "F.Cu" "B.Cu")
		(net "GND")
	)
	(via
		(at 94.3356 -155.6258)
		(size 0.5588)
		(drill 0.3048)
		(layers "F.Cu" "B.Cu")
		(net "GND")
	)
	(via
		(at 193.05651 -32.00019)
		(size 0.7112)
		(drill 0.4064)
		(layers "F.Cu" "B.Cu")
		(net "GND")
	)
	(via
		(at 198.649844 -136.25449)
		(size 0.508)
		(drill 0.254)
		(layers "F.Cu" "B.Cu")
		(net "GND")
	)
	(via
		(at 71.47433 -191.837564)
		(size 0.7112)
		(drill 0.4064)
		(layers "F.Cu" "B.Cu")
		(net "GND")
	)
	(via
		(at 204.608684 -2.162556)
		(size 0.7112)
		(drill 0.4064)
		(layers "F.Cu" "B.Cu")
		(net "GND")
	)
	(via
		(at 49.88433 -191.837564)
		(size 0.7112)
		(drill 0.4064)
		(layers "F.Cu" "B.Cu")
		(net "GND")
	)
	(via
		(at 74.2188 -139.335256)
		(size 0.6096)
		(drill 0.3048)
		(layers "F.Cu" "B.Cu")
		(net "GND")
	)
	(via
		(at 205.98765 -157.837378)
		(size 0.7112)
		(drill 0.4064)
		(layers "F.Cu" "B.Cu")
		(net "GND")
	)
	(via
		(at 200.67651 -57.40019)
		(size 0.7112)
		(drill 0.4064)
		(layers "F.Cu" "B.Cu")
		(net "GND")
	)
	(via
		(at 83.9216 -162.5854)
		(size 0.7112)
		(drill 0.4064)
		(layers "F.Cu" "B.Cu")
		(net "GND")
	)
	(via
		(at 17.755616 -127.527558)
		(size 0.508)
		(drill 0.254)
		(layers "F.Cu" "B.Cu")
		(net "GND")
	)
	(via
		(at 207.148684 -2.162556)
		(size 0.7112)
		(drill 0.4064)
		(layers "F.Cu" "B.Cu")
		(net "GND")
	)
	(via
		(at 182.89651 -80.26019)
		(size 0.7112)
		(drill 0.4064)
		(layers "F.Cu" "B.Cu")
		(net "GND")
	)
	(via
		(at 228.041962 -52.751736)
		(size 0.7112)
		(drill 0.4064)
		(layers "F.Cu" "B.Cu")
		(net "GND")
	)
	(via
		(at 203.21651 -90.42019)
		(size 0.7112)
		(drill 0.4064)
		(layers "F.Cu" "B.Cu")
		(net "GND")
	)
	(via
		(at 195.59651 -59.94019)
		(size 0.7112)
		(drill 0.4064)
		(layers "F.Cu" "B.Cu")
		(net "GND")
	)
	(via
		(at 12.954 -15.113)
		(size 0.508)
		(drill 0.254)
		(layers "F.Cu" "B.Cu")
		(net "GND")
	)
	(via
		(at 96.379792 -123.7615)
		(size 0.508)
		(drill 0.254)
		(layers "F.Cu" "B.Cu")
		(net "GND")
	)
	(via
		(at 232.837482 -85.693758)
		(size 0.7112)
		(drill 0.4064)
		(layers "F.Cu" "B.Cu")
		(net "GND")
	)
	(via
		(at 185.43651 -105.66019)
		(size 0.7112)
		(drill 0.4064)
		(layers "F.Cu" "B.Cu")
		(net "GND")
	)
	(via
		(at 43.700192 -149.800056)
		(size 0.4572)
		(drill 0.2032)
		(layers "F.Cu" "B.Cu")
		(net "GND")
	)
	(via
		(at 67.146932 -154.470608)
		(size 0.508)
		(drill 0.254)
		(layers "F.Cu" "B.Cu")
		(net "GND")
	)
	(via
		(at 232.837482 -74.263758)
		(size 0.7112)
		(drill 0.4064)
		(layers "F.Cu" "B.Cu")
		(net "GND")
	)
	(via
		(at 190.51651 -95.50019)
		(size 0.7112)
		(drill 0.4064)
		(layers "F.Cu" "B.Cu")
		(net "GND")
	)
	(via
		(at 185.63082 -70.126098)
		(size 0.7112)
		(drill 0.4064)
		(layers "F.Cu" "B.Cu")
		(net "GND")
	)
	(via
		(at 232.837482 -86.963758)
		(size 0.7112)
		(drill 0.4064)
		(layers "F.Cu" "B.Cu")
		(net "GND")
	)
	(via
		(at 95.939356 -160.34512)
		(size 0.508)
		(drill 0.254)
		(layers "F.Cu" "B.Cu")
		(net "GND")
	)
	(via
		(at 205.75651 -77.72019)
		(size 0.7112)
		(drill 0.4064)
		(layers "F.Cu" "B.Cu")
		(net "GND")
	)
	(via
		(at 167.347138 -6.885178)
		(size 0.7112)
		(drill 0.4064)
		(layers "F.Cu" "B.Cu")
		(net "GND")
	)
	(via
		(at 193.05651 -87.88019)
		(size 0.7112)
		(drill 0.4064)
		(layers "F.Cu" "B.Cu")
		(net "GND")
	)
	(via
		(at 90.2208 -154.3558)
		(size 0.6096)
		(drill 0.3048)
		(layers "F.Cu" "B.Cu")
		(net "GND")
	)
	(via
		(at 33.024826 -183.00573)
		(size 0.5588)
		(drill 0.3048)
		(layers "F.Cu" "B.Cu")
		(net "GND")
	)
	(via
		(at 2.162556 -52.220622)
		(size 0.7112)
		(drill 0.4064)
		(layers "F.Cu" "B.Cu")
		(net "GND")
	)
	(via
		(at 203.21651 -95.50019)
		(size 0.7112)
		(drill 0.4064)
		(layers "F.Cu" "B.Cu")
		(net "GND")
	)
	(via
		(at 198.13651 -67.56019)
		(size 0.7112)
		(drill 0.4064)
		(layers "F.Cu" "B.Cu")
		(net "GND")
	)
	(via
		(at 218.59748 -96.411288)
		(size 0.5588)
		(drill 0.3048)
		(layers "F.Cu" "B.Cu")
		(net "GND")
	)
	(via
		(at 232.837482 -32.353758)
		(size 0.7112)
		(drill 0.4064)
		(layers "F.Cu" "B.Cu")
		(net "GND")
	)
	(via
		(at 52.499768 -150.599902)
		(size 0.4572)
		(drill 0.2032)
		(layers "F.Cu" "B.Cu")
		(net "GND")
	)
	(via
		(at 188.368432 -70.401434)
		(size 0.7112)
		(drill 0.4064)
		(layers "F.Cu" "B.Cu")
		(net "GND")
	)
	(via
		(at 46.89983 -136.99998)
		(size 0.4572)
		(drill 0.2032)
		(layers "F.Cu" "B.Cu")
		(net "GND")
	)
	(via
		(at 203.338684 -2.162556)
		(size 0.7112)
		(drill 0.4064)
		(layers "F.Cu" "B.Cu")
		(net "GND")
	)
	(via
		(at 2.162556 -151.280622)
		(size 0.7112)
		(drill 0.4064)
		(layers "F.Cu" "B.Cu")
		(net "GND")
	)
	(via
		(at 200.67651 -75.18019)
		(size 0.7112)
		(drill 0.4064)
		(layers "F.Cu" "B.Cu")
		(net "GND")
	)
	(via
		(at 232.837482 -80.613758)
		(size 0.7112)
		(drill 0.4064)
		(layers "F.Cu" "B.Cu")
		(net "GND")
	)
	(via
		(at 176.77765 -157.837378)
		(size 0.7112)
		(drill 0.4064)
		(layers "F.Cu" "B.Cu")
		(net "GND")
	)
	(via
		(at 180.35651 -67.56019)
		(size 0.7112)
		(drill 0.4064)
		(layers "F.Cu" "B.Cu")
		(net "GND")
	)
	(via
		(at 77.4192 -140.828522)
		(size 0.508)
		(drill 0.254)
		(layers "F.Cu" "B.Cu")
		(net "GND")
	)
	(via
		(at 230.008684 -2.162556)
		(size 0.7112)
		(drill 0.4064)
		(layers "F.Cu" "B.Cu")
		(net "GND")
	)
	(via
		(at 146.462496 -134.16407)
		(size 0.7112)
		(drill 0.4064)
		(layers "F.Cu" "B.Cu")
		(net "GND")
	)
	(via
		(at 2.162556 -49.680622)
		(size 0.7112)
		(drill 0.4064)
		(layers "F.Cu" "B.Cu")
		(net "GND")
	)
	(via
		(at 176.121568 -132.202428)
		(size 0.7112)
		(drill 0.4064)
		(layers "F.Cu" "B.Cu")
		(net "GND")
	)
	(via
		(at 193.05651 -52.32019)
		(size 0.7112)
		(drill 0.4064)
		(layers "F.Cu" "B.Cu")
		(net "GND")
	)
	(via
		(at 26.397712 -189.17285)
		(size 0.7112)
		(drill 0.4064)
		(layers "F.Cu" "B.Cu")
		(net "GND")
	)
	(via
		(at 232.837482 -28.543758)
		(size 0.7112)
		(drill 0.4064)
		(layers "F.Cu" "B.Cu")
		(net "GND")
	)
	(via
		(at 33.024826 -180.26253)
		(size 0.5588)
		(drill 0.3048)
		(layers "F.Cu" "B.Cu")
		(net "GND")
	)
	(via
		(at 75.192636 -25.146508)
		(size 0.7112)
		(drill 0.4064)
		(layers "F.Cu" "B.Cu")
		(net "GND")
	)
	(via
		(at 71.247 -179.8574)
		(size 0.508)
		(drill 0.254)
		(layers "F.Cu" "B.Cu")
		(net "GND")
	)
	(via
		(at 198.13651 -65.02019)
		(size 0.7112)
		(drill 0.4064)
		(layers "F.Cu" "B.Cu")
		(net "GND")
	)
	(via
		(at 153.351738 -18.137378)
		(size 0.508)
		(drill 0.254)
		(layers "F.Cu" "B.Cu")
		(net "GND")
	)
	(via
		(at 27.02433 -191.837564)
		(size 0.7112)
		(drill 0.4064)
		(layers "F.Cu" "B.Cu")
		(net "GND")
	)
	(via
		(at 221.404688 -47.31131)
		(size 0.5588)
		(drill 0.3048)
		(layers "F.Cu" "B.Cu")
		(net "GND")
	)
	(via
		(at 134.100062 -45.600112)
		(size 0.6604)
		(drill 0.3556)
		(layers "F.Cu" "B.Cu")
		(net "GND")
	)
	(via
		(at 177.81651 -59.94019)
		(size 0.7112)
		(drill 0.4064)
		(layers "F.Cu" "B.Cu")
		(net "GND")
	)
	(via
		(at 77.8002 -162.2044)
		(size 0.5588)
		(drill 0.3048)
		(layers "F.Cu" "B.Cu")
		(net "GND")
	)
	(via
		(at 28.937712 -189.17285)
		(size 0.7112)
		(drill 0.4064)
		(layers "F.Cu" "B.Cu")
		(net "GND")
	)
	(via
		(at 53.773324 -163.918646)
		(size 0.508)
		(drill 0.254)
		(layers "F.Cu" "B.Cu")
		(net "GND")
	)
	(via
		(at 167.88765 -157.837378)
		(size 0.7112)
		(drill 0.4064)
		(layers "F.Cu" "B.Cu")
		(net "GND")
	)
	(via
		(at 102.8954 -40.4622)
		(size 0.508)
		(drill 0.254)
		(layers "F.Cu" "B.Cu")
		(net "GND")
	)
	(via
		(at 146.462496 -92.25407)
		(size 0.7112)
		(drill 0.4064)
		(layers "F.Cu" "B.Cu")
		(net "GND")
	)
	(via
		(at 89.987628 -48.696372)
		(size 0.508)
		(drill 0.254)
		(layers "F.Cu" "B.Cu")
		(net "GND")
	)
	(via
		(at 185.43651 -34.54019)
		(size 0.7112)
		(drill 0.4064)
		(layers "F.Cu" "B.Cu")
		(net "GND")
	)
	(via
		(at 71.717662 -187.96508)
		(size 0.508)
		(drill 0.254)
		(layers "F.Cu" "B.Cu")
		(net "GND")
	)
	(via
		(at 232.837482 -142.843758)
		(size 0.7112)
		(drill 0.4064)
		(layers "F.Cu" "B.Cu")
		(net "GND")
	)
	(via
		(at 232.837482 -20.923758)
		(size 0.7112)
		(drill 0.4064)
		(layers "F.Cu" "B.Cu")
		(net "GND")
	)
	(via
		(at 203.21651 -85.34019)
		(size 0.7112)
		(drill 0.4064)
		(layers "F.Cu" "B.Cu")
		(net "GND")
	)
	(via
		(at 182.89651 -82.80019)
		(size 0.7112)
		(drill 0.4064)
		(layers "F.Cu" "B.Cu")
		(net "GND")
	)
	(via
		(at 232.837482 -31.083758)
		(size 0.7112)
		(drill 0.4064)
		(layers "F.Cu" "B.Cu")
		(net "GND")
	)
	(via
		(at 39.699946 -148.999956)
		(size 0.4572)
		(drill 0.2032)
		(layers "F.Cu" "B.Cu")
		(net "GND")
	)
	(via
		(at 185.43651 -82.80019)
		(size 0.7112)
		(drill 0.4064)
		(layers "F.Cu" "B.Cu")
		(net "GND")
	)
	(via
		(at 185.43651 -95.50019)
		(size 0.7112)
		(drill 0.4064)
		(layers "F.Cu" "B.Cu")
		(net "GND")
	)
	(via
		(at 208.29651 -57.40019)
		(size 0.7112)
		(drill 0.4064)
		(layers "F.Cu" "B.Cu")
		(net "GND")
	)
	(via
		(at 2.162556 -2.690622)
		(size 0.7112)
		(drill 0.4064)
		(layers "F.Cu" "B.Cu")
		(net "GND")
	)
	(via
		(at 2.162556 -70.000622)
		(size 0.7112)
		(drill 0.4064)
		(layers "F.Cu" "B.Cu")
		(net "GND")
	)
	(via
		(at 24.1808 -169.545)
		(size 0.7112)
		(drill 0.4064)
		(layers "F.Cu" "B.Cu")
		(net "GND")
	)
	(via
		(at 101.537516 -179.342034)
		(size 0.7112)
		(drill 0.4064)
		(layers "F.Cu" "B.Cu")
		(net "GND")
	)
	(via
		(at 76.526644 -162.2171)
		(size 0.5588)
		(drill 0.3048)
		(layers "F.Cu" "B.Cu")
		(net "GND")
	)
	(via
		(at 12.8016 -168.5798)
		(size 0.508)
		(drill 0.254)
		(layers "F.Cu" "B.Cu")
		(net "GND")
	)
	(via
		(at 185.43651 -59.94019)
		(size 0.7112)
		(drill 0.4064)
		(layers "F.Cu" "B.Cu")
		(net "GND")
	)
	(via
		(at 190.51651 -34.54019)
		(size 0.7112)
		(drill 0.4064)
		(layers "F.Cu" "B.Cu")
		(net "GND")
	)
	(via
		(at 205.75651 -29.46019)
		(size 0.7112)
		(drill 0.4064)
		(layers "F.Cu" "B.Cu")
		(net "GND")
	)
	(via
		(at 2.162556 -63.650622)
		(size 0.7112)
		(drill 0.4064)
		(layers "F.Cu" "B.Cu")
		(net "GND")
	)
	(via
		(at 96.3803 -181.4576)
		(size 0.508)
		(drill 0.254)
		(layers "F.Cu" "B.Cu")
		(net "GND")
	)
	(via
		(at 46.900084 -141.00048)
		(size 0.4572)
		(drill 0.2032)
		(layers "F.Cu" "B.Cu")
		(net "GND")
	)
	(via
		(at 92.837 -157.226)
		(size 0.5588)
		(drill 0.3048)
		(layers "F.Cu" "B.Cu")
		(net "GND")
	)
	(via
		(at 232.837482 -27.273758)
		(size 0.7112)
		(drill 0.4064)
		(layers "F.Cu" "B.Cu")
		(net "GND")
	)
	(via
		(at 28.367482 -61.789564)
		(size 0.7112)
		(drill 0.4064)
		(layers "F.Cu" "B.Cu")
		(net "GND")
	)
	(via
		(at 2.162556 -66.190622)
		(size 0.7112)
		(drill 0.4064)
		(layers "F.Cu" "B.Cu")
		(net "GND")
	)
	(via
		(at 89.594436 -137.623804)
		(size 0.508)
		(drill 0.254)
		(layers "F.Cu" "B.Cu")
		(net "GND")
	)
	(via
		(at 189.765178 -136.29132)
		(size 0.7112)
		(drill 0.4064)
		(layers "F.Cu" "B.Cu")
		(net "GND")
	)
	(via
		(at 217.067384 -39.443152)
		(size 0.508)
		(drill 0.254)
		(layers "F.Cu" "B.Cu")
		(net "GND")
	)
	(via
		(at 2.162556 -152.550622)
		(size 0.7112)
		(drill 0.4064)
		(layers "F.Cu" "B.Cu")
		(net "GND")
	)
	(via
		(at 37.655246 -176.72431)
		(size 0.508)
		(drill 0.254)
		(layers "F.Cu" "B.Cu")
		(net "GND")
	)
	(via
		(at 187.97651 -103.12019)
		(size 0.7112)
		(drill 0.4064)
		(layers "F.Cu" "B.Cu")
		(net "GND")
	)
	(via
		(at 187.649866 -136.25449)
		(size 0.508)
		(drill 0.254)
		(layers "F.Cu" "B.Cu")
		(net "GND")
	)
	(via
		(at 57.3786 -156.21)
		(size 0.508)
		(drill 0.254)
		(layers "F.Cu" "B.Cu")
		(net "GND")
	)
	(via
		(at 220.490288 -49.85131)
		(size 0.5588)
		(drill 0.3048)
		(layers "F.Cu" "B.Cu")
		(net "GND")
	)
	(via
		(at 185.289444 -75.207876)
		(size 0.7112)
		(drill 0.4064)
		(layers "F.Cu" "B.Cu")
		(net "GND")
	)
	(via
		(at 15.4178 -169.1386)
		(size 0.5588)
		(drill 0.3048)
		(layers "F.Cu" "B.Cu")
		(net "GND")
	)
	(via
		(at 198.13651 -85.34019)
		(size 0.7112)
		(drill 0.4064)
		(layers "F.Cu" "B.Cu")
		(net "GND")
	)
	(via
		(at 191.908684 -2.162556)
		(size 0.7112)
		(drill 0.4064)
		(layers "F.Cu" "B.Cu")
		(net "GND")
	)
	(via
		(at 28.367482 -47.819564)
		(size 0.7112)
		(drill 0.4064)
		(layers "F.Cu" "B.Cu")
		(net "GND")
	)
	(via
		(at 86.513924 -99.034346)
		(size 0.508)
		(drill 0.254)
		(layers "F.Cu" "B.Cu")
		(net "GND")
	)
	(via
		(at 28.367482 -93.539564)
		(size 0.7112)
		(drill 0.4064)
		(layers "F.Cu" "B.Cu")
		(net "GND")
	)
	(via
		(at 190.51651 -24.38019)
		(size 0.7112)
		(drill 0.4064)
		(layers "F.Cu" "B.Cu")
		(net "GND")
	)
	(via
		(at 146.462496 -54.15407)
		(size 0.7112)
		(drill 0.4064)
		(layers "F.Cu" "B.Cu")
		(net "GND")
	)
	(via
		(at 195.59651 -67.56019)
		(size 0.7112)
		(drill 0.4064)
		(layers "F.Cu" "B.Cu")
		(net "GND")
	)
	(via
		(at 7.3152 -139.566396)
		(size 0.508)
		(drill 0.254)
		(layers "F.Cu" "B.Cu")
		(net "GND")
	)
	(via
		(at 187.97651 -95.50019)
		(size 0.7112)
		(drill 0.4064)
		(layers "F.Cu" "B.Cu")
		(net "GND")
	)
	(via
		(at 193.05651 -49.78019)
		(size 0.7112)
		(drill 0.4064)
		(layers "F.Cu" "B.Cu")
		(net "GND")
	)
	(via
		(at 190.74765 -157.837378)
		(size 0.7112)
		(drill 0.4064)
		(layers "F.Cu" "B.Cu")
		(net "GND")
	)
	(via
		(at 2.162556 -94.130622)
		(size 0.7112)
		(drill 0.4064)
		(layers "F.Cu" "B.Cu")
		(net "GND")
	)
	(via
		(at 38.45433 -191.837564)
		(size 0.7112)
		(drill 0.4064)
		(layers "F.Cu" "B.Cu")
		(net "GND")
	)
	(via
		(at 80.114394 -178.29911)
		(size 0.6096)
		(drill 0.3048)
		(layers "F.Cu" "B.Cu")
		(net "GND")
	)
	(via
		(at 232.837482 -26.003758)
		(size 0.7112)
		(drill 0.4064)
		(layers "F.Cu" "B.Cu")
		(net "GND")
	)
	(via
		(at 203.21651 -72.64019)
		(size 0.7112)
		(drill 0.4064)
		(layers "F.Cu" "B.Cu")
		(net "GND")
	)
	(via
		(at 75.192636 -23.876508)
		(size 0.7112)
		(drill 0.4064)
		(layers "F.Cu" "B.Cu")
		(net "GND")
	)
	(via
		(at 2.162556 -113.180622)
		(size 0.7112)
		(drill 0.4064)
		(layers "F.Cu" "B.Cu")
		(net "GND")
	)
	(via
		(at 187.97651 -37.08019)
		(size 0.7112)
		(drill 0.4064)
		(layers "F.Cu" "B.Cu")
		(net "GND")
	)
	(via
		(at 185.43651 -103.12019)
		(size 0.7112)
		(drill 0.4064)
		(layers "F.Cu" "B.Cu")
		(net "GND")
	)
	(via
		(at 80.14208 -180.77688)
		(size 0.7112)
		(drill 0.4064)
		(layers "F.Cu" "B.Cu")
		(net "GND")
	)
	(via
		(at 47.879 -174.4472)
		(size 0.508)
		(drill 0.254)
		(layers "F.Cu" "B.Cu")
		(net "GND")
	)
	(via
		(at 81.643728 -86.888828)
		(size 0.508)
		(drill 0.254)
		(layers "F.Cu" "B.Cu")
		(net "GND")
	)
	(via
		(at 34.2392 -153.6192)
		(size 0.6096)
		(drill 0.3048)
		(layers "F.Cu" "B.Cu")
		(net "GND")
	)
	(via
		(at 193.05651 -108.20019)
		(size 0.7112)
		(drill 0.4064)
		(layers "F.Cu" "B.Cu")
		(net "GND")
	)
	(via
		(at 2.162556 -158.900622)
		(size 0.7112)
		(drill 0.4064)
		(layers "F.Cu" "B.Cu")
		(net "GND")
	)
	(via
		(at 190.51651 -37.08019)
		(size 0.7112)
		(drill 0.4064)
		(layers "F.Cu" "B.Cu")
		(net "GND")
	)
	(via
		(at 123.57989 -12.052046)
		(size 0.508)
		(drill 0.254)
		(layers "F.Cu" "B.Cu")
		(net "GND")
	)
	(via
		(at 75.091036 -180.35778)
		(size 0.5588)
		(drill 0.3048)
		(layers "F.Cu" "B.Cu")
		(net "GND")
	)
	(via
		(at 95.3262 -15.7861)
		(size 0.508)
		(drill 0.254)
		(layers "F.Cu" "B.Cu")
		(net "GND")
	)
	(via
		(at 187.97651 -39.62019)
		(size 0.7112)
		(drill 0.4064)
		(layers "F.Cu" "B.Cu")
		(net "GND")
	)
	(via
		(at 56.3118 -179.06619)
		(size 0.7112)
		(drill 0.4064)
		(layers "F.Cu" "B.Cu")
		(net "GND")
	)
	(via
		(at 186.828684 -2.162556)
		(size 0.7112)
		(drill 0.4064)
		(layers "F.Cu" "B.Cu")
		(net "GND")
	)
	(via
		(at 90.1954 -165.564058)
		(size 0.508)
		(drill 0.254)
		(layers "F.Cu" "B.Cu")
		(net "GND")
	)
	(via
		(at 207.1624 -98.0948)
		(size 0.4572)
		(drill 0.2032)
		(layers "F.Cu" "B.Cu")
		(net "GND")
	)
	(via
		(at 146.462496 -135.43407)
		(size 0.7112)
		(drill 0.4064)
		(layers "F.Cu" "B.Cu")
		(net "GND")
	)
	(via
		(at 28.367482 -44.009564)
		(size 0.7112)
		(drill 0.4064)
		(layers "F.Cu" "B.Cu")
		(net "GND")
	)
	(via
		(at 14.33449 -2.162556)
		(size 0.7112)
		(drill 0.4064)
		(layers "F.Cu" "B.Cu")
		(net "GND")
	)
	(via
		(at 99.98456 -186.595512)
		(size 0.7112)
		(drill 0.4064)
		(layers "F.Cu" "B.Cu")
		(net "GND")
	)
	(via
		(at 72.5932 -139.546076)
		(size 0.508)
		(drill 0.254)
		(layers "F.Cu" "B.Cu")
		(net "GND")
	)
	(via
		(at 190.51651 -39.62019)
		(size 0.7112)
		(drill 0.4064)
		(layers "F.Cu" "B.Cu")
		(net "GND")
	)
	(via
		(at 2.162556 -141.120622)
		(size 0.7112)
		(drill 0.4064)
		(layers "F.Cu" "B.Cu")
		(net "GND")
	)
	(via
		(at 205.279752 -102.8573)
		(size 0.508)
		(drill 0.254)
		(layers "F.Cu" "B.Cu")
		(net "GND")
	)
	(via
		(at 187.97651 -57.40019)
		(size 0.7112)
		(drill 0.4064)
		(layers "F.Cu" "B.Cu")
		(net "GND")
	)
	(via
		(at 180.478684 -2.162556)
		(size 0.7112)
		(drill 0.4064)
		(layers "F.Cu" "B.Cu")
		(net "GND")
	)
	(via
		(at 75.192636 -20.066508)
		(size 0.7112)
		(drill 0.4064)
		(layers "F.Cu" "B.Cu")
		(net "GND")
	)
	(via
		(at 205.75651 -39.62019)
		(size 0.7112)
		(drill 0.4064)
		(layers "F.Cu" "B.Cu")
		(net "GND")
	)
	(via
		(at 204.71765 -157.837378)
		(size 0.7112)
		(drill 0.4064)
		(layers "F.Cu" "B.Cu")
		(net "GND")
	)
	(via
		(at 81.643728 -90.088974)
		(size 0.508)
		(drill 0.254)
		(layers "F.Cu" "B.Cu")
		(net "GND")
	)
	(via
		(at 2.162556 -138.580622)
		(size 0.7112)
		(drill 0.4064)
		(layers "F.Cu" "B.Cu")
		(net "GND")
	)
	(via
		(at 2.162556 -172.870622)
		(size 0.7112)
		(drill 0.4064)
		(layers "F.Cu" "B.Cu")
		(net "GND")
	)
	(via
		(at 200.67651 -113.28019)
		(size 0.7112)
		(drill 0.4064)
		(layers "F.Cu" "B.Cu")
		(net "GND")
	)
	(via
		(at 187.97651 -82.80019)
		(size 0.7112)
		(drill 0.4064)
		(layers "F.Cu" "B.Cu")
		(net "GND")
	)
	(via
		(at 198.13651 -77.72019)
		(size 0.7112)
		(drill 0.4064)
		(layers "F.Cu" "B.Cu")
		(net "GND")
	)
	(via
		(at 141.299946 -45.600112)
		(size 0.6604)
		(drill 0.3556)
		(layers "F.Cu" "B.Cu")
		(net "GND")
	)
	(via
		(at 168.2496 -131.953)
		(size 0.508)
		(drill 0.254)
		(layers "F.Cu" "B.Cu")
		(net "GND")
	)
	(via
		(at 146.462496 -97.33407)
		(size 0.7112)
		(drill 0.4064)
		(layers "F.Cu" "B.Cu")
		(net "GND")
	)
	(via
		(at 33.024826 -181.17693)
		(size 0.5588)
		(drill 0.3048)
		(layers "F.Cu" "B.Cu")
		(net "GND")
	)
	(via
		(at 79.09433 -191.837564)
		(size 0.7112)
		(drill 0.4064)
		(layers "F.Cu" "B.Cu")
		(net "GND")
	)
	(via
		(at 180.35651 -77.72019)
		(size 0.7112)
		(drill 0.4064)
		(layers "F.Cu" "B.Cu")
		(net "GND")
	)
	(via
		(at 219.51188 -98.240088)
		(size 0.5588)
		(drill 0.3048)
		(layers "F.Cu" "B.Cu")
		(net "GND")
	)
	(via
		(at 2.162556 -163.980622)
		(size 0.7112)
		(drill 0.4064)
		(layers "F.Cu" "B.Cu")
		(net "GND")
	)
	(via
		(at 33.1978 -154.3939)
		(size 0.508)
		(drill 0.254)
		(layers "F.Cu" "B.Cu")
		(net "GND")
	)
	(via
		(at 193.05651 -75.18019)
		(size 0.7112)
		(drill 0.4064)
		(layers "F.Cu" "B.Cu")
		(net "GND")
	)
	(via
		(at 232.548684 -2.162556)
		(size 0.7112)
		(drill 0.4064)
		(layers "F.Cu" "B.Cu")
		(net "GND")
	)
	(via
		(at 193.178684 -2.162556)
		(size 0.7112)
		(drill 0.4064)
		(layers "F.Cu" "B.Cu")
		(net "GND")
	)
	(via
		(at 187.97651 -118.36019)
		(size 0.7112)
		(drill 0.4064)
		(layers "F.Cu" "B.Cu")
		(net "GND")
	)
	(via
		(at 190.51651 -110.74019)
		(size 0.7112)
		(drill 0.4064)
		(layers "F.Cu" "B.Cu")
		(net "GND")
	)
	(via
		(at 148.128228 -152.820624)
		(size 0.7112)
		(drill 0.4064)
		(layers "F.Cu" "B.Cu")
		(net "GND")
	)
	(via
		(at 223.68891 -104.353614)
		(size 0.7112)
		(drill 0.4064)
		(layers "F.Cu" "B.Cu")
		(net "GND")
	)
	(via
		(at 180.35651 -62.48019)
		(size 0.7112)
		(drill 0.4064)
		(layers "F.Cu" "B.Cu")
		(net "GND")
	)
	(via
		(at 7.380732 -136.709912)
		(size 0.508)
		(drill 0.254)
		(layers "F.Cu" "B.Cu")
		(net "GND")
	)
	(via
		(at 35.91433 -191.837564)
		(size 0.7112)
		(drill 0.4064)
		(layers "F.Cu" "B.Cu")
		(net "GND")
	)
	(via
		(at 43.700192 -141.00048)
		(size 0.4572)
		(drill 0.2032)
		(layers "F.Cu" "B.Cu")
		(net "GND")
	)
	(via
		(at 2.525268 -184.215024)
		(size 0.7112)
		(drill 0.4064)
		(layers "F.Cu" "B.Cu")
		(net "GND")
	)
	(via
		(at 81.516728 -95.776796)
		(size 0.508)
		(drill 0.254)
		(layers "F.Cu" "B.Cu")
		(net "GND")
	)
	(via
		(at 232.837482 -118.713758)
		(size 0.7112)
		(drill 0.4064)
		(layers "F.Cu" "B.Cu")
		(net "GND")
	)
	(via
		(at 232.837482 -147.923758)
		(size 0.7112)
		(drill 0.4064)
		(layers "F.Cu" "B.Cu")
		(net "GND")
	)
	(via
		(at 218.092528 -55.099966)
		(size 0.508)
		(drill 0.254)
		(layers "F.Cu" "B.Cu")
		(net "GND")
	)
	(via
		(at 146.462496 -64.31407)
		(size 0.7112)
		(drill 0.4064)
		(layers "F.Cu" "B.Cu")
		(net "GND")
	)
	(via
		(at 232.837482 -121.253758)
		(size 0.7112)
		(drill 0.4064)
		(layers "F.Cu" "B.Cu")
		(net "GND")
	)
	(via
		(at 146.462496 -132.89407)
		(size 0.7112)
		(drill 0.4064)
		(layers "F.Cu" "B.Cu")
		(net "GND")
	)
	(via
		(at 203.21651 -65.02019)
		(size 0.7112)
		(drill 0.4064)
		(layers "F.Cu" "B.Cu")
		(net "GND")
	)
	(via
		(at 146.99234 -150.548848)
		(size 0.7112)
		(drill 0.4064)
		(layers "F.Cu" "B.Cu")
		(net "GND")
	)
	(via
		(at 198.13651 -110.74019)
		(size 0.7112)
		(drill 0.4064)
		(layers "F.Cu" "B.Cu")
		(net "GND")
	)
	(via
		(at 2.162556 -33.170622)
		(size 0.7112)
		(drill 0.4064)
		(layers "F.Cu" "B.Cu")
		(net "GND")
	)
	(via
		(at 28.367482 -40.199564)
		(size 0.7112)
		(drill 0.4064)
		(layers "F.Cu" "B.Cu")
		(net "GND")
	)
	(via
		(at 195.64985 -136.25449)
		(size 0.508)
		(drill 0.254)
		(layers "F.Cu" "B.Cu")
		(net "GND")
	)
	(via
		(at 232.837482 -108.553758)
		(size 0.7112)
		(drill 0.4064)
		(layers "F.Cu" "B.Cu")
		(net "GND")
	)
	(via
		(at 146.462496 -61.77407)
		(size 0.7112)
		(drill 0.4064)
		(layers "F.Cu" "B.Cu")
		(net "GND")
	)
	(via
		(at 178.04765 -157.837378)
		(size 0.7112)
		(drill 0.4064)
		(layers "F.Cu" "B.Cu")
		(net "GND")
	)
	(via
		(at 217.162634 -166.957502)
		(size 0.7112)
		(drill 0.4064)
		(layers "F.Cu" "B.Cu")
		(net "GND")
	)
	(via
		(at 232.837482 -98.393758)
		(size 0.7112)
		(drill 0.4064)
		(layers "F.Cu" "B.Cu")
		(net "GND")
	)
	(via
		(at 232.837482 -177.133758)
		(size 0.7112)
		(drill 0.4064)
		(layers "F.Cu" "B.Cu")
		(net "GND")
	)
	(via
		(at 28.367482 -4.639564)
		(size 0.7112)
		(drill 0.4064)
		(layers "F.Cu" "B.Cu")
		(net "GND")
	)
	(via
		(at 182.89651 -26.92019)
		(size 0.7112)
		(drill 0.4064)
		(layers "F.Cu" "B.Cu")
		(net "GND")
	)
	(via
		(at 232.837482 -97.123758)
		(size 0.7112)
		(drill 0.4064)
		(layers "F.Cu" "B.Cu")
		(net "GND")
	)
	(via
		(at 137.700004 -45.600112)
		(size 0.6604)
		(drill 0.3556)
		(layers "F.Cu" "B.Cu")
		(net "GND")
	)
	(via
		(at 232.837482 -168.243758)
		(size 0.7112)
		(drill 0.4064)
		(layers "F.Cu" "B.Cu")
		(net "GND")
	)
	(via
		(at 79.857092 -170.244516)
		(size 0.508)
		(drill 0.254)
		(layers "F.Cu" "B.Cu")
		(net "GND")
	)
	(via
		(at 71.0184 -134.0866)
		(size 0.508)
		(drill 0.254)
		(layers "F.Cu" "B.Cu")
		(net "GND")
	)
	(via
		(at 185.46826 -56.781446)
		(size 0.7112)
		(drill 0.4064)
		(layers "F.Cu" "B.Cu")
		(net "GND")
	)
	(via
		(at 47.34433 -191.837564)
		(size 0.7112)
		(drill 0.4064)
		(layers "F.Cu" "B.Cu")
		(net "GND")
	)
	(via
		(at 2.162556 -34.440622)
		(size 0.7112)
		(drill 0.4064)
		(layers "F.Cu" "B.Cu")
		(net "GND")
	)
	(via
		(at 39.699438 -141.799818)
		(size 0.4572)
		(drill 0.2032)
		(layers "F.Cu" "B.Cu")
		(net "GND")
	)
	(via
		(at 232.837482 -144.113758)
		(size 0.7112)
		(drill 0.4064)
		(layers "F.Cu" "B.Cu")
		(net "GND")
	)
	(via
		(at 177.81651 -65.02019)
		(size 0.7112)
		(drill 0.4064)
		(layers "F.Cu" "B.Cu")
		(net "GND")
	)
	(via
		(at 2.162556 -132.230622)
		(size 0.7112)
		(drill 0.4064)
		(layers "F.Cu" "B.Cu")
		(net "GND")
	)
	(via
		(at 47.69993 -153.000202)
		(size 0.4572)
		(drill 0.2032)
		(layers "F.Cu" "B.Cu")
		(net "GND")
	)
	(via
		(at 34.294826 -179.34813)
		(size 0.5588)
		(drill 0.3048)
		(layers "F.Cu" "B.Cu")
		(net "GND")
	)
	(via
		(at 148.696172 -153.956766)
		(size 0.7112)
		(drill 0.4064)
		(layers "F.Cu" "B.Cu")
		(net "GND")
	)
	(via
		(at 85.44433 -191.837564)
		(size 0.7112)
		(drill 0.4064)
		(layers "F.Cu" "B.Cu")
		(net "GND")
	)
	(via
		(at 232.837482 -122.523758)
		(size 0.7112)
		(drill 0.4064)
		(layers "F.Cu" "B.Cu")
		(net "GND")
	)
	(via
		(at 12.827 -169.6466)
		(size 0.508)
		(drill 0.254)
		(layers "F.Cu" "B.Cu")
		(net "GND")
	)
	(via
		(at 146.462496 -49.07407)
		(size 0.7112)
		(drill 0.4064)
		(layers "F.Cu" "B.Cu")
		(net "GND")
	)
	(via
		(at 208.52765 -157.837378)
		(size 0.7112)
		(drill 0.4064)
		(layers "F.Cu" "B.Cu")
		(net "GND")
	)
	(via
		(at 232.837482 -15.843758)
		(size 0.7112)
		(drill 0.4064)
		(layers "F.Cu" "B.Cu")
		(net "GND")
	)
	(via
		(at 217.162634 -175.847502)
		(size 0.7112)
		(drill 0.4064)
		(layers "F.Cu" "B.Cu")
		(net "GND")
	)
	(via
		(at 28.367482 -98.619564)
		(size 0.7112)
		(drill 0.4064)
		(layers "F.Cu" "B.Cu")
		(net "GND")
	)
	(via
		(at 73.84288 -179.10048)
		(size 0.5588)
		(drill 0.3048)
		(layers "F.Cu" "B.Cu")
		(net "GND")
	)
	(via
		(at 232.837482 -9.493758)
		(size 0.7112)
		(drill 0.4064)
		(layers "F.Cu" "B.Cu")
		(net "GND")
	)
	(via
		(at 90.3224 -43.9166)
		(size 0.4572)
		(drill 0.2032)
		(layers "F.Cu" "B.Cu")
		(net "GND")
	)
	(via
		(at 203.149962 -136.25449)
		(size 0.508)
		(drill 0.254)
		(layers "F.Cu" "B.Cu")
		(net "GND")
	)
	(via
		(at 198.13651 -72.64019)
		(size 0.7112)
		(drill 0.4064)
		(layers "F.Cu" "B.Cu")
		(net "GND")
	)
	(via
		(at 203.21651 -62.48019)
		(size 0.7112)
		(drill 0.4064)
		(layers "F.Cu" "B.Cu")
		(net "GND")
	)
	(via
		(at 217.162634 -180.927502)
		(size 0.7112)
		(drill 0.4064)
		(layers "F.Cu" "B.Cu")
		(net "GND")
	)
	(via
		(at 75.192636 -6.096508)
		(size 0.7112)
		(drill 0.4064)
		(layers "F.Cu" "B.Cu")
		(net "GND")
	)
	(via
		(at 230.000302 -189.16396)
		(size 0.7112)
		(drill 0.4064)
		(layers "F.Cu" "B.Cu")
		(net "GND")
	)
	(via
		(at 210.958684 -2.162556)
		(size 0.7112)
		(drill 0.4064)
		(layers "F.Cu" "B.Cu")
		(net "GND")
	)
	(via
		(at 68.93433 -191.837564)
		(size 0.7112)
		(drill 0.4064)
		(layers "F.Cu" "B.Cu")
		(net "GND")
	)
	(via
		(at 2.162556 -76.350622)
		(size 0.7112)
		(drill 0.4064)
		(layers "F.Cu" "B.Cu")
		(net "GND")
	)
	(via
		(at 146.462496 -129.08407)
		(size 0.7112)
		(drill 0.4064)
		(layers "F.Cu" "B.Cu")
		(net "GND")
	)
	(via
		(at 185.43651 -54.86019)
		(size 0.7112)
		(drill 0.4064)
		(layers "F.Cu" "B.Cu")
		(net "GND")
	)
	(via
		(at 22.834346 -143.36141)
		(size 0.508)
		(drill 0.254)
		(layers "F.Cu" "B.Cu")
		(net "GND")
	)
	(via
		(at 205.878684 -2.162556)
		(size 0.7112)
		(drill 0.4064)
		(layers "F.Cu" "B.Cu")
		(net "GND")
	)
	(via
		(at 203.21651 -29.46019)
		(size 0.7112)
		(drill 0.4064)
		(layers "F.Cu" "B.Cu")
		(net "GND")
	)
	(via
		(at 146.462496 -110.03407)
		(size 0.7112)
		(drill 0.4064)
		(layers "F.Cu" "B.Cu")
		(net "GND")
	)
	(via
		(at 2.162556 -96.670622)
		(size 0.7112)
		(drill 0.4064)
		(layers "F.Cu" "B.Cu")
		(net "GND")
	)
	(via
		(at 188.649864 -136.25449)
		(size 0.508)
		(drill 0.254)
		(layers "F.Cu" "B.Cu")
		(net "GND")
	)
	(via
		(at 23.21433 -191.837564)
		(size 0.7112)
		(drill 0.4064)
		(layers "F.Cu" "B.Cu")
		(net "GND")
	)
	(via
		(at 79.066644 -163.5125)
		(size 0.5588)
		(drill 0.3048)
		(layers "F.Cu" "B.Cu")
		(net "GND")
	)
	(via
		(at 203.21651 -87.88019)
		(size 0.7112)
		(drill 0.4064)
		(layers "F.Cu" "B.Cu")
		(net "GND")
	)
	(via
		(at 7.98449 -2.162556)
		(size 0.7112)
		(drill 0.4064)
		(layers "F.Cu" "B.Cu")
		(net "GND")
	)
	(via
		(at 190.51651 -54.86019)
		(size 0.7112)
		(drill 0.4064)
		(layers "F.Cu" "B.Cu")
		(net "GND")
	)
	(via
		(at 202.068684 -2.162556)
		(size 0.7112)
		(drill 0.4064)
		(layers "F.Cu" "B.Cu")
		(net "GND")
	)
	(via
		(at 2.162556 -109.370622)
		(size 0.7112)
		(drill 0.4064)
		(layers "F.Cu" "B.Cu")
		(net "GND")
	)
	(via
		(at 56.49976 -153.800048)
		(size 0.4572)
		(drill 0.2032)
		(layers "F.Cu" "B.Cu")
		(net "GND")
	)
	(via
		(at 17.234662 -145.76171)
		(size 0.508)
		(drill 0.254)
		(layers "F.Cu" "B.Cu")
		(net "GND")
	)
	(via
		(at 232.837482 -62.833758)
		(size 0.7112)
		(drill 0.4064)
		(layers "F.Cu" "B.Cu")
		(net "GND")
	)
	(via
		(at 146.462496 -84.63407)
		(size 0.7112)
		(drill 0.4064)
		(layers "F.Cu" "B.Cu")
		(net "GND")
	)
	(via
		(at 232.837482 -174.593758)
		(size 0.7112)
		(drill 0.4064)
		(layers "F.Cu" "B.Cu")
		(net "GND")
	)
	(via
		(at 193.05651 -37.08019)
		(size 0.7112)
		(drill 0.4064)
		(layers "F.Cu" "B.Cu")
		(net "GND")
	)
	(via
		(at 2.162556 -161.440622)
		(size 0.7112)
		(drill 0.4064)
		(layers "F.Cu" "B.Cu")
		(net "GND")
	)
	(via
		(at 141.35354 -13.621004)
		(size 0.7112)
		(drill 0.4064)
		(layers "F.Cu" "B.Cu")
		(net "GND")
	)
	(via
		(at 34.294826 -181.57063)
		(size 0.5588)
		(drill 0.3048)
		(layers "F.Cu" "B.Cu")
		(net "GND")
	)
	(via
		(at 75.192636 -26.416508)
		(size 0.7112)
		(drill 0.4064)
		(layers "F.Cu" "B.Cu")
		(net "GND")
	)
	(via
		(at 190.51651 -65.02019)
		(size 0.7112)
		(drill 0.4064)
		(layers "F.Cu" "B.Cu")
		(net "GND")
	)
	(via
		(at 138.1125 -19.42592)
		(size 0.7112)
		(drill 0.4064)
		(layers "F.Cu" "B.Cu")
		(net "GND")
	)
	(via
		(at 200.67651 -90.42019)
		(size 0.7112)
		(drill 0.4064)
		(layers "F.Cu" "B.Cu")
		(net "GND")
	)
	(via
		(at 50.4698 -130.429)
		(size 0.508)
		(drill 0.254)
		(layers "F.Cu" "B.Cu")
		(net "GND")
	)
	(via
		(at 39.699946 -147.40001)
		(size 0.4572)
		(drill 0.2032)
		(layers "F.Cu" "B.Cu")
		(net "GND")
	)
	(via
		(at 232.837482 -8.223758)
		(size 0.7112)
		(drill 0.4064)
		(layers "F.Cu" "B.Cu")
		(net "GND")
	)
	(via
		(at 33.024826 -182.09133)
		(size 0.5588)
		(drill 0.3048)
		(layers "F.Cu" "B.Cu")
		(net "GND")
	)
	(via
		(at 2.162556 -21.740622)
		(size 0.7112)
		(drill 0.4064)
		(layers "F.Cu" "B.Cu")
		(net "GND")
	)
	(via
		(at 208.418684 -2.162556)
		(size 0.7112)
		(drill 0.4064)
		(layers "F.Cu" "B.Cu")
		(net "GND")
	)
	(via
		(at 205.75651 -75.18019)
		(size 0.7112)
		(drill 0.4064)
		(layers "F.Cu" "B.Cu")
		(net "GND")
	)
	(via
		(at 85.1408 -162.5854)
		(size 0.7112)
		(drill 0.4064)
		(layers "F.Cu" "B.Cu")
		(net "GND")
	)
	(via
		(at 220.42628 -96.411288)
		(size 0.5588)
		(drill 0.3048)
		(layers "F.Cu" "B.Cu")
		(net "GND")
	)
	(via
		(at 232.837482 -69.183758)
		(size 0.7112)
		(drill 0.4064)
		(layers "F.Cu" "B.Cu")
		(net "GND")
	)
	(via
		(at 79.092044 -160.8963)
		(size 0.5588)
		(drill 0.3048)
		(layers "F.Cu" "B.Cu")
		(net "GND")
	)
	(via
		(at 193.05651 -47.24019)
		(size 0.7112)
		(drill 0.4064)
		(layers "F.Cu" "B.Cu")
		(net "GND")
	)
	(via
		(at 198.13651 -98.04019)
		(size 0.7112)
		(drill 0.4064)
		(layers "F.Cu" "B.Cu")
		(net "GND")
	)
	(via
		(at 232.837482 -133.953758)
		(size 0.7112)
		(drill 0.4064)
		(layers "F.Cu" "B.Cu")
		(net "GND")
	)
	(via
		(at 2.162556 -95.400622)
		(size 0.7112)
		(drill 0.4064)
		(layers "F.Cu" "B.Cu")
		(net "GND")
	)
	(via
		(at 232.837482 -158.083758)
		(size 0.7112)
		(drill 0.4064)
		(layers "F.Cu" "B.Cu")
		(net "GND")
	)
	(via
		(at 202.946 -112.0394)
		(size 0.508)
		(drill 0.254)
		(layers "F.Cu" "B.Cu")
		(net "GND")
	)
	(via
		(at 86.95182 -157.5562)
		(size 0.508)
		(drill 0.254)
		(layers "F.Cu" "B.Cu")
		(net "GND")
	)
	(via
		(at 228.041962 -54.021736)
		(size 0.7112)
		(drill 0.4064)
		(layers "F.Cu" "B.Cu")
		(net "GND")
	)
	(via
		(at 230.568246 -188.028072)
		(size 0.7112)
		(drill 0.4064)
		(layers "F.Cu" "B.Cu")
		(net "GND")
	)
	(via
		(at 220.42628 -97.325688)
		(size 0.5588)
		(drill 0.3048)
		(layers "F.Cu" "B.Cu")
		(net "GND")
	)
	(via
		(at 198.258684 -2.162556)
		(size 0.7112)
		(drill 0.4064)
		(layers "F.Cu" "B.Cu")
		(net "GND")
	)
	(via
		(at 146.462496 -146.86407)
		(size 0.7112)
		(drill 0.4064)
		(layers "F.Cu" "B.Cu")
		(net "GND")
	)
	(via
		(at 193.28765 -157.837378)
		(size 0.7112)
		(drill 0.4064)
		(layers "F.Cu" "B.Cu")
		(net "GND")
	)
	(via
		(at 28.367482 -97.349564)
		(size 0.7112)
		(drill 0.4064)
		(layers "F.Cu" "B.Cu")
		(net "GND")
	)
	(via
		(at 208.29651 -26.92019)
		(size 0.7112)
		(drill 0.4064)
		(layers "F.Cu" "B.Cu")
		(net "GND")
	)
	(via
		(at 80.8228 -132.8166)
		(size 0.508)
		(drill 0.254)
		(layers "F.Cu" "B.Cu")
		(net "GND")
	)
	(via
		(at 75.192636 -13.716508)
		(size 0.7112)
		(drill 0.4064)
		(layers "F.Cu" "B.Cu")
		(net "GND")
	)
	(via
		(at 2.162556 -59.840622)
		(size 0.7112)
		(drill 0.4064)
		(layers "F.Cu" "B.Cu")
		(net "GND")
	)
	(via
		(at 209.55 -136.1948)
		(size 0.508)
		(drill 0.254)
		(layers "F.Cu" "B.Cu")
		(net "GND")
	)
	(via
		(at 207.25765 -157.837378)
		(size 0.7112)
		(drill 0.4064)
		(layers "F.Cu" "B.Cu")
		(net "GND")
	)
	(via
		(at 182.89651 -92.96019)
		(size 0.7112)
		(drill 0.4064)
		(layers "F.Cu" "B.Cu")
		(net "GND")
	)
	(via
		(at 228.808026 -80.357218)
		(size 0.7112)
		(drill 0.4064)
		(layers "F.Cu" "B.Cu")
		(net "GND")
	)
	(via
		(at 216.038684 -2.162556)
		(size 0.7112)
		(drill 0.4064)
		(layers "F.Cu" "B.Cu")
		(net "GND")
	)
	(via
		(at 232.837482 -151.733758)
		(size 0.7112)
		(drill 0.4064)
		(layers "F.Cu" "B.Cu")
		(net "GND")
	)
	(via
		(at 2.162556 -9.040622)
		(size 0.7112)
		(drill 0.4064)
		(layers "F.Cu" "B.Cu")
		(net "GND")
	)
	(via
		(at 176.649888 -133.225794)
		(size 0.508)
		(drill 0.254)
		(layers "F.Cu" "B.Cu")
		(net "GND")
	)
	(via
		(at 218.59748 -97.325688)
		(size 0.5588)
		(drill 0.3048)
		(layers "F.Cu" "B.Cu")
		(net "GND")
	)
	(via
		(at 2.162556 -106.830622)
		(size 0.7112)
		(drill 0.4064)
		(layers "F.Cu" "B.Cu")
		(net "GND")
	)
	(via
		(at 179.09032 -132.396738)
		(size 0.7112)
		(drill 0.4064)
		(layers "F.Cu" "B.Cu")
		(net "GND")
	)
	(via
		(at 190.51651 -100.58019)
		(size 0.7112)
		(drill 0.4064)
		(layers "F.Cu" "B.Cu")
		(net "GND")
	)
	(via
		(at 195.59651 -87.88019)
		(size 0.7112)
		(drill 0.4064)
		(layers "F.Cu" "B.Cu")
		(net "GND")
	)
	(via
		(at 77.247496 -144.837658)
		(size 0.508)
		(drill 0.254)
		(layers "F.Cu" "B.Cu")
		(net "GND")
	)
	(via
		(at 62.476634 -177.3936)
		(size 0.508)
		(drill 0.254)
		(layers "F.Cu" "B.Cu")
		(net "GND")
	)
	(via
		(at 92.9386 -50.419)
		(size 0.508)
		(drill 0.254)
		(layers "F.Cu" "B.Cu")
		(net "GND")
	)
	(via
		(at 48.708564 -172.69968)
		(size 0.508)
		(drill 0.254)
		(layers "F.Cu" "B.Cu")
		(net "GND")
	)
	(via
		(at 222.25508 -98.240088)
		(size 0.5588)
		(drill 0.3048)
		(layers "F.Cu" "B.Cu")
		(net "GND")
	)
	(via
		(at 91.151456 -155.60548)
		(size 0.5588)
		(drill 0.3048)
		(layers "F.Cu" "B.Cu")
		(net "GND")
	)
	(via
		(at 190.51651 -59.94019)
		(size 0.7112)
		(drill 0.4064)
		(layers "F.Cu" "B.Cu")
		(net "GND")
	)
	(via
		(at 186.93765 -157.837378)
		(size 0.7112)
		(drill 0.4064)
		(layers "F.Cu" "B.Cu")
		(net "GND")
	)
	(via
		(at 83.0326 -128.9558)
		(size 0.508)
		(drill 0.254)
		(layers "F.Cu" "B.Cu")
		(net "GND")
	)
	(via
		(at 180.35651 -34.54019)
		(size 0.7112)
		(drill 0.4064)
		(layers "F.Cu" "B.Cu")
		(net "GND")
	)
	(via
		(at 28.367482 -28.769564)
		(size 0.7112)
		(drill 0.4064)
		(layers "F.Cu" "B.Cu")
		(net "GND")
	)
	(via
		(at 200.67651 -32.00019)
		(size 0.7112)
		(drill 0.4064)
		(layers "F.Cu" "B.Cu")
		(net "GND")
	)
	(via
		(at 146.462496 -140.51407)
		(size 0.7112)
		(drill 0.4064)
		(layers "F.Cu" "B.Cu")
		(net "GND")
	)
	(via
		(at 198.13651 -70.10019)
		(size 0.7112)
		(drill 0.4064)
		(layers "F.Cu" "B.Cu")
		(net "GND")
	)
	(via
		(at 28.367482 -99.889564)
		(size 0.7112)
		(drill 0.4064)
		(layers "F.Cu" "B.Cu")
		(net "GND")
	)
	(via
		(at 75.192636 -8.636508)
		(size 0.7112)
		(drill 0.4064)
		(layers "F.Cu" "B.Cu")
		(net "GND")
	)
	(via
		(at 193.05651 -105.66019)
		(size 0.7112)
		(drill 0.4064)
		(layers "F.Cu" "B.Cu")
		(net "GND")
	)
	(via
		(at 195.59651 -34.54019)
		(size 0.7112)
		(drill 0.4064)
		(layers "F.Cu" "B.Cu")
		(net "GND")
	)
	(via
		(at 2.162556 -175.410622)
		(size 0.7112)
		(drill 0.4064)
		(layers "F.Cu" "B.Cu")
		(net "GND")
	)
	(via
		(at 197.09765 -157.837378)
		(size 0.7112)
		(drill 0.4064)
		(layers "F.Cu" "B.Cu")
		(net "GND")
	)
	(via
		(at 28.367482 -87.189564)
		(size 0.7112)
		(drill 0.4064)
		(layers "F.Cu" "B.Cu")
		(net "GND")
	)
	(via
		(at 18.034508 -146.561302)
		(size 0.508)
		(drill 0.254)
		(layers "F.Cu" "B.Cu")
		(net "GND")
	)
	(via
		(at 36.83 -126.3904)
		(size 0.508)
		(drill 0.254)
		(layers "F.Cu" "B.Cu")
		(net "GND")
	)
	(via
		(at 28.367482 -37.659564)
		(size 0.7112)
		(drill 0.4064)
		(layers "F.Cu" "B.Cu")
		(net "GND")
	)
	(via
		(at 19.40433 -191.837564)
		(size 0.7112)
		(drill 0.4064)
		(layers "F.Cu" "B.Cu")
		(net "GND")
	)
	(via
		(at 146.462496 -57.96407)
		(size 0.7112)
		(drill 0.4064)
		(layers "F.Cu" "B.Cu")
		(net "GND")
	)
	(via
		(at 232.837482 -4.413758)
		(size 0.7112)
		(drill 0.4064)
		(layers "F.Cu" "B.Cu")
		(net "GND")
	)
	(via
		(at 232.837482 -164.433758)
		(size 0.7112)
		(drill 0.4064)
		(layers "F.Cu" "B.Cu")
		(net "GND")
	)
	(via
		(at 62.760352 -154.999944)
		(size 0.508)
		(drill 0.254)
		(layers "F.Cu" "B.Cu")
		(net "GND")
	)
	(via
		(at 28.367482 -27.499564)
		(size 0.7112)
		(drill 0.4064)
		(layers "F.Cu" "B.Cu")
		(net "GND")
	)
	(via
		(at 16.480536 -165.349936)
		(size 0.508)
		(drill 0.254)
		(layers "F.Cu" "B.Cu")
		(net "GND")
	)
	(via
		(at 75.192636 -28.956508)
		(size 0.7112)
		(drill 0.4064)
		(layers "F.Cu" "B.Cu")
		(net "GND")
	)
	(via
		(at 75.192636 -12.446508)
		(size 0.7112)
		(drill 0.4064)
		(layers "F.Cu" "B.Cu")
		(net "GND")
	)
	(via
		(at 7.310628 -141.000226)
		(size 0.508)
		(drill 0.254)
		(layers "F.Cu" "B.Cu")
		(net "GND")
	)
	(via
		(at 2.162556 -157.630622)
		(size 0.7112)
		(drill 0.4064)
		(layers "F.Cu" "B.Cu")
		(net "GND")
	)
	(via
		(at 50.099722 -137.000234)
		(size 0.4572)
		(drill 0.2032)
		(layers "F.Cu" "B.Cu")
		(net "GND")
	)
	(via
		(at 82.2198 -58.5724)
		(size 0.508)
		(drill 0.254)
		(layers "F.Cu" "B.Cu")
		(net "GND")
	)
	(via
		(at 38.899846 -136.200134)
		(size 0.4572)
		(drill 0.2032)
		(layers "F.Cu" "B.Cu")
		(net "GND")
	)
	(via
		(at 2.162556 -136.040622)
		(size 0.7112)
		(drill 0.4064)
		(layers "F.Cu" "B.Cu")
		(net "GND")
	)
	(via
		(at 30.226 -164.338)
		(size 0.508)
		(drill 0.254)
		(layers "F.Cu" "B.Cu")
		(net "GND")
	)
	(via
		(at 187.97651 -92.96019)
		(size 0.7112)
		(drill 0.4064)
		(layers "F.Cu" "B.Cu")
		(net "GND")
	)
	(via
		(at 190.51651 -29.46019)
		(size 0.7112)
		(drill 0.4064)
		(layers "F.Cu" "B.Cu")
		(net "GND")
	)
	(via
		(at 182.89651 -37.08019)
		(size 0.7112)
		(drill 0.4064)
		(layers "F.Cu" "B.Cu")
		(net "GND")
	)
	(via
		(at 219.575888 -49.85131)
		(size 0.5588)
		(drill 0.3048)
		(layers "F.Cu" "B.Cu")
		(net "GND")
	)
	(via
		(at 187.97651 -115.82019)
		(size 0.7112)
		(drill 0.4064)
		(layers "F.Cu" "B.Cu")
		(net "GND")
	)
	(via
		(at 81.758028 -77.310996)
		(size 0.508)
		(drill 0.254)
		(layers "F.Cu" "B.Cu")
		(net "GND")
	)
	(via
		(at 232.837482 -114.903758)
		(size 0.7112)
		(drill 0.4064)
		(layers "F.Cu" "B.Cu")
		(net "GND")
	)
	(via
		(at 154.442922 -11.939524)
		(size 0.5588)
		(drill 0.3048)
		(layers "F.Cu" "B.Cu")
		(net "GND")
	)
	(via
		(at 232.837482 -178.403758)
		(size 0.7112)
		(drill 0.4064)
		(layers "F.Cu" "B.Cu")
		(net "GND")
	)
	(via
		(at 2.162556 -110.640622)
		(size 0.7112)
		(drill 0.4064)
		(layers "F.Cu" "B.Cu")
		(net "GND")
	)
	(via
		(at 91.9861 -54.400196)
		(size 0.508)
		(drill 0.254)
		(layers "F.Cu" "B.Cu")
		(net "GND")
	)
	(via
		(at 146.462496 -90.98407)
		(size 0.7112)
		(drill 0.4064)
		(layers "F.Cu" "B.Cu")
		(net "GND")
	)
	(via
		(at 47.73295 -143.412718)
		(size 0.4572)
		(drill 0.2032)
		(layers "F.Cu" "B.Cu")
		(net "GND")
	)
	(via
		(at 232.837482 -146.653758)
		(size 0.7112)
		(drill 0.4064)
		(layers "F.Cu" "B.Cu")
		(net "GND")
	)
	(via
		(at 195.59651 -57.40019)
		(size 0.7112)
		(drill 0.4064)
		(layers "F.Cu" "B.Cu")
		(net "GND")
	)
	(via
		(at 183.279796 -72.64019)
		(size 0.7112)
		(drill 0.4064)
		(layers "F.Cu" "B.Cu")
		(net "GND")
	)
	(via
		(at 232.837482 -127.603758)
		(size 0.7112)
		(drill 0.4064)
		(layers "F.Cu" "B.Cu")
		(net "GND")
	)
	(via
		(at 232.837482 -141.573758)
		(size 0.7112)
		(drill 0.4064)
		(layers "F.Cu" "B.Cu")
		(net "GND")
	)
	(via
		(at 195.59651 -92.96019)
		(size 0.7112)
		(drill 0.4064)
		(layers "F.Cu" "B.Cu")
		(net "GND")
	)
	(via
		(at 16.6878 -167.8686)
		(size 0.5588)
		(drill 0.3048)
		(layers "F.Cu" "B.Cu")
		(net "GND")
	)
	(via
		(at 2.162556 -120.800622)
		(size 0.7112)
		(drill 0.4064)
		(layers "F.Cu" "B.Cu")
		(net "GND")
	)
	(via
		(at 193.05651 -103.12019)
		(size 0.7112)
		(drill 0.4064)
		(layers "F.Cu" "B.Cu")
		(net "GND")
	)
	(via
		(at 2.162556 -114.450622)
		(size 0.7112)
		(drill 0.4064)
		(layers "F.Cu" "B.Cu")
		(net "GND")
	)
	(via
		(at 232.837482 -76.803758)
		(size 0.7112)
		(drill 0.4064)
		(layers "F.Cu" "B.Cu")
		(net "GND")
	)
	(via
		(at 208.29651 -34.54019)
		(size 0.7112)
		(drill 0.4064)
		(layers "F.Cu" "B.Cu")
		(net "GND")
	)
	(via
		(at 190.51651 -52.32019)
		(size 0.7112)
		(drill 0.4064)
		(layers "F.Cu" "B.Cu")
		(net "GND")
	)
	(via
		(at 127.604266 -26.211276)
		(size 0.508)
		(drill 0.254)
		(layers "F.Cu" "B.Cu")
		(net "GND")
	)
	(via
		(at 170.6499 -133.225794)
		(size 0.508)
		(drill 0.254)
		(layers "F.Cu" "B.Cu")
		(net "GND")
	)
	(via
		(at 215.32088 -94.252288)
		(size 0.508)
		(drill 0.254)
		(layers "F.Cu" "B.Cu")
		(net "GND")
	)
	(via
		(at 28.367482 -52.899564)
		(size 0.7112)
		(drill 0.4064)
		(layers "F.Cu" "B.Cu")
		(net "GND")
	)
	(via
		(at 217.68308 -96.411288)
		(size 0.5588)
		(drill 0.3048)
		(layers "F.Cu" "B.Cu")
		(net "GND")
	)
	(via
		(at 217.162634 -177.117502)
		(size 0.7112)
		(drill 0.4064)
		(layers "F.Cu" "B.Cu")
		(net "GND")
	)
	(via
		(at 177.938684 -2.162556)
		(size 0.7112)
		(drill 0.4064)
		(layers "F.Cu" "B.Cu")
		(net "GND")
	)
	(via
		(at 229.15753 -68.754752)
		(size 0.7112)
		(drill 0.4064)
		(layers "F.Cu" "B.Cu")
		(net "GND")
	)
	(via
		(at 219.575888 -47.31131)
		(size 0.5588)
		(drill 0.3048)
		(layers "F.Cu" "B.Cu")
		(net "GND")
	)
	(via
		(at 43.53433 -191.837564)
		(size 0.7112)
		(drill 0.4064)
		(layers "F.Cu" "B.Cu")
		(net "GND")
	)
	(via
		(at 198.13651 -105.66019)
		(size 0.7112)
		(drill 0.4064)
		(layers "F.Cu" "B.Cu")
		(net "GND")
	)
	(via
		(at 232.837482 -64.103758)
		(size 0.7112)
		(drill 0.4064)
		(layers "F.Cu" "B.Cu")
		(net "GND")
	)
	(via
		(at 173.837346 -118.613936)
		(size 0.7112)
		(drill 0.4064)
		(layers "F.Cu" "B.Cu")
		(net "GND")
	)
	(via
		(at 232.837482 -55.213758)
		(size 0.7112)
		(drill 0.4064)
		(layers "F.Cu" "B.Cu")
		(net "GND")
	)
	(via
		(at 67.945 -163.9824)
		(size 0.508)
		(drill 0.254)
		(layers "F.Cu" "B.Cu")
		(net "GND")
	)
	(via
		(at 17.9324 -169.1132)
		(size 0.5588)
		(drill 0.3048)
		(layers "F.Cu" "B.Cu")
		(net "GND")
	)
	(via
		(at 88.6206 -29.3116)
		(size 0.508)
		(drill 0.254)
		(layers "F.Cu" "B.Cu")
		(net "GND")
	)
	(via
		(at 26.035 -126.9238)
		(size 0.6096)
		(drill 0.3048)
		(layers "F.Cu" "B.Cu")
		(net "GND")
	)
	(via
		(at 146.462496 -145.59407)
		(size 0.7112)
		(drill 0.4064)
		(layers "F.Cu" "B.Cu")
		(net "GND")
	)
	(via
		(at 224.973388 -16.183356)
		(size 0.7112)
		(drill 0.4064)
		(layers "F.Cu" "B.Cu")
		(net "GND")
	)
	(via
		(at 190.51651 -32.00019)
		(size 0.7112)
		(drill 0.4064)
		(layers "F.Cu" "B.Cu")
		(net "GND")
	)
	(via
		(at 205.664308 -105.755186)
		(size 0.508)
		(drill 0.254)
		(layers "F.Cu" "B.Cu")
		(net "GND")
	)
	(via
		(at 139.3317 -19.42592)
		(size 0.7112)
		(drill 0.4064)
		(layers "F.Cu" "B.Cu")
		(net "GND")
	)
	(via
		(at 8.68045 -133.850126)
		(size 0.508)
		(drill 0.254)
		(layers "F.Cu" "B.Cu")
		(net "GND")
	)
	(via
		(at 232.837482 -10.763758)
		(size 0.7112)
		(drill 0.4064)
		(layers "F.Cu" "B.Cu")
		(net "GND")
	)
	(via
		(at 198.13651 -90.42019)
		(size 0.7112)
		(drill 0.4064)
		(layers "F.Cu" "B.Cu")
		(net "GND")
	)
	(via
		(at 2.162556 -68.730622)
		(size 0.7112)
		(drill 0.4064)
		(layers "F.Cu" "B.Cu")
		(net "GND")
	)
	(via
		(at 80.148684 -2.162556)
		(size 0.7112)
		(drill 0.4064)
		(layers "F.Cu" "B.Cu")
		(net "GND")
	)
	(via
		(at 183.018684 -2.162556)
		(size 0.7112)
		(drill 0.4064)
		(layers "F.Cu" "B.Cu")
		(net "GND")
	)
	(via
		(at 232.837482 -67.913758)
		(size 0.7112)
		(drill 0.4064)
		(layers "F.Cu" "B.Cu")
		(net "GND")
	)
	(via
		(at 182.89651 -34.54019)
		(size 0.7112)
		(drill 0.4064)
		(layers "F.Cu" "B.Cu")
		(net "GND")
	)
	(via
		(at 185.240676 -72.640698)
		(size 0.7112)
		(drill 0.4064)
		(layers "F.Cu" "B.Cu")
		(net "GND")
	)
	(via
		(at 166.928546 -134.66953)
		(size 0.508)
		(drill 0.254)
		(layers "F.Cu" "B.Cu")
		(net "GND")
	)
	(via
		(at 2.162556 -171.600622)
		(size 0.7112)
		(drill 0.4064)
		(layers "F.Cu" "B.Cu")
		(net "GND")
	)
	(via
		(at 182.89651 -95.50019)
		(size 0.7112)
		(drill 0.4064)
		(layers "F.Cu" "B.Cu")
		(net "GND")
	)
	(via
		(at 190.51651 -87.88019)
		(size 0.7112)
		(drill 0.4064)
		(layers "F.Cu" "B.Cu")
		(net "GND")
	)
	(via
		(at 209.688684 -2.162556)
		(size 0.7112)
		(drill 0.4064)
		(layers "F.Cu" "B.Cu")
		(net "GND")
	)
	(via
		(at 35.538664 -182.021988)
		(size 0.5588)
		(drill 0.3048)
		(layers "F.Cu" "B.Cu")
		(net "GND")
	)
	(via
		(at 187.97651 -85.34019)
		(size 0.7112)
		(drill 0.4064)
		(layers "F.Cu" "B.Cu")
		(net "GND")
	)
	(via
		(at 92.151454 -139.216638)
		(size 0.508)
		(drill 0.254)
		(layers "F.Cu" "B.Cu")
		(net "GND")
	)
	(via
		(at 217.68308 -98.240088)
		(size 0.5588)
		(drill 0.3048)
		(layers "F.Cu" "B.Cu")
		(net "GND")
	)
	(via
		(at 187.97651 -49.78019)
		(size 0.7112)
		(drill 0.4064)
		(layers "F.Cu" "B.Cu")
		(net "GND")
	)
	(via
		(at 187.97651 -29.46019)
		(size 0.7112)
		(drill 0.4064)
		(layers "F.Cu" "B.Cu")
		(net "GND")
	)
	(via
		(at 129.196084 -4.670044)
		(size 0.508)
		(drill 0.254)
		(layers "F.Cu" "B.Cu")
		(net "GND")
	)
	(via
		(at 133.4008 -20.5486)
		(size 0.7112)
		(drill 0.4064)
		(layers "F.Cu" "B.Cu")
		(net "GND")
	)
	(via
		(at 187.97651 -98.04019)
		(size 0.7112)
		(drill 0.4064)
		(layers "F.Cu" "B.Cu")
		(net "GND")
	)
	(via
		(at 68.28028 -181.6354)
		(size 0.508)
		(drill 0.254)
		(layers "F.Cu" "B.Cu")
		(net "GND")
	)
	(via
		(at 27.526234 -146.623532)
		(size 0.508)
		(drill 0.254)
		(layers "F.Cu" "B.Cu")
		(net "GND")
	)
	(via
		(at 175.839628 -121.08688)
		(size 0.7112)
		(drill 0.4064)
		(layers "F.Cu" "B.Cu")
		(net "GND")
	)
	(via
		(at 54.099968 -148.999956)
		(size 0.4572)
		(drill 0.2032)
		(layers "F.Cu" "B.Cu")
		(net "GND")
	)
	(via
		(at 28.367482 -85.919564)
		(size 0.7112)
		(drill 0.4064)
		(layers "F.Cu" "B.Cu")
		(net "GND")
	)
	(via
		(at 46.07433 -191.837564)
		(size 0.7112)
		(drill 0.4064)
		(layers "F.Cu" "B.Cu")
		(net "GND")
	)
	(via
		(at 77.82433 -191.837564)
		(size 0.7112)
		(drill 0.4064)
		(layers "F.Cu" "B.Cu")
		(net "GND")
	)
	(via
		(at 187.97651 -67.56019)
		(size 0.7112)
		(drill 0.4064)
		(layers "F.Cu" "B.Cu")
		(net "GND")
	)
	(via
		(at 75.28433 -191.837564)
		(size 0.7112)
		(drill 0.4064)
		(layers "F.Cu" "B.Cu")
		(net "GND")
	)
	(via
		(at 20.67433 -191.837564)
		(size 0.7112)
		(drill 0.4064)
		(layers "F.Cu" "B.Cu")
		(net "GND")
	)
	(via
		(at 2.162556 -61.110622)
		(size 0.7112)
		(drill 0.4064)
		(layers "F.Cu" "B.Cu")
		(net "GND")
	)
	(via
		(at 205.75651 -70.10019)
		(size 0.7112)
		(drill 0.4064)
		(layers "F.Cu" "B.Cu")
		(net "GND")
	)
	(via
		(at 75.192636 -35.306508)
		(size 0.7112)
		(drill 0.4064)
		(layers "F.Cu" "B.Cu")
		(net "GND")
	)
	(via
		(at 86.78926 -154.92222)
		(size 0.508)
		(drill 0.254)
		(layers "F.Cu" "B.Cu")
		(net "GND")
	)
	(via
		(at 195.59651 -103.12019)
		(size 0.7112)
		(drill 0.4064)
		(layers "F.Cu" "B.Cu")
		(net "GND")
	)
	(via
		(at 80.663288 -153.208482)
		(size 0.508)
		(drill 0.254)
		(layers "F.Cu" "B.Cu")
		(net "GND")
	)
	(via
		(at 146.462496 -149.40407)
		(size 0.7112)
		(drill 0.4064)
		(layers "F.Cu" "B.Cu")
		(net "GND")
	)
	(via
		(at 232.837482 -117.443758)
		(size 0.7112)
		(drill 0.4064)
		(layers "F.Cu" "B.Cu")
		(net "GND")
	)
	(via
		(at 193.05651 -57.40019)
		(size 0.7112)
		(drill 0.4064)
		(layers "F.Cu" "B.Cu")
		(net "GND")
	)
	(via
		(at 198.13651 -108.20019)
		(size 0.7112)
		(drill 0.4064)
		(layers "F.Cu" "B.Cu")
		(net "GND")
	)
	(via
		(at 232.837482 -79.343758)
		(size 0.7112)
		(drill 0.4064)
		(layers "F.Cu" "B.Cu")
		(net "GND")
	)
	(via
		(at 30.3276 -129.921)
		(size 0.508)
		(drill 0.254)
		(layers "F.Cu" "B.Cu")
		(net "GND")
	)
	(via
		(at 208.29651 -72.64019)
		(size 0.7112)
		(drill 0.4064)
		(layers "F.Cu" "B.Cu")
		(net "GND")
	)
	(via
		(at 180.35651 -37.08019)
		(size 0.7112)
		(drill 0.4064)
		(layers "F.Cu" "B.Cu")
		(net "GND")
	)
	(via
		(at 75.08748 -179.10048)
		(size 0.5588)
		(drill 0.3048)
		(layers "F.Cu" "B.Cu")
		(net "GND")
	)
	(via
		(at 178.0286 -107.6452)
		(size 0.508)
		(drill 0.254)
		(layers "F.Cu" "B.Cu")
		(net "GND")
	)
	(via
		(at 2.162556 -116.990622)
		(size 0.7112)
		(drill 0.4064)
		(layers "F.Cu" "B.Cu")
		(net "GND")
	)
	(via
		(at 221.963488 -48.58131)
		(size 0.5588)
		(drill 0.3048)
		(layers "F.Cu" "B.Cu")
		(net "GND")
	)
	(via
		(at 200.67651 -110.74019)
		(size 0.7112)
		(drill 0.4064)
		(layers "F.Cu" "B.Cu")
		(net "GND")
	)
	(via
		(at 2.162556 -62.380622)
		(size 0.7112)
		(drill 0.4064)
		(layers "F.Cu" "B.Cu")
		(net "GND")
	)
	(via
		(at 146.462496 -99.87407)
		(size 0.7112)
		(drill 0.4064)
		(layers "F.Cu" "B.Cu")
		(net "GND")
	)
	(via
		(at 99.8474 -143.3576)
		(size 0.508)
		(drill 0.254)
		(layers "F.Cu" "B.Cu")
		(net "GND")
	)
	(via
		(at 187.97651 -77.72019)
		(size 0.7112)
		(drill 0.4064)
		(layers "F.Cu" "B.Cu")
		(net "GND")
	)
	(via
		(at 28.367482 -80.839564)
		(size 0.7112)
		(drill 0.4064)
		(layers "F.Cu" "B.Cu")
		(net "GND")
	)
	(via
		(at 48.499776 -144.200372)
		(size 0.4572)
		(drill 0.2032)
		(layers "F.Cu" "B.Cu")
		(net "GND")
	)
	(via
		(at 179.31765 -157.837378)
		(size 0.7112)
		(drill 0.4064)
		(layers "F.Cu" "B.Cu")
		(net "GND")
	)
	(via
		(at 2.162556 -92.860622)
		(size 0.7112)
		(drill 0.4064)
		(layers "F.Cu" "B.Cu")
		(net "GND")
	)
	(via
		(at 88.471756 -163.538662)
		(size 0.508)
		(drill 0.254)
		(layers "F.Cu" "B.Cu")
		(net "GND")
	)
	(via
		(at 193.05651 -44.70019)
		(size 0.7112)
		(drill 0.4064)
		(layers "F.Cu" "B.Cu")
		(net "GND")
	)
	(via
		(at 48.499776 -146.600164)
		(size 0.4572)
		(drill 0.2032)
		(layers "F.Cu" "B.Cu")
		(net "GND")
	)
	(via
		(at 213.643464 -88.624156)
		(size 0.508)
		(drill 0.254)
		(layers "F.Cu" "B.Cu")
		(net "GND")
	)
	(via
		(at 86.539324 -32.667448)
		(size 0.508)
		(drill 0.254)
		(layers "F.Cu" "B.Cu")
		(net "GND")
	)
	(via
		(at 232.837482 -145.383758)
		(size 0.7112)
		(drill 0.4064)
		(layers "F.Cu" "B.Cu")
		(net "GND")
	)
	(via
		(at 75.192636 -34.036508)
		(size 0.7112)
		(drill 0.4064)
		(layers "F.Cu" "B.Cu")
		(net "GND")
	)
	(via
		(at 97.155 -22.352)
		(size 0.508)
		(drill 0.254)
		(layers "F.Cu" "B.Cu")
		(net "GND")
	)
	(via
		(at 146.462496 -144.32407)
		(size 0.7112)
		(drill 0.4064)
		(layers "F.Cu" "B.Cu")
		(net "GND")
	)
	(via
		(at 28.367482 -64.329564)
		(size 0.7112)
		(drill 0.4064)
		(layers "F.Cu" "B.Cu")
		(net "GND")
	)
	(via
		(at 66.39433 -191.837564)
		(size 0.7112)
		(drill 0.4064)
		(layers "F.Cu" "B.Cu")
		(net "GND")
	)
	(via
		(at 52.8828 -163.957)
		(size 0.508)
		(drill 0.254)
		(layers "F.Cu" "B.Cu")
		(net "GND")
	)
	(via
		(at 2.162556 -5.230622)
		(size 0.7112)
		(drill 0.4064)
		(layers "F.Cu" "B.Cu")
		(net "GND")
	)
	(via
		(at 190.51651 -108.20019)
		(size 0.7112)
		(drill 0.4064)
		(layers "F.Cu" "B.Cu")
		(net "GND")
	)
	(via
		(at 187.97651 -34.54019)
		(size 0.7112)
		(drill 0.4064)
		(layers "F.Cu" "B.Cu")
		(net "GND")
	)
	(via
		(at 2.162556 -36.980622)
		(size 0.7112)
		(drill 0.4064)
		(layers "F.Cu" "B.Cu")
		(net "GND")
	)
	(via
		(at 228.738684 -2.162556)
		(size 0.7112)
		(drill 0.4064)
		(layers "F.Cu" "B.Cu")
		(net "GND")
	)
	(via
		(at 51.71567 -153.878534)
		(size 0.4572)
		(drill 0.2032)
		(layers "F.Cu" "B.Cu")
		(net "GND")
	)
	(via
		(at 190.51651 -115.82019)
		(size 0.7112)
		(drill 0.4064)
		(layers "F.Cu" "B.Cu")
		(net "GND")
	)
	(via
		(at 203.21651 -37.08019)
		(size 0.7112)
		(drill 0.4064)
		(layers "F.Cu" "B.Cu")
		(net "GND")
	)
	(via
		(at 227.995988 -15.040356)
		(size 0.7112)
		(drill 0.4064)
		(layers "F.Cu" "B.Cu")
		(net "GND")
	)
	(via
		(at 51.6382 -159.7406)
		(size 0.508)
		(drill 0.254)
		(layers "F.Cu" "B.Cu")
		(net "GND")
	)
	(via
		(at 195.59651 -32.00019)
		(size 0.7112)
		(drill 0.4064)
		(layers "F.Cu" "B.Cu")
		(net "GND")
	)
	(via
		(at 190.51651 -75.18019)
		(size 0.7112)
		(drill 0.4064)
		(layers "F.Cu" "B.Cu")
		(net "GND")
	)
	(via
		(at 193.05651 -54.86019)
		(size 0.7112)
		(drill 0.4064)
		(layers "F.Cu" "B.Cu")
		(net "GND")
	)
	(via
		(at 96.647 -7.62)
		(size 0.508)
		(drill 0.254)
		(layers "F.Cu" "B.Cu")
		(net "GND")
	)
	(via
		(at 232.837482 -42.513758)
		(size 0.7112)
		(drill 0.4064)
		(layers "F.Cu" "B.Cu")
		(net "GND")
	)
	(via
		(at 46.89983 -145.838164)
		(size 0.4572)
		(drill 0.2032)
		(layers "F.Cu" "B.Cu")
		(net "GND")
	)
	(via
		(at 28.367482 -56.709564)
		(size 0.7112)
		(drill 0.4064)
		(layers "F.Cu" "B.Cu")
		(net "GND")
	)
	(via
		(at 232.837482 -95.853758)
		(size 0.7112)
		(drill 0.4064)
		(layers "F.Cu" "B.Cu")
		(net "GND")
	)
	(via
		(at 182.89651 -77.72019)
		(size 0.7112)
		(drill 0.4064)
		(layers "F.Cu" "B.Cu")
		(net "GND")
	)
	(via
		(at 180.35651 -32.00019)
		(size 0.7112)
		(drill 0.4064)
		(layers "F.Cu" "B.Cu")
		(net "GND")
	)
	(via
		(at 185.558684 -2.162556)
		(size 0.7112)
		(drill 0.4064)
		(layers "F.Cu" "B.Cu")
		(net "GND")
	)
	(via
		(at 98.658172 -165.239446)
		(size 0.508)
		(drill 0.254)
		(layers "F.Cu" "B.Cu")
		(net "GND")
	)
	(via
		(at 27.556968 -137.654792)
		(size 0.6096)
		(drill 0.3048)
		(layers "F.Cu" "B.Cu")
		(net "GND")
	)
	(via
		(at 195.59651 -90.42019)
		(size 0.7112)
		(drill 0.4064)
		(layers "F.Cu" "B.Cu")
		(net "GND")
	)
	(via
		(at 212.649816 -136.25449)
		(size 0.508)
		(drill 0.254)
		(layers "F.Cu" "B.Cu")
		(net "GND")
	)
	(via
		(at 208.29651 -32.00019)
		(size 0.7112)
		(drill 0.4064)
		(layers "F.Cu" "B.Cu")
		(net "GND")
	)
	(via
		(at 2.162556 -35.710622)
		(size 0.7112)
		(drill 0.4064)
		(layers "F.Cu" "B.Cu")
		(net "GND")
	)
	(via
		(at 56.3372 -156.1592)
		(size 0.508)
		(drill 0.254)
		(layers "F.Cu" "B.Cu")
		(net "GND")
	)
	(via
		(at 208.29651 -62.48019)
		(size 0.7112)
		(drill 0.4064)
		(layers "F.Cu" "B.Cu")
		(net "GND")
	)
	(via
		(at 23.22449 -2.162556)
		(size 0.7112)
		(drill 0.4064)
		(layers "F.Cu" "B.Cu")
		(net "GND")
	)
	(via
		(at 203.21651 -82.80019)
		(size 0.7112)
		(drill 0.4064)
		(layers "F.Cu" "B.Cu")
		(net "GND")
	)
	(via
		(at 195.59651 -72.64019)
		(size 0.7112)
		(drill 0.4064)
		(layers "F.Cu" "B.Cu")
		(net "GND")
	)
	(via
		(at 217.162634 -164.417502)
		(size 0.7112)
		(drill 0.4064)
		(layers "F.Cu" "B.Cu")
		(net "GND")
	)
	(via
		(at 30.4546 -157.734)
		(size 0.508)
		(drill 0.254)
		(layers "F.Cu" "B.Cu")
		(net "GND")
	)
	(via
		(at 217.162634 -161.877502)
		(size 0.7112)
		(drill 0.4064)
		(layers "F.Cu" "B.Cu")
		(net "GND")
	)
	(via
		(at 179.909978 -75.038966)
		(size 0.7112)
		(drill 0.4064)
		(layers "F.Cu" "B.Cu")
		(net "GND")
	)
	(via
		(at 180.35651 -92.96019)
		(size 0.7112)
		(drill 0.4064)
		(layers "F.Cu" "B.Cu")
		(net "GND")
	)
	(via
		(at 82.58048 -180.77688)
		(size 0.7112)
		(drill 0.4064)
		(layers "F.Cu" "B.Cu")
		(net "GND")
	)
	(via
		(at 179.208684 -2.162556)
		(size 0.7112)
		(drill 0.4064)
		(layers "F.Cu" "B.Cu")
		(net "GND")
	)
	(via
		(at 47.69993 -146.600164)
		(size 0.4572)
		(drill 0.2032)
		(layers "F.Cu" "B.Cu")
		(net "GND")
	)
	(via
		(at 28.367482 -101.159564)
		(size 0.7112)
		(drill 0.4064)
		(layers "F.Cu" "B.Cu")
		(net "GND")
	)
	(via
		(at 159.168338 -18.416778)
		(size 0.7112)
		(drill 0.4064)
		(layers "F.Cu" "B.Cu")
		(net "GND")
	)
	(via
		(at 180.35651 -82.80019)
		(size 0.7112)
		(drill 0.4064)
		(layers "F.Cu" "B.Cu")
		(net "GND")
	)
	(via
		(at 200.67651 -80.26019)
		(size 0.7112)
		(drill 0.4064)
		(layers "F.Cu" "B.Cu")
		(net "GND")
	)
	(via
		(at 161.53765 -157.837378)
		(size 0.7112)
		(drill 0.4064)
		(layers "F.Cu" "B.Cu")
		(net "GND")
	)
	(via
		(at 28.367482 -46.549564)
		(size 0.7112)
		(drill 0.4064)
		(layers "F.Cu" "B.Cu")
		(net "GND")
	)
	(via
		(at 191.135 -72.644)
		(size 0.7112)
		(drill 0.4064)
		(layers "F.Cu" "B.Cu")
		(net "GND")
	)
	(via
		(at 2.162556 -23.010622)
		(size 0.7112)
		(drill 0.4064)
		(layers "F.Cu" "B.Cu")
		(net "GND")
	)
	(via
		(at 217.68308 -97.325688)
		(size 0.5588)
		(drill 0.3048)
		(layers "F.Cu" "B.Cu")
		(net "GND")
	)
	(via
		(at 46.900084 -145.000218)
		(size 0.4572)
		(drill 0.2032)
		(layers "F.Cu" "B.Cu")
		(net "GND")
	)
	(via
		(at 75.13828 -181.66588)
		(size 0.5588)
		(drill 0.3048)
		(layers "F.Cu" "B.Cu")
		(net "GND")
	)
	(via
		(at 35.538664 -182.936388)
		(size 0.5588)
		(drill 0.3048)
		(layers "F.Cu" "B.Cu")
		(net "GND")
	)
	(via
		(at 232.837482 -48.863758)
		(size 0.7112)
		(drill 0.4064)
		(layers "F.Cu" "B.Cu")
		(net "GND")
	)
	(via
		(at 180.35651 -95.50019)
		(size 0.7112)
		(drill 0.4064)
		(layers "F.Cu" "B.Cu")
		(net "GND")
	)
	(via
		(at 47.699676 -148.999956)
		(size 0.4572)
		(drill 0.2032)
		(layers "F.Cu" "B.Cu")
		(net "GND")
	)
	(via
		(at 5.932932 -191.030606)
		(size 0.7112)
		(drill 0.4064)
		(layers "F.Cu" "B.Cu")
		(net "GND")
	)
	(via
		(at 185.43651 -32.00019)
		(size 0.7112)
		(drill 0.4064)
		(layers "F.Cu" "B.Cu")
		(net "GND")
	)
	(via
		(at 2.162556 -64.920622)
		(size 0.7112)
		(drill 0.4064)
		(layers "F.Cu" "B.Cu")
		(net "GND")
	)
	(via
		(at 77.648562 -51.484784)
		(size 0.508)
		(drill 0.254)
		(layers "F.Cu" "B.Cu")
		(net "GND")
	)
	(via
		(at 185.43651 -65.02019)
		(size 0.7112)
		(drill 0.4064)
		(layers "F.Cu" "B.Cu")
		(net "GND")
	)
	(via
		(at 146.462496 -59.23407)
		(size 0.7112)
		(drill 0.4064)
		(layers "F.Cu" "B.Cu")
		(net "GND")
	)
	(via
		(at 101.120448 -184.323736)
		(size 0.7112)
		(drill 0.4064)
		(layers "F.Cu" "B.Cu")
		(net "GND")
	)
	(via
		(at 195.718684 -2.162556)
		(size 0.7112)
		(drill 0.4064)
		(layers "F.Cu" "B.Cu")
		(net "GND")
	)
	(via
		(at 232.837482 -61.563758)
		(size 0.7112)
		(drill 0.4064)
		(layers "F.Cu" "B.Cu")
		(net "GND")
	)
	(via
		(at 177.81651 -105.66019)
		(size 0.7112)
		(drill 0.4064)
		(layers "F.Cu" "B.Cu")
		(net "GND")
	)
	(via
		(at 193.05651 -21.84019)
		(size 0.7112)
		(drill 0.4064)
		(layers "F.Cu" "B.Cu")
		(net "GND")
	)
	(via
		(at 146.1262 -11.675618)
		(size 0.508)
		(drill 0.254)
		(layers "F.Cu" "B.Cu")
		(net "GND")
	)
	(via
		(at 80.772 -172.28058)
		(size 0.508)
		(drill 0.254)
		(layers "F.Cu" "B.Cu")
		(net "GND")
	)
	(via
		(at 28.367482 -22.419564)
		(size 0.7112)
		(drill 0.4064)
		(layers "F.Cu" "B.Cu")
		(net "GND")
	)
	(via
		(at 128.2446 -4.6228)
		(size 0.508)
		(drill 0.254)
		(layers "F.Cu" "B.Cu")
		(net "GND")
	)
	(via
		(at 185.43651 -118.36019)
		(size 0.7112)
		(drill 0.4064)
		(layers "F.Cu" "B.Cu")
		(net "GND")
	)
	(via
		(at 28.367482 -77.029564)
		(size 0.7112)
		(drill 0.4064)
		(layers "F.Cu" "B.Cu")
		(net "GND")
	)
	(via
		(at 193.05651 -26.92019)
		(size 0.7112)
		(drill 0.4064)
		(layers "F.Cu" "B.Cu")
		(net "GND")
	)
	(via
		(at 193.05651 -65.02019)
		(size 0.7112)
		(drill 0.4064)
		(layers "F.Cu" "B.Cu")
		(net "GND")
	)
	(via
		(at 232.837482 -182.213758)
		(size 0.7112)
		(drill 0.4064)
		(layers "F.Cu" "B.Cu")
		(net "GND")
	)
	(via
		(at 97.536 -7.62)
		(size 0.508)
		(drill 0.254)
		(layers "F.Cu" "B.Cu")
		(net "GND")
	)
	(via
		(at 214.16264 -43.044618)
		(size 0.508)
		(drill 0.254)
		(layers "F.Cu" "B.Cu")
		(net "GND")
	)
	(via
		(at 21.9202 -179.832)
		(size 0.7112)
		(drill 0.4064)
		(layers "F.Cu" "B.Cu")
		(net "GND")
	)
	(via
		(at 58.6486 -147.7264)
		(size 0.508)
		(drill 0.254)
		(layers "F.Cu" "B.Cu")
		(net "GND")
	)
	(via
		(at 2.162556 -91.590622)
		(size 0.7112)
		(drill 0.4064)
		(layers "F.Cu" "B.Cu")
		(net "GND")
	)
	(via
		(at 203.21651 -80.26019)
		(size 0.7112)
		(drill 0.4064)
		(layers "F.Cu" "B.Cu")
		(net "GND")
	)
	(via
		(at 28.29433 -191.837564)
		(size 0.7112)
		(drill 0.4064)
		(layers "F.Cu" "B.Cu")
		(net "GND")
	)
	(via
		(at 232.837482 -166.973758)
		(size 0.7112)
		(drill 0.4064)
		(layers "F.Cu" "B.Cu")
		(net "GND")
	)
	(via
		(at 57.5818 -179.06619)
		(size 0.7112)
		(drill 0.4064)
		(layers "F.Cu" "B.Cu")
		(net "GND")
	)
	(via
		(at 153.401522 -10.872724)
		(size 0.5588)
		(drill 0.3048)
		(layers "F.Cu" "B.Cu")
		(net "GND")
	)
	(via
		(at 195.59651 -29.46019)
		(size 0.7112)
		(drill 0.4064)
		(layers "F.Cu" "B.Cu")
		(net "GND")
	)
	(via
		(at 231.704134 -185.756042)
		(size 0.7112)
		(drill 0.4064)
		(layers "F.Cu" "B.Cu")
		(net "GND")
	)
	(via
		(at 2.162556 -26.820622)
		(size 0.7112)
		(drill 0.4064)
		(layers "F.Cu" "B.Cu")
		(net "GND")
	)
	(via
		(at 54.96433 -191.837564)
		(size 0.7112)
		(drill 0.4064)
		(layers "F.Cu" "B.Cu")
		(net "GND")
	)
	(via
		(at 200.67651 -95.50019)
		(size 0.7112)
		(drill 0.4064)
		(layers "F.Cu" "B.Cu")
		(net "GND")
	)
	(via
		(at 200.67651 -29.46019)
		(size 0.7112)
		(drill 0.4064)
		(layers "F.Cu" "B.Cu")
		(net "GND")
	)
	(via
		(at 187.790836 -133.135624)
		(size 0.7112)
		(drill 0.4064)
		(layers "F.Cu" "B.Cu")
		(net "GND")
	)
	(via
		(at 50.899822 -151.400002)
		(size 0.4572)
		(drill 0.2032)
		(layers "F.Cu" "B.Cu")
		(net "GND")
	)
	(via
		(at 2.162556 -11.580622)
		(size 0.7112)
		(drill 0.4064)
		(layers "F.Cu" "B.Cu")
		(net "GND")
	)
	(via
		(at 232.837482 -83.153758)
		(size 0.7112)
		(drill 0.4064)
		(layers "F.Cu" "B.Cu")
		(net "GND")
	)
	(via
		(at 32.10433 -191.837564)
		(size 0.7112)
		(drill 0.4064)
		(layers "F.Cu" "B.Cu")
		(net "GND")
	)
	(via
		(at 212.228684 -2.162556)
		(size 0.7112)
		(drill 0.4064)
		(layers "F.Cu" "B.Cu")
		(net "GND")
	)
	(via
		(at 182.726076 -136.22147)
		(size 0.508)
		(drill 0.254)
		(layers "F.Cu" "B.Cu")
		(net "GND")
	)
	(via
		(at 232.837482 -154.273758)
		(size 0.7112)
		(drill 0.4064)
		(layers "F.Cu" "B.Cu")
		(net "GND")
	)
	(via
		(at 2.162556 -97.940622)
		(size 0.7112)
		(drill 0.4064)
		(layers "F.Cu" "B.Cu")
		(net "GND")
	)
	(via
		(at 190.638684 -2.162556)
		(size 0.7112)
		(drill 0.4064)
		(layers "F.Cu" "B.Cu")
		(net "GND")
	)
	(via
		(at 194.448684 -2.162556)
		(size 0.7112)
		(drill 0.4064)
		(layers "F.Cu" "B.Cu")
		(net "GND")
	)
	(via
		(at 146.462496 -88.44407)
		(size 0.7112)
		(drill 0.4064)
		(layers "F.Cu" "B.Cu")
		(net "GND")
	)
	(via
		(at 193.835782 -70.073774)
		(size 0.7112)
		(drill 0.4064)
		(layers "F.Cu" "B.Cu")
		(net "GND")
	)
	(via
		(at 166.61765 -157.837378)
		(size 0.7112)
		(drill 0.4064)
		(layers "F.Cu" "B.Cu")
		(net "GND")
	)
	(via
		(at 184.15 -136.25449)
		(size 0.508)
		(drill 0.254)
		(layers "F.Cu" "B.Cu")
		(net "GND")
	)
	(via
		(at 232.837482 -111.093758)
		(size 0.7112)
		(drill 0.4064)
		(layers "F.Cu" "B.Cu")
		(net "GND")
	)
	(via
		(at 2.162556 -45.870622)
		(size 0.7112)
		(drill 0.4064)
		(layers "F.Cu" "B.Cu")
		(net "GND")
	)
	(via
		(at 62.2554 -162.433)
		(size 0.508)
		(drill 0.254)
		(layers "F.Cu" "B.Cu")
		(net "GND")
	)
	(via
		(at 232.837482 -131.413758)
		(size 0.7112)
		(drill 0.4064)
		(layers "F.Cu" "B.Cu")
		(net "GND")
	)
	(via
		(at 193.05651 -95.50019)
		(size 0.7112)
		(drill 0.4064)
		(layers "F.Cu" "B.Cu")
		(net "GND")
	)
	(via
		(at 77.827378 -52.338478)
		(size 0.508)
		(drill 0.254)
		(layers "F.Cu" "B.Cu")
		(net "GND")
	)
	(via
		(at 188.098684 -2.162556)
		(size 0.7112)
		(drill 0.4064)
		(layers "F.Cu" "B.Cu")
		(net "GND")
	)
	(via
		(at 2.162556 -50.950622)
		(size 0.7112)
		(drill 0.4064)
		(layers "F.Cu" "B.Cu")
		(net "GND")
	)
	(via
		(at 15.4432 -167.8686)
		(size 0.5588)
		(drill 0.3048)
		(layers "F.Cu" "B.Cu")
		(net "GND")
	)
	(via
		(at 185.43651 -26.92019)
		(size 0.7112)
		(drill 0.4064)
		(layers "F.Cu" "B.Cu")
		(net "GND")
	)
	(segment
		(start 67.2719 -149.5806)
		(end 67.3735 -149.479)
		(width 0.508)
		(layer "B.Cu")
		(net "GND")
	)
	(segment
		(start 74.43978 -141.69898)
		(end 74.170794 -141.429994)
		(width 0.508)
		(layer "B.Cu")
		(net "GND")
	)
	(segment
		(start 48.690276 -135.274812)
		(end 48.178212 -135.274812)
		(width 0.508)
		(layer "B.Cu")
		(net "GND")
	)
	(segment
		(start 30.549342 -128.110742)
		(end 30.607 -128.1684)
		(width 0.508)
		(layer "B.Cu")
		(net "GND")
	)
	(segment
		(start 33.958022 -158.2928)
		(end 32.4993 -158.2928)
		(width 0.508)
		(layer "B.Cu")
		(net "GND")
	)
	(segment
		(start 61.4934 -148.0693)
		(end 62.0395 -148.0693)
		(width 0.508)
		(layer "B.Cu")
		(net "GND")
	)
	(segment
		(start 207.094836 -99.088448)
		(end 207.094836 -98.162364)
		(width 0.508)
		(layer "B.Cu")
		(net "GND")
	)
	(segment
		(start 121.520966 -6.5532)
		(end 121.520966 -5.18922)
		(width 0.508)
		(layer "B.Cu")
		(net "GND")
	)
	(segment
		(start 82.69224 -129.62636)
		(end 82.0039 -129.62636)
		(width 0.254)
		(layer "B.Cu")
		(net "GND")
	)
	(segment
		(start 204.93355 -106.84891)
		(end 204.93355 -106.485944)
		(width 0.508)
		(layer "B.Cu")
		(net "GND")
	)
	(segment
		(start 16.3449 -148.0058)
		(end 17.078706 -148.0058)
		(width 0.508)
		(layer "B.Cu")
		(net "GND")
	)
	(segment
		(start 57.809892 -147.743164)
		(end 58.631836 -147.743164)
		(width 0.508)
		(layer "B.Cu")
		(net "GND")
	)
	(segment
		(start 87.4141 -147.124674)
		(end 86.174326 -147.124674)
		(width 0.508)
		(layer "B.Cu")
		(net "GND")
	)
	(segment
		(start 76.745338 -151.29256)
		(end 77.0255 -151.29256)
		(width 0.381)
		(layer "B.Cu")
		(net "GND")
	)
	(segment
		(start 59.2582 -137.617454)
		(end 59.2582 -138.0871)
		(width 0.254)
		(layer "B.Cu")
		(net "GND")
	)
	(segment
		(start 88.471756 -163.538662)
		(end 88.471756 -162.251644)
		(width 0.508)
		(layer "B.Cu")
		(net "GND")
	)
	(segment
		(start 74.2188 -140.479018)
		(end 74.170794 -140.527024)
		(width 0.508)
		(layer "B.Cu")
		(net "GND")
	)
	(segment
		(start 39.557452 -144.85747)
		(end 38.675564 -144.85747)
		(width 0.254)
		(layer "B.Cu")
		(net "GND")
	)
	(segment
		(start 59.600592 -137.275062)
		(end 59.78144 -137.094214)
		(width 0.508)
		(layer "B.Cu")
		(net "GND")
	)
	(segment
		(start 57.294526 -161.083752)
		(end 57.731152 -161.083752)
		(width 0.508)
		(layer "B.Cu")
		(net "GND")
	)
	(segment
		(start 206.183992 -106.27487)
		(end 205.664308 -105.755186)
		(width 0.3048)
		(layer "B.Cu")
		(net "GND")
	)
	(segment
		(start 55.2958 -161.163)
		(end 55.5752 -161.4424)
		(width 0.508)
		(layer "B.Cu")
		(net "GND")
	)
	(segment
		(start 48.887634 -156.626306)
		(end 48.56734 -156.9466)
		(width 0.254)
		(layer "B.Cu")
		(net "GND")
	)
	(segment
		(start 218.092528 -55.099966)
		(end 218.85783 -54.334664)
		(width 0.254)
		(layer "B.Cu")
		(net "GND")
	)
	(segment
		(start 37.9476 -154.9146)
		(end 38.899846 -153.962354)
		(width 0.254)
		(layer "B.Cu")
		(net "GND")
	)
	(segment
		(start 48.513492 -156.892752)
		(end 47.79264 -156.892752)
		(width 0.254)
		(layer "B.Cu")
		(net "GND")
	)
	(segment
		(start 60.6933 -150.749)
		(end 61.6839 -149.7584)
		(width 0.508)
		(layer "B.Cu")
		(net "GND")
	)
	(segment
		(start 37.521642 -155.485084)
		(end 37.9476 -155.059126)
		(width 0.254)
		(layer "B.Cu")
		(net "GND")
	)
	(segment
		(start 78.4098 -130.0353)
		(end 77.760068 -130.0353)
		(width 0.508)
		(layer "B.Cu")
		(net "GND")
	)
	(segment
		(start 94.425008 -146.8247)
		(end 94.729554 -146.520154)
		(width 0.508)
		(layer "B.Cu")
		(net "GND")
	)
	(segment
		(start 75.9714 -150.518622)
		(end 76.745338 -151.29256)
		(width 0.381)
		(layer "B.Cu")
		(net "GND")
	)
	(segment
		(start 208.474564 -89.938606)
		(end 207.147414 -89.938606)
		(width 0.508)
		(layer "B.Cu")
		(net "GND")
	)
	(segment
		(start 85.377528 -149.756622)
		(end 84.244942 -148.624036)
		(width 0.381)
		(layer "B.Cu")
		(net "GND")
	)
	(segment
		(start 45.466 -127.7747)
		(end 45.466 -126.9492)
		(width 0.508)
		(layer "B.Cu")
		(net "GND")
	)
	(segment
		(start 85.991954 -147.307046)
		(end 85.070442 -147.307046)
		(width 0.508)
		(layer "B.Cu")
		(net "GND")
	)
	(segment
		(start 93.5355 -131.45516)
		(end 93.4974 -131.41706)
		(width 0.254)
		(layer "B.Cu")
		(net "GND")
	)
	(segment
		(start 91.176856 -147.964144)
		(end 91.67622 -147.964144)
		(width 0.508)
		(layer "B.Cu")
		(net "GND")
	)
	(segment
		(start 95.939356 -160.34512)
		(end 95.939356 -159.45612)
		(width 0.508)
		(layer "B.Cu")
		(net "GND")
	)
	(segment
		(start 87.690706 -168.069006)
		(end 86.489794 -168.069006)
		(width 0.3048)
		(layer "B.Cu")
		(net "GND")
	)
	(segment
		(start 57.5183 -150.6728)
		(end 58.3692 -150.6728)
		(width 0.508)
		(layer "B.Cu")
		(net "GND")
	)
	(segment
		(start 46.682152 -136.169654)
		(end 46.682152 -136.782302)
		(width 0.508)
		(layer "B.Cu")
		(net "GND")
	)
	(segment
		(start 92.00642 -138.2268)
		(end 92.00642 -138.707622)
		(width 0.508)
		(layer "B.Cu")
		(net "GND")
	)
	(segment
		(start 92.3163 -144.11325)
		(end 93.5736 -144.11325)
		(width 0.254)
		(layer "B.Cu")
		(net "GND")
	)
	(segment
		(start 207.094836 -98.162364)
		(end 207.1624 -98.0948)
		(width 0.508)
		(layer "B.Cu")
		(net "GND")
	)
	(segment
		(start 38.899846 -153.962354)
		(end 38.899846 -153.800302)
		(width 0.254)
		(layer "B.Cu")
		(net "GND")
	)
	(segment
		(start 195.641976 -136.262364)
		(end 195.64985 -136.25449)
		(width 0.508)
		(layer "B.Cu")
		(net "GND")
	)
	(segment
		(start 76.5429 -134.8105)
		(end 76.5429 -134.0866)
		(width 0.508)
		(layer "B.Cu")
		(net "GND")
	)
	(segment
		(start 77.5462 -130.249168)
		(end 77.5462 -130.6195)
		(width 0.508)
		(layer "B.Cu")
		(net "GND")
	)
	(segment
		(start 66.862452 -169.282618)
		(end 66.862452 -168.322244)
		(width 0.508)
		(layer "B.Cu")
		(net "GND")
	)
	(segment
		(start 77.247496 -144.837658)
		(end 76.11237 -144.837658)
		(width 0.3556)
		(layer "B.Cu")
		(net "GND")
	)
	(segment
		(start 61.241432 -137.094214)
		(end 62.140846 -136.1948)
		(width 0.508)
		(layer "B.Cu")
		(net "GND")
	)
	(segment
		(start 78.296262 -135.936228)
		(end 77.668628 -135.936228)
		(width 0.508)
		(layer "B.Cu")
		(net "GND")
	)
	(segment
		(start 133.4008 -21.24202)
		(end 133.4008 -20.5486)
		(width 0.508)
		(layer "B.Cu")
		(net "GND")
	)
	(segment
		(start 53.690012 -135.217154)
		(end 53.0098 -134.536942)
		(width 0.508)
		(layer "B.Cu")
		(net "GND")
	)
	(segment
		(start 75.512168 -145.43786)
		(end 75.512168 -146.138646)
		(width 0.3556)
		(layer "B.Cu")
		(net "GND")
	)
	(segment
		(start 53.975 -155.4353)
		(end 54.082442 -155.542742)
		(width 0.508)
		(layer "B.Cu")
		(net "GND")
	)
	(segment
		(start 37.9476 -155.059126)
		(end 37.9476 -154.9146)
		(width 0.254)
		(layer "B.Cu")
		(net "GND")
	)
	(segment
		(start 62.0395 -148.0693)
		(end 62.3316 -147.7772)
		(width 0.508)
		(layer "B.Cu")
		(net "GND")
	)
	(segment
		(start 52.7304 -126.77902)
		(end 52.7304 -127.587248)
		(width 0.508)
		(layer "B.Cu")
		(net "GND")
	)
	(segment
		(start 51.36007 -159.46247)
		(end 51.36007 -158.956756)
		(width 0.254)
		(layer "B.Cu")
		(net "GND")
	)
	(segment
		(start 122.612658 -10.63498)
		(end 122.447304 -10.469626)
		(width 0.508)
		(layer "B.Cu")
		(net "GND")
	)
	(segment
		(start 93.269054 -133.81355)
		(end 93.269054 -133.8072)
		(width 0.3556)
		(layer "B.Cu")
		(net "GND")
	)
	(segment
		(start 121.520966 -5.18922)
		(end 121.520204 -5.188458)
		(width 0.508)
		(layer "B.Cu")
		(net "GND")
	)
	(segment
		(start 93.2688 -133.813804)
		(end 93.269054 -133.81355)
		(width 0.3556)
		(layer "B.Cu")
		(net "GND")
	)
	(segment
		(start 37.6555 -149.76602)
		(end 37.6555 -149.987)
		(width 0.508)
		(layer "B.Cu")
		(net "GND")
	)
	(segment
		(start 32.0421 -158.75)
		(end 32.0421 -159.0802)
		(width 0.508)
		(layer "B.Cu")
		(net "GND")
	)
	(segment
		(start 131.64185 -15.32763)
		(end 131.64185 -16.35506)
		(width 0.508)
		(layer "B.Cu")
		(net "GND")
	)
	(segment
		(start 87.129874 -99.650296)
		(end 86.513924 -99.034346)
		(width 0.508)
		(layer "B.Cu")
		(net "GND")
	)
	(segment
		(start 77.760068 -130.0353)
		(end 77.5462 -130.249168)
		(width 0.508)
		(layer "B.Cu")
		(net "GND")
	)
	(segment
		(start 204.93355 -106.485944)
		(end 205.664308 -105.755186)
		(width 0.508)
		(layer "B.Cu")
		(net "GND")
	)
	(segment
		(start 54.3306 -120.5611)
		(end 54.4576 -120.6881)
		(width 0.508)
		(layer "B.Cu")
		(net "GND")
	)
	(segment
		(start 89.58199 -132.1816)
		(end 89.811606 -131.951984)
		(width 0.254)
		(layer "B.Cu")
		(net "GND")
	)
	(segment
		(start 35.6997 -126.62916)
		(end 36.59124 -126.62916)
		(width 0.254)
		(layer "B.Cu")
		(net "GND")
	)
	(segment
		(start 51.603402 -161.1376)
		(end 51.044602 -161.6964)
		(width 0.508)
		(layer "B.Cu")
		(net "GND")
	)
	(segment
		(start 34.720022 -157.5308)
		(end 34.469324 -157.781498)
		(width 0.508)
		(layer "B.Cu")
		(net "GND")
	)
	(segment
		(start 90.678 -148.463)
		(end 91.176856 -147.964144)
		(width 0.508)
		(layer "B.Cu")
		(net "GND")
	)
	(segment
		(start 57.634124 -161.999676)
		(end 58.1406 -161.4932)
		(width 0.508)
		(layer "B.Cu")
		(net "GND")
	)
	(segment
		(start 66.862452 -168.322244)
		(end 66.757804 -168.217596)
		(width 0.508)
		(layer "B.Cu")
		(net "GND")
	)
	(segment
		(start 23.634192 -146.561556)
		(end 23.777702 -146.418046)
		(width 0.508)
		(layer "B.Cu")
		(net "GND")
	)
	(segment
		(start 79.321406 -135.935974)
		(end 78.296516 -135.935974)
		(width 0.508)
		(layer "B.Cu")
		(net "GND")
	)
	(segment
		(start 39.699946 -144.999964)
		(end 39.557452 -144.85747)
		(width 0.254)
		(layer "B.Cu")
		(net "GND")
	)
	(segment
		(start 92.793058 -134.2898)
		(end 93.2688 -133.814058)
		(width 0.3556)
		(layer "B.Cu")
		(net "GND")
	)
	(segment
		(start 87.504524 -99.650296)
		(end 87.129874 -99.650296)
		(width 0.508)
		(layer "B.Cu")
		(net "GND")
	)
	(segment
		(start 84.0232 -153.06294)
		(end 83.727544 -153.358596)
		(width 0.508)
		(layer "B.Cu")
		(net "GND")
	)
	(segment
		(start 37.592 -119.9007)
		(end 37.592 -119.126)
		(width 0.508)
		(layer "B.Cu")
		(net "GND")
	)
	(segment
		(start 56.896 -156.718)
		(end 56.3372 -156.1592)
		(width 0.508)
		(layer "B.Cu")
		(net "GND")
	)
	(segment
		(start 92.151454 -139.727432)
		(end 92.151454 -139.216638)
		(width 0.508)
		(layer "B.Cu")
		(net "GND")
	)
	(segment
		(start 26.67 -162.306)
		(end 26.6319 -162.3441)
		(width 0.508)
		(layer "B.Cu")
		(net "GND")
	)
	(segment
		(start 74.2188 -139.335256)
		(end 74.2188 -140.479018)
		(width 0.508)
		(layer "B.Cu")
		(net "GND")
	)
	(segment
		(start 74.170794 -141.429994)
		(end 74.170794 -140.527024)
		(width 0.508)
		(layer "B.Cu")
		(net "GND")
	)
	(segment
		(start 55.8165 -119.6594)
		(end 56.4134 -120.2563)
		(width 0.508)
		(layer "B.Cu")
		(net "GND")
	)
	(segment
		(start 57.634124 -162.025076)
		(end 57.634124 -161.999676)
		(width 0.508)
		(layer "B.Cu")
		(net "GND")
	)
	(segment
		(start 59.600592 -137.275062)
		(end 59.2582 -137.617454)
		(width 0.254)
		(layer "B.Cu")
		(net "GND")
	)
	(segment
		(start 77.5462 -130.6195)
		(end 77.5589 -130.6322)
		(width 0.508)
		(layer "B.Cu")
		(net "GND")
	)
	(segment
		(start 74.2188 -137.788142)
		(end 74.2188 -139.335256)
		(width 0.508)
		(layer "B.Cu")
		(net "GND")
	)
	(segment
		(start 74.43978 -142.525242)
		(end 74.43978 -141.69898)
		(width 0.508)
		(layer "B.Cu")
		(net "GND")
	)
	(segment
		(start 59.78144 -137.094214)
		(end 61.241432 -137.094214)
		(width 0.508)
		(layer "B.Cu")
		(net "GND")
	)
	(segment
		(start 93.2688 -133.814058)
		(end 93.2688 -133.813804)
		(width 0.3556)
		(layer "B.Cu")
		(net "GND")
	)
	(segment
		(start 92.00642 -139.872466)
		(end 92.151454 -139.727432)
		(width 0.508)
		(layer "B.Cu")
		(net "GND")
	)
	(segment
		(start 51.451002 -162.1028)
		(end 51.044602 -161.6964)
		(width 0.508)
		(layer "B.Cu")
		(net "GND")
	)
	(segment
		(start 85.725508 -149.756622)
		(end 85.377528 -149.756622)
		(width 0.381)
		(layer "B.Cu")
		(net "GND")
	)
	(segment
		(start 35.4965 -157.5308)
		(end 34.720022 -157.5308)
		(width 0.508)
		(layer "B.Cu")
		(net "GND")
	)
	(segment
		(start 89.292938 -164.068252)
		(end 89.916 -163.44519)
		(width 0.508)
		(layer "B.Cu")
		(net "GND")
	)
	(segment
		(start 50.0126 -122.682)
		(end 50.6349 -122.682)
		(width 0.508)
		(layer "B.Cu")
		(net "GND")
	)
	(segment
		(start 84.244942 -148.624036)
		(end 84.244942 -147.307046)
		(width 0.381)
		(layer "B.Cu")
		(net "GND")
	)
	(segment
		(start 62.140846 -136.1948)
		(end 62.8777 -136.1948)
		(width 0.508)
		(layer "B.Cu")
		(net "GND")
	)
	(segment
		(start 76.11237 -144.837658)
		(end 75.512168 -145.43786)
		(width 0.3556)
		(layer "B.Cu")
		(net "GND")
	)
	(segment
		(start 132.8928 -21.75002)
		(end 133.4008 -21.24202)
		(width 0.508)
		(layer "B.Cu")
		(net "GND")
	)
	(segment
		(start 30.549342 -127.205486)
		(end 30.549342 -128.110742)
		(width 0.508)
		(layer "B.Cu")
		(net "GND")
	)
	(segment
		(start 75.9714 -149.6568)
		(end 75.9714 -150.518622)
		(width 0.381)
		(layer "B.Cu")
		(net "GND")
	)
	(segment
		(start 48.56734 -156.9466)
		(end 48.513492 -156.892752)
		(width 0.254)
		(layer "B.Cu")
		(net "GND")
	)
	(segment
		(start 57.731152 -161.083752)
		(end 58.1406 -161.4932)
		(width 0.508)
		(layer "B.Cu")
		(net "GND")
	)
	(segment
		(start 23.777702 -146.418046)
		(end 24.456898 -146.418046)
		(width 0.508)
		(layer "B.Cu")
		(net "GND")
	)
	(segment
		(start 30.897322 -156.991558)
		(end 30.897322 -157.291278)
		(width 0.254)
		(layer "B.Cu")
		(net "GND")
	)
	(segment
		(start 93.4974 -131.41706)
		(end 93.4974 -130.3274)
		(width 0.254)
		(layer "B.Cu")
		(net "GND")
	)
	(segment
		(start 36.59124 -126.62916)
		(end 36.83 -126.3904)
		(width 0.254)
		(layer "B.Cu")
		(net "GND")
	)
	(segment
		(start 208.341214 -84.205826)
		(end 208.294986 -84.252054)
		(width 0.508)
		(layer "B.Cu")
		(net "GND")
	)
	(segment
		(start 32.0929 -162.306)
		(end 26.67 -162.306)
		(width 0.508)
		(layer "B.Cu")
		(net "GND")
	)
	(segment
		(start 92.76842 -134.314184)
		(end 92.792804 -134.2898)
		(width 0.3556)
		(layer "B.Cu")
		(net "GND")
	)
	(segment
		(start 58.631836 -147.743164)
		(end 58.6486 -147.7264)
		(width 0.508)
		(layer "B.Cu")
		(net "GND")
	)
	(segment
		(start 55.66664 -128.07442)
		(end 56.37784 -128.07442)
		(width 0.254)
		(layer "B.Cu")
		(net "GND")
	)
	(segment
		(start 83.727544 -153.358596)
		(end 83.194652 -153.358596)
		(width 0.508)
		(layer "B.Cu")
		(net "GND")
	)
	(segment
		(start 24.456898 -146.418046)
		(end 25.444958 -146.418046)
		(width 0.508)
		(layer "B.Cu")
		(net "GND")
	)
	(segment
		(start 92.928186 -129.463546)
		(end 92.928186 -129.758186)
		(width 0.508)
		(layer "B.Cu")
		(net "GND")
	)
	(segment
		(start 56.3372 -156.1592)
		(end 56.3372 -155.3845)
		(width 0.508)
		(layer "B.Cu")
		(net "GND")
	)
	(segment
		(start 48.178212 -135.274812)
		(end 47.9044 -135.001)
		(width 0.508)
		(layer "B.Cu")
		(net "GND")
	)
	(segment
		(start 77.668628 -135.936228)
		(end 76.5429 -134.8105)
		(width 0.508)
		(layer "B.Cu")
		(net "GND")
	)
	(segment
		(start 17.078706 -148.0058)
		(end 17.234408 -148.161502)
		(width 0.508)
		(layer "B.Cu")
		(net "GND")
	)
	(segment
		(start 78.296516 -135.935974)
		(end 78.296262 -135.936228)
		(width 0.508)
		(layer "B.Cu")
		(net "GND")
	)
	(segment
		(start 90.408506 -137.207752)
		(end 90.010488 -137.207752)
		(width 0.508)
		(layer "B.Cu")
		(net "GND")
	)
	(segment
		(start 38.09238 -149.32914)
		(end 37.6555 -149.76602)
		(width 0.508)
		(layer "B.Cu")
		(net "GND")
	)
	(segment
		(start 178.25085 -113.280444)
		(end 179.39385 -113.280444)
		(width 0.508)
		(layer "B.Cu")
		(net "GND")
	)
	(segment
		(start 51.71567 -154.52217)
		(end 51.71567 -153.878534)
		(width 0.508)
		(layer "B.Cu")
		(net "GND")
	)
	(segment
		(start 56.896 -157.2895)
		(end 56.896 -156.718)
		(width 0.508)
		(layer "B.Cu")
		(net "GND")
	)
	(segment
		(start 92.00642 -140.05306)
		(end 92.00642 -139.872466)
		(width 0.508)
		(layer "B.Cu")
		(net "GND")
	)
	(segment
		(start 92.928186 -129.758186)
		(end 93.4974 -130.3274)
		(width 0.508)
		(layer "B.Cu")
		(net "GND")
	)
	(segment
		(start 89.811606 -131.951984)
		(end 90.084148 -131.951984)
		(width 0.254)
		(layer "B.Cu")
		(net "GND")
	)
	(segment
		(start 39.370762 -149.32914)
		(end 38.09238 -149.32914)
		(width 0.508)
		(layer "B.Cu")
		(net "GND")
	)
	(segment
		(start 31.4579 -128.1684)
		(end 30.607 -128.1684)
		(width 0.508)
		(layer "B.Cu")
		(net "GND")
	)
	(segment
		(start 93.5736 -144.112488)
		(end 93.573346 -144.112488)
		(width 0.254)
		(layer "B.Cu")
		(net "GND")
	)
	(segment
		(start 92.792804 -134.2898)
		(end 92.793058 -134.2898)
		(width 0.3556)
		(layer "B.Cu")
		(net "GND")
	)
	(segment
		(start 51.8033 -162.1028)
		(end 51.451002 -162.1028)
		(width 0.508)
		(layer "B.Cu")
		(net "GND")
	)
	(segment
		(start 66.5226 -149.5806)
		(end 67.2719 -149.5806)
		(width 0.508)
		(layer "B.Cu")
		(net "GND")
	)
	(segment
		(start 39.699946 -148.999956)
		(end 39.370762 -149.32914)
		(width 0.508)
		(layer "B.Cu")
		(net "GND")
	)
	(segment
		(start 61.6839 -149.7584)
		(end 62.6872 -149.7584)
		(width 0.508)
		(layer "B.Cu")
		(net "GND")
	)
	(segment
		(start 83.0326 -129.286)
		(end 82.69224 -129.62636)
		(width 0.254)
		(layer "B.Cu")
		(net "GND")
	)
	(segment
		(start 15.6845 -138.6967)
		(end 15.5194 -138.8618)
		(width 0.508)
		(layer "B.Cu")
		(net "GND")
	)
	(segment
		(start 122.447304 -10.469626)
		(end 121.245122 -10.469626)
		(width 0.508)
		(layer "B.Cu")
		(net "GND")
	)
	(segment
		(start 91.67622 -147.964144)
		(end 91.68892 -147.976844)
		(width 0.508)
		(layer "B.Cu")
		(net "GND")
	)
	(segment
		(start 42.357294 -125.03658)
		(end 43.40098 -125.03658)
		(width 0.508)
		(layer "B.Cu")
		(net "GND")
	)
	(segment
		(start 93.9292 -146.8247)
		(end 94.425008 -146.8247)
		(width 0.508)
		(layer "B.Cu")
		(net "GND")
	)
	(segment
		(start 132.41782 -21.75002)
		(end 132.8928 -21.75002)
		(width 0.508)
		(layer "B.Cu")
		(net "GND")
	)
	(segment
		(start 51.8287 -154.6352)
		(end 51.71567 -154.52217)
		(width 0.508)
		(layer "B.Cu")
		(net "GND")
	)
	(segment
		(start 25.444958 -146.418046)
		(end 25.44572 -146.418808)
		(width 0.508)
		(layer "B.Cu")
		(net "GND")
	)
	(segment
		(start 93.5736 -144.11325)
		(end 93.5736 -144.112488)
		(width 0.254)
		(layer "B.Cu")
		(net "GND")
	)
	(segment
		(start 36.531042 -155.472384)
		(end 37.508942 -155.472384)
		(width 0.254)
		(layer "B.Cu")
		(net "GND")
	)
	(segment
		(start 53.0098 -134.536942)
		(end 53.0098 -134.3914)
		(width 0.508)
		(layer "B.Cu")
		(net "GND")
	)
	(segment
		(start 206.183992 -107.349798)
		(end 206.183992 -106.27487)
		(width 0.3048)
		(layer "B.Cu")
		(net "GND")
	)
	(segment
		(start 51.8033 -161.1376)
		(end 51.603402 -161.1376)
		(width 0.508)
		(layer "B.Cu")
		(net "GND")
	)
	(segment
		(start 92.76842 -134.57936)
		(end 92.76842 -134.314184)
		(width 0.3556)
		(layer "B.Cu")
		(net "GND")
	)
	(segment
		(start 16.6116 -138.6967)
		(end 15.6845 -138.6967)
		(width 0.508)
		(layer "B.Cu")
		(net "GND")
	)
	(segment
		(start 48.39716 -121.06656)
		(end 49.8094 -122.4788)
		(width 0.254)
		(layer "B.Cu")
		(net "GND")
	)
	(segment
		(start 72.335644 -151.998426)
		(end 71.501 -151.998426)
		(width 0.508)
		(layer "B.Cu")
		(net "GND")
	)
	(segment
		(start 63.8175 -154.8892)
		(end 62.871096 -154.8892)
		(width 0.508)
		(layer "B.Cu")
		(net "GND")
	)
	(segment
		(start 89.916 -163.44519)
		(end 89.916 -162.0266)
		(width 0.508)
		(layer "B.Cu")
		(net "GND")
	)
	(segment
		(start 54.6735 -162.1536)
		(end 54.864 -162.1536)
		(width 0.508)
		(layer "B.Cu")
		(net "GND")
	)
	(segment
		(start 84.244942 -147.307046)
		(end 85.070442 -147.307046)
		(width 0.508)
		(layer "B.Cu")
		(net "GND")
	)
	(segment
		(start 90.678 -149.0345)
		(end 90.678 -148.463)
		(width 0.508)
		(layer "B.Cu")
		(net "GND")
	)
	(segment
		(start 62.2554 -161.544)
		(end 62.2554 -162.433)
		(width 0.508)
		(layer "B.Cu")
		(net "GND")
	)
	(segment
		(start 91.68892 -149.081744)
		(end 91.68892 -147.976844)
		(width 0.508)
		(layer "B.Cu")
		(net "GND")
	)
	(segment
		(start 49.8094 -122.4788)
		(end 50.0126 -122.682)
		(width 0.508)
		(layer "B.Cu")
		(net "GND")
	)
	(segment
		(start 46.682152 -136.782302)
		(end 46.89983 -136.99998)
		(width 0.508)
		(layer "B.Cu")
		(net "GND")
	)
	(segment
		(start 32.4993 -158.2928)
		(end 32.0421 -158.75)
		(width 0.508)
		(layer "B.Cu")
		(net "GND")
	)
	(segment
		(start 34.469324 -157.781498)
		(end 33.958022 -158.2928)
		(width 0.508)
		(layer "B.Cu")
		(net "GND")
	)
	(segment
		(start 57.3786 -155.3591)
		(end 57.3786 -156.21)
		(width 0.508)
		(layer "B.Cu")
		(net "GND")
	)
	(segment
		(start 83.67649 -55.393336)
		(end 82.560668 -55.393336)
		(width 0.508)
		(layer "B.Cu")
		(net "GND")
	)
	(segment
		(start 93.269054 -133.8072)
		(end 93.345 -133.8072)
		(width 0.3556)
		(layer "B.Cu")
		(net "GND")
	)
	(segment
		(start 89.123266 -132.1816)
		(end 89.58199 -132.1816)
		(width 0.254)
		(layer "B.Cu")
		(net "GND")
	)
	(segment
		(start 54.4576 -120.6881)
		(end 56.4134 -120.6881)
		(width 0.508)
		(layer "B.Cu")
		(net "GND")
	)
	(segment
		(start 54.864 -162.1536)
		(end 55.5752 -161.4424)
		(width 0.508)
		(layer "B.Cu")
		(net "GND")
	)
	(segment
		(start 46.66234 -121.06656)
		(end 48.39716 -121.06656)
		(width 0.254)
		(layer "B.Cu")
		(net "GND")
	)
	(segment
		(start 62.871096 -154.8892)
		(end 62.760352 -154.999944)
		(width 0.508)
		(layer "B.Cu")
		(net "GND")
	)
	(segment
		(start 37.508942 -155.472384)
		(end 37.521642 -155.485084)
		(width 0.254)
		(layer "B.Cu")
		(net "GND")
	)
	(segment
		(start 56.4134 -120.2563)
		(end 56.4134 -120.6881)
		(width 0.508)
		(layer "B.Cu")
		(net "GND")
	)
	(segment
		(start 195.641976 -137.218674)
		(end 195.641976 -136.262364)
		(width 0.508)
		(layer "B.Cu")
		(net "GND")
	)
	(segment
		(start 52.7304 -127.587248)
		(end 52.705 -127.612648)
		(width 0.508)
		(layer "B.Cu")
		(net "GND")
	)
	(segment
		(start 88.471756 -162.251644)
		(end 88.6968 -162.0266)
		(width 0.508)
		(layer "B.Cu")
		(net "GND")
	)
	(segment
		(start 48.887634 -156.054552)
		(end 48.887634 -156.626306)
		(width 0.254)
		(layer "B.Cu")
		(net "GND")
	)
	(segment
		(start 131.79806 -15.17142)
		(end 131.64185 -15.32763)
		(width 0.508)
		(layer "B.Cu")
		(net "GND")
	)
	(segment
		(start 30.897322 -157.291278)
		(end 30.4546 -157.734)
		(width 0.254)
		(layer "B.Cu")
		(net "GND")
	)
	(segment
		(start 92.151454 -138.852656)
		(end 92.151454 -139.216638)
		(width 0.508)
		(layer "B.Cu")
		(net "GND")
	)
	(segment
		(start 55.8165 -118.6942)
		(end 55.8165 -119.6594)
		(width 0.508)
		(layer "B.Cu")
		(net "GND")
	)
	(segment
		(start 54.6735 -161.163)
		(end 55.2958 -161.163)
		(width 0.508)
		(layer "B.Cu")
		(net "GND")
	)
	(segment
		(start 92.00642 -138.707622)
		(end 92.151454 -138.852656)
		(width 0.508)
		(layer "B.Cu")
		(net "GND")
	)
	(segment
		(start 86.174326 -147.124674)
		(end 85.991954 -147.307046)
		(width 0.508)
		(layer "B.Cu")
		(net "GND")
	)
	(segment
		(start 86.489794 -168.069006)
		(end 86.36 -168.1988)
		(width 0.3048)
		(layer "B.Cu")
		(net "GND")
	)
	(segment
		(start 82.560668 -55.393336)
		(end 82.255868 -55.698136)
		(width 0.508)
		(layer "B.Cu")
		(net "GND")
	)
	(segment
		(start 83.0326 -128.9558)
		(end 83.0326 -129.286)
		(width 0.254)
		(layer "B.Cu")
		(net "GND")
	)
	(segment
		(start 90.010488 -137.207752)
		(end 89.594436 -137.623804)
		(width 0.508)
		(layer "B.Cu")
		(net "GND")
	)
	(segment
		(start 54.082442 -155.542742)
		(end 54.082442 -156.21)
		(width 0.508)
		(layer "B.Cu")
		(net "GND")
	)
	(segment
		(start 208.341214 -83.069176)
		(end 208.341214 -84.205826)
		(width 0.508)
		(layer "B.Cu")
		(net "GND")
	)
	(segment
		(start 57.291732 -162.025076)
		(end 57.634124 -162.025076)
		(width 0.508)
		(layer "B.Cu")
		(net "GND")
	)
	(segment
		(start 51.6382 -159.7406)
		(end 51.36007 -159.46247)
		(width 0.254)
		(layer "B.Cu")
		(net "GND")
	)
	(segment
		(start 218.85783 -54.334664)
		(end 218.85783 -53.89499)
		(width 0.254)
		(layer "B.Cu")
		(net "GND")
	)
	(segment
		(start 42.494454 -149.281134)
		(end 42.494454 -148.852128)
		(width 0.127)
		(layer "In2.Cu")
		(net "GND")
	)
	(segment
		(start 53.702204 -149.39772)
		(end 53.123084 -149.39772)
		(width 0.127)
		(layer "In2.Cu")
		(net "GND")
	)
	(segment
		(start 52.895754 -150.203916)
		(end 52.499768 -150.599902)
		(width 0.127)
		(layer "In2.Cu")
		(net "GND")
	)
	(segment
		(start 52.895754 -150.203916)
		(end 53.51145 -150.203916)
		(width 0.127)
		(layer "In2.Cu")
		(net "GND")
	)
	(segment
		(start 42.618914 -147.794218)
		(end 43.181016 -147.794218)
		(width 0.127)
		(layer "In2.Cu")
		(net "GND")
	)
	(segment
		(start 53.702204 -150.013162)
		(end 53.702204 -149.39772)
		(width 0.127)
		(layer "In2.Cu")
		(net "GND")
	)
	(segment
		(start 52.895754 -149.62505)
		(end 52.895754 -150.203916)
		(width 0.127)
		(layer "In2.Cu")
		(net "GND")
	)
	(segment
		(start 43.18127 -148.605494)
		(end 42.752264 -148.605494)
		(width 0.127)
		(layer "In2.Cu")
		(net "GND")
	)
	(segment
		(start 53.51145 -150.203916)
		(end 53.702204 -150.013162)
		(width 0.127)
		(layer "In2.Cu")
		(net "GND")
	)
	(segment
		(start 53.702204 -149.39772)
		(end 54.099968 -148.999956)
		(width 0.127)
		(layer "In2.Cu")
		(net "GND")
	)
	(segment
		(start 53.123084 -149.39772)
		(end 52.895754 -149.62505)
		(width 0.127)
		(layer "In2.Cu")
		(net "GND")
	)
	(segment
		(start 20.705572 -15.24127)
		(end 19.880072 -15.24127)
		(width 0.127)
		(layer "F.Cu")
		(net "FP_PWR_BTN_N")
	)
	(segment
		(start 19.562572 -14.92377)
		(end 18.737072 -14.92377)
		(width 0.127)
		(layer "F.Cu")
		(net "FP_PWR_BTN_N")
	)
	(segment
		(start 20.84832 -8.750046)
		(end 20.846796 -8.75157)
		(width 0.127)
		(layer "F.Cu")
		(net "FP_PWR_BTN_N")
	)
	(segment
		(start 19.418808 -8.75157)
		(end 18.737072 -9.433306)
		(width 0.127)
		(layer "F.Cu")
		(net "FP_PWR_BTN_N")
	)
	(segment
		(start 19.880072 -15.24127)
		(end 19.562572 -14.92377)
		(width 0.127)
		(layer "F.Cu")
		(net "FP_PWR_BTN_N")
	)
	(segment
		(start 18.737072 -9.433306)
		(end 18.737072 -14.92377)
		(width 0.127)
		(layer "F.Cu")
		(net "FP_PWR_BTN_N")
	)
	(segment
		(start 21.912072 -14.92377)
		(end 21.023072 -14.92377)
		(width 0.127)
		(layer "F.Cu")
		(net "FP_PWR_BTN_N")
	)
	(segment
		(start 20.846796 -8.75157)
		(end 19.418808 -8.75157)
		(width 0.127)
		(layer "F.Cu")
		(net "FP_PWR_BTN_N")
	)
	(segment
		(start 21.023072 -14.92377)
		(end 20.705572 -15.24127)
		(width 0.127)
		(layer "F.Cu")
		(net "FP_PWR_BTN_N")
	)
	(segment
		(start 21.75002 -8.750046)
		(end 20.84832 -8.750046)
		(width 0.127)
		(layer "F.Cu")
		(net "FP_PWR_BTN_N")
	)
	(segment
		(start 74.37247 -138.863324)
		(end 75.248516 -138.863324)
		(width 0.127)
		(layer "F.Cu")
		(net "FP_PWR_BTN_N")
	)
	(via
		(at 21.912072 -14.92377)
		(size 0.508)
		(drill 0.254)
		(layers "F.Cu" "B.Cu")
		(net "FP_PWR_BTN_N")
	)
	(via
		(at 75.248516 -138.863324)
		(size 0.508)
		(drill 0.254)
		(layers "F.Cu" "B.Cu")
		(net "FP_PWR_BTN_N")
	)
	(via
		(at 30.793182 -114.5286)
		(size 0.508)
		(drill 0.254)
		(layers "F.Cu" "B.Cu")
		(net "FP_PWR_BTN_N")
	)
	(via
		(at 74.6252 -135.636)
		(size 0.6096)
		(drill 0.3048)
		(layers "F.Cu" "B.Cu")
		(net "FP_PWR_BTN_N")
	)
	(segment
		(start 34.383218 -116.84)
		(end 41.0972 -116.84)
		(width 0.127)
		(layer "B.Cu")
		(net "FP_PWR_BTN_N")
	)
	(segment
		(start 48.264064 -116.2939)
		(end 48.716946 -115.841018)
		(width 0.127)
		(layer "B.Cu")
		(net "FP_PWR_BTN_N")
	)
	(segment
		(start 53.804566 -115.841018)
		(end 65.424812 -127.461264)
		(width 0.127)
		(layer "B.Cu")
		(net "FP_PWR_BTN_N")
	)
	(segment
		(start 65.424812 -127.461264)
		(end 68.895468 -127.461264)
		(width 0.127)
		(layer "B.Cu")
		(net "FP_PWR_BTN_N")
	)
	(segment
		(start 41.6433 -116.2939)
		(end 48.264064 -116.2939)
		(width 0.127)
		(layer "B.Cu")
		(net "FP_PWR_BTN_N")
	)
	(segment
		(start 68.895468 -127.461264)
		(end 71.2089 -129.774696)
		(width 0.127)
		(layer "B.Cu")
		(net "FP_PWR_BTN_N")
	)
	(segment
		(start 48.716946 -115.841018)
		(end 53.804566 -115.841018)
		(width 0.127)
		(layer "B.Cu")
		(net "FP_PWR_BTN_N")
	)
	(segment
		(start 30.793182 -114.5286)
		(end 32.071818 -114.5286)
		(width 0.127)
		(layer "B.Cu")
		(net "FP_PWR_BTN_N")
	)
	(segment
		(start 71.2089 -129.774696)
		(end 71.2089 -132.2197)
		(width 0.127)
		(layer "B.Cu")
		(net "FP_PWR_BTN_N")
	)
	(segment
		(start 75.248516 -136.259316)
		(end 75.248516 -138.863324)
		(width 0.127)
		(layer "B.Cu")
		(net "FP_PWR_BTN_N")
	)
	(segment
		(start 74.6252 -135.636)
		(end 75.248516 -136.259316)
		(width 0.127)
		(layer "B.Cu")
		(net "FP_PWR_BTN_N")
	)
	(segment
		(start 41.0972 -116.84)
		(end 41.6433 -116.2939)
		(width 0.127)
		(layer "B.Cu")
		(net "FP_PWR_BTN_N")
	)
	(segment
		(start 32.071818 -114.5286)
		(end 34.383218 -116.84)
		(width 0.127)
		(layer "B.Cu")
		(net "FP_PWR_BTN_N")
	)
	(segment
		(start 71.2089 -132.2197)
		(end 74.6252 -135.636)
		(width 0.127)
		(layer "B.Cu")
		(net "FP_PWR_BTN_N")
	)
	(segment
		(start 26.6446 -72.514968)
		(end 26.6446 -109.89945)
		(width 0.127)
		(layer "In2.Cu")
		(net "FP_PWR_BTN_N")
	)
	(segment
		(start 16.819372 -57.684416)
		(end 16.819372 -62.68974)
		(width 0.127)
		(layer "In2.Cu")
		(net "FP_PWR_BTN_N")
	)
	(segment
		(start 21.912072 -14.92377)
		(end 23.46833 -14.92377)
		(width 0.127)
		(layer "In2.Cu")
		(net "FP_PWR_BTN_N")
	)
	(segment
		(start 26.8732 -47.630588)
		(end 16.819372 -57.684416)
		(width 0.127)
		(layer "In2.Cu")
		(net "FP_PWR_BTN_N")
	)
	(segment
		(start 16.819372 -62.68974)
		(end 26.6446 -72.514968)
		(width 0.127)
		(layer "In2.Cu")
		(net "FP_PWR_BTN_N")
	)
	(segment
		(start 26.6446 -109.89945)
		(end 30.793182 -114.048032)
		(width 0.127)
		(layer "In2.Cu")
		(net "FP_PWR_BTN_N")
	)
	(segment
		(start 30.793182 -114.048032)
		(end 30.793182 -114.5286)
		(width 0.127)
		(layer "In2.Cu")
		(net "FP_PWR_BTN_N")
	)
	(segment
		(start 26.8732 -18.32864)
		(end 26.8732 -47.630588)
		(width 0.127)
		(layer "In2.Cu")
		(net "FP_PWR_BTN_N")
	)
	(segment
		(start 23.46833 -14.92377)
		(end 26.8732 -18.32864)
		(width 0.127)
		(layer "In2.Cu")
		(net "FP_PWR_BTN_N")
	)
	(segment
		(start 70.239636 -138.895836)
		(end 70.35673 -139.01293)
		(width 0.127)
		(layer "F.Cu")
		(net "FP_PWRBTN")
	)
	(segment
		(start 70.35673 -139.01293)
		(end 70.35673 -141.7574)
		(width 0.127)
		(layer "F.Cu")
		(net "FP_PWRBTN")
	)
	(segment
		(start 70.07225 -137.981436)
		(end 69.65823 -138.395456)
		(width 0.127)
		(layer "F.Cu")
		(net "FP_PWRBTN")
	)
	(segment
		(start 69.65823 -138.395456)
		(end 69.65823 -138.895836)
		(width 0.127)
		(layer "F.Cu")
		(net "FP_PWRBTN")
	)
	(segment
		(start 69.65823 -138.895836)
		(end 70.239636 -138.895836)
		(width 0.127)
		(layer "F.Cu")
		(net "FP_PWRBTN")
	)
	(segment
		(start 70.07225 -137.444734)
		(end 70.07225 -137.981436)
		(width 0.127)
		(layer "F.Cu")
		(net "FP_PWRBTN")
	)
	(segment
		(start 70.35673 -141.7574)
		(end 71.269606 -142.670276)
		(width 0.127)
		(layer "F.Cu")
		(net "FP_PWRBTN")
	)
	(segment
		(start 71.269606 -142.670276)
		(end 71.37273 -142.670276)
		(width 0.127)
		(layer "F.Cu")
		(net "FP_PWRBTN")
	)
	(via
		(at 70.35673 -141.7574)
		(size 0.6604)
		(drill 0.3302)
		(layers "F.Cu" "B.Cu")
		(net "FP_PWRBTN")
	)
	(segment
		(start 63.90132 -178.3715)
		(end 62.865 -178.3715)
		(width 0.127)
		(layer "F.Cu")
		(net "FM_BMC_RESET_N")
	)
	(segment
		(start 63.9064 -178.36642)
		(end 63.90132 -178.3715)
		(width 0.127)
		(layer "F.Cu")
		(net "FM_BMC_RESET_N")
	)
	(segment
		(start 62.865 -178.3715)
		(end 63.126874 -178.109626)
		(width 0.127)
		(layer "F.Cu")
		(net "FM_BMC_RESET_N")
	)
	(segment
		(start 63.126874 -178.109626)
		(end 63.126874 -175.964596)
		(width 0.127)
		(layer "F.Cu")
		(net "FM_BMC_RESET_N")
	)
	(segment
		(start 64.7446 -178.2953)
		(end 64.67348 -178.36642)
		(width 0.127)
		(layer "F.Cu")
		(net "FM_BMC_RESET_N")
	)
	(segment
		(start 64.67348 -178.36642)
		(end 63.9064 -178.36642)
		(width 0.127)
		(layer "F.Cu")
		(net "FM_BMC_RESET_N")
	)
	(via
		(at 42.357294 -126.7206)
		(size 0.508)
		(drill 0.254)
		(layers "F.Cu" "B.Cu")
		(net "FM_BMC_RESET_N")
	)
	(via
		(at 64.7446 -178.2953)
		(size 0.508)
		(drill 0.254)
		(layers "F.Cu" "B.Cu")
		(net "FM_BMC_RESET_N")
	)
	(via
		(at 70.2056 -177.9651)
		(size 0.508)
		(drill 0.254)
		(layers "F.Cu" "B.Cu")
		(net "FM_BMC_RESET_N")
	)
	(via
		(at 69.920104 -125.480318)
		(size 0.508)
		(drill 0.254)
		(layers "F.Cu" "B.Cu")
		(net "FM_BMC_RESET_N")
	)
	(segment
		(start 43.565826 -125.92558)
		(end 43.63212 -125.991874)
		(width 0.127)
		(layer "B.Cu")
		(net "FM_BMC_RESET_N")
	)
	(segment
		(start 42.357294 -125.92558)
		(end 42.357294 -126.7206)
		(width 0.127)
		(layer "B.Cu")
		(net "FM_BMC_RESET_N")
	)
	(segment
		(start 42.357294 -125.92558)
		(end 43.565826 -125.92558)
		(width 0.127)
		(layer "B.Cu")
		(net "FM_BMC_RESET_N")
	)
	(segment
		(start 42.351198 -127.534416)
		(end 42.351198 -126.726696)
		(width 0.127)
		(layer "B.Cu")
		(net "FM_BMC_RESET_N")
	)
	(segment
		(start 42.352214 -125.9205)
		(end 42.357294 -125.92558)
		(width 0.127)
		(layer "B.Cu")
		(net "FM_BMC_RESET_N")
	)
	(segment
		(start 42.351198 -126.726696)
		(end 42.357294 -126.7206)
		(width 0.127)
		(layer "B.Cu")
		(net "FM_BMC_RESET_N")
	)
	(segment
		(start 41.3258 -125.9205)
		(end 42.352214 -125.9205)
		(width 0.127)
		(layer "B.Cu")
		(net "FM_BMC_RESET_N")
	)
	(segment
		(start 73.690226 -174.480474)
		(end 73.690226 -170.588686)
		(width 0.127)
		(layer "In2.Cu")
		(net "FM_BMC_RESET_N")
	)
	(segment
		(start 73.6727 -158.223712)
		(end 73.6727 -148.293074)
		(width 0.127)
		(layer "In2.Cu")
		(net "FM_BMC_RESET_N")
	)
	(segment
		(start 73.690226 -170.588686)
		(end 72.48398 -169.38244)
		(width 0.127)
		(layer "In2.Cu")
		(net "FM_BMC_RESET_N")
	)
	(segment
		(start 70.3326 -135.655812)
		(end 70.3326 -130.4671)
		(width 0.127)
		(layer "In2.Cu")
		(net "FM_BMC_RESET_N")
	)
	(segment
		(start 73.6727 -148.293074)
		(end 71.113396 -145.73377)
		(width 0.127)
		(layer "In2.Cu")
		(net "FM_BMC_RESET_N")
	)
	(segment
		(start 71.113396 -145.73377)
		(end 71.113396 -145.491962)
		(width 0.127)
		(layer "In2.Cu")
		(net "FM_BMC_RESET_N")
	)
	(segment
		(start 70.499224 -135.822436)
		(end 70.3326 -135.655812)
		(width 0.127)
		(layer "In2.Cu")
		(net "FM_BMC_RESET_N")
	)
	(segment
		(start 70.9803 -129.8194)
		(end 70.9803 -126.540514)
		(width 0.127)
		(layer "In2.Cu")
		(net "FM_BMC_RESET_N")
	)
	(segment
		(start 70.2056 -177.9651)
		(end 73.690226 -174.480474)
		(width 0.127)
		(layer "In2.Cu")
		(net "FM_BMC_RESET_N")
	)
	(segment
		(start 70.3326 -130.4671)
		(end 70.9803 -129.8194)
		(width 0.127)
		(layer "In2.Cu")
		(net "FM_BMC_RESET_N")
	)
	(segment
		(start 71.113396 -145.491962)
		(end 70.499224 -144.87779)
		(width 0.127)
		(layer "In2.Cu")
		(net "FM_BMC_RESET_N")
	)
	(segment
		(start 70.9803 -126.540514)
		(end 69.920104 -125.480318)
		(width 0.127)
		(layer "In2.Cu")
		(net "FM_BMC_RESET_N")
	)
	(segment
		(start 70.499224 -144.87779)
		(end 70.499224 -135.822436)
		(width 0.127)
		(layer "In2.Cu")
		(net "FM_BMC_RESET_N")
	)
	(segment
		(start 72.48398 -169.38244)
		(end 72.48398 -159.412432)
		(width 0.127)
		(layer "In2.Cu")
		(net "FM_BMC_RESET_N")
	)
	(segment
		(start 72.48398 -159.412432)
		(end 73.6727 -158.223712)
		(width 0.127)
		(layer "In2.Cu")
		(net "FM_BMC_RESET_N")
	)
	(segment
		(start 68.8975 -178.2953)
		(end 69.2277 -177.9651)
		(width 0.127)
		(layer "In5.Cu")
		(net "FM_BMC_RESET_N")
	)
	(segment
		(start 43.563794 -127.9271)
		(end 42.357294 -126.7206)
		(width 0.127)
		(layer "In5.Cu")
		(net "FM_BMC_RESET_N")
	)
	(segment
		(start 51.559968 -127.434848)
		(end 47.73041 -127.434848)
		(width 0.127)
		(layer "In5.Cu")
		(net "FM_BMC_RESET_N")
	)
	(segment
		(start 54.253638 -126.518924)
		(end 52.475892 -126.518924)
		(width 0.127)
		(layer "In5.Cu")
		(net "FM_BMC_RESET_N")
	)
	(segment
		(start 47.73041 -127.434848)
		(end 47.238158 -127.9271)
		(width 0.127)
		(layer "In5.Cu")
		(net "FM_BMC_RESET_N")
	)
	(segment
		(start 69.004434 -125.73)
		(end 66.540634 -125.73)
		(width 0.127)
		(layer "In5.Cu")
		(net "FM_BMC_RESET_N")
	)
	(segment
		(start 69.254116 -125.480318)
		(end 69.004434 -125.73)
		(width 0.127)
		(layer "In5.Cu")
		(net "FM_BMC_RESET_N")
	)
	(segment
		(start 64.7446 -178.2953)
		(end 68.8975 -178.2953)
		(width 0.127)
		(layer "In5.Cu")
		(net "FM_BMC_RESET_N")
	)
	(segment
		(start 66.362834 -125.5522)
		(end 55.220362 -125.5522)
		(width 0.127)
		(layer "In5.Cu")
		(net "FM_BMC_RESET_N")
	)
	(segment
		(start 69.920104 -125.480318)
		(end 69.254116 -125.480318)
		(width 0.127)
		(layer "In5.Cu")
		(net "FM_BMC_RESET_N")
	)
	(segment
		(start 47.238158 -127.9271)
		(end 43.563794 -127.9271)
		(width 0.127)
		(layer "In5.Cu")
		(net "FM_BMC_RESET_N")
	)
	(segment
		(start 66.540634 -125.73)
		(end 66.362834 -125.5522)
		(width 0.127)
		(layer "In5.Cu")
		(net "FM_BMC_RESET_N")
	)
	(segment
		(start 69.2277 -177.9651)
		(end 70.2056 -177.9651)
		(width 0.127)
		(layer "In5.Cu")
		(net "FM_BMC_RESET_N")
	)
	(segment
		(start 52.475892 -126.518924)
		(end 51.559968 -127.434848)
		(width 0.127)
		(layer "In5.Cu")
		(net "FM_BMC_RESET_N")
	)
	(segment
		(start 55.220362 -125.5522)
		(end 54.253638 -126.518924)
		(width 0.127)
		(layer "In5.Cu")
		(net "FM_BMC_RESET_N")
	)
	(segment
		(start 97.917 -136.4996)
		(end 97.5614 -136.4996)
		(width 0.127)
		(layer "F.Cu")
		(net "EEPROM_WP")
	)
	(segment
		(start 97.9805 -136.4361)
		(end 97.9424 -136.4742)
		(width 0.127)
		(layer "F.Cu")
		(net "EEPROM_WP")
	)
	(segment
		(start 96.743774 -135.351774)
		(end 96.288352 -135.351774)
		(width 0.127)
		(layer "F.Cu")
		(net "EEPROM_WP")
	)
	(segment
		(start 97.3582 -135.9662)
		(end 96.743774 -135.351774)
		(width 0.127)
		(layer "F.Cu")
		(net "EEPROM_WP")
	)
	(segment
		(start 97.9805 -135.4836)
		(end 97.9805 -136.4361)
		(width 0.127)
		(layer "F.Cu")
		(net "EEPROM_WP")
	)
	(segment
		(start 97.3582 -136.2964)
		(end 97.3582 -135.9662)
		(width 0.127)
		(layer "F.Cu")
		(net "EEPROM_WP")
	)
	(segment
		(start 97.9424 -136.4742)
		(end 97.917 -136.4996)
		(width 0.127)
		(layer "F.Cu")
		(net "EEPROM_WP")
	)
	(segment
		(start 97.5614 -136.4996)
		(end 97.3582 -136.2964)
		(width 0.127)
		(layer "F.Cu")
		(net "EEPROM_WP")
	)
	(via
		(at 97.9424 -136.4742)
		(size 0.6604)
		(drill 0.3302)
		(layers "F.Cu" "B.Cu")
		(net "EEPROM_WP")
	)
	(segment
		(start 44.099988 -146.99996)
		(end 44.099988 -146.977608)
		(width 0.3556)
		(layer "F.Cu")
		(net "DDR_VREF")
	)
	(segment
		(start 44.099988 -146.977608)
		(end 43.69308 -146.5707)
		(width 0.3556)
		(layer "F.Cu")
		(net "DDR_VREF")
	)
	(segment
		(start 15.881858 -139.761468)
		(end 15.818104 -139.825222)
		(width 0.3048)
		(layer "F.Cu")
		(net "DDR_VREF")
	)
	(segment
		(start 16.834612 -139.761468)
		(end 15.881858 -139.761468)
		(width 0.3048)
		(layer "F.Cu")
		(net "DDR_VREF")
	)
	(via
		(at 38.77056 -148.016468)
		(size 0.6096)
		(drill 0.3048)
		(layers "F.Cu" "B.Cu")
		(net "DDR_VREF")
	)
	(via
		(at 15.818104 -139.825222)
		(size 0.508)
		(drill 0.254)
		(layers "F.Cu" "B.Cu")
		(net "DDR_VREF")
	)
	(via
		(at 43.69308 -146.5707)
		(size 0.4572)
		(drill 0.2032)
		(layers "F.Cu" "B.Cu")
		(net "DDR_VREF")
	)
	(segment
		(start 16.6116 -139.5857)
		(end 16.057626 -139.5857)
		(width 0.508)
		(layer "B.Cu")
		(net "DDR_VREF")
	)
	(segment
		(start 39.1541 -147.632928)
		(end 38.77056 -148.016468)
		(width 0.381)
		(layer "B.Cu")
		(net "DDR_VREF")
	)
	(segment
		(start 39.420292 -146.07921)
		(end 39.1541 -146.345402)
		(width 0.381)
		(layer "B.Cu")
		(net "DDR_VREF")
	)
	(segment
		(start 35.862006 -149.21611)
		(end 36.691316 -148.3868)
		(width 0.508)
		(layer "B.Cu")
		(net "DDR_VREF")
	)
	(segment
		(start 37.2745 -148.3868)
		(end 38.400228 -148.3868)
		(width 0.381)
		(layer "B.Cu")
		(net "DDR_VREF")
	)
	(segment
		(start 39.1541 -146.345402)
		(end 39.1541 -147.632928)
		(width 0.381)
		(layer "B.Cu")
		(net "DDR_VREF")
	)
	(segment
		(start 35.862006 -151.266398)
		(end 35.862006 -149.21611)
		(width 0.508)
		(layer "B.Cu")
		(net "DDR_VREF")
	)
	(segment
		(start 16.057626 -139.5857)
		(end 15.818104 -139.825222)
		(width 0.508)
		(layer "B.Cu")
		(net "DDR_VREF")
	)
	(segment
		(start 43.08475 -146.07921)
		(end 39.420292 -146.07921)
		(width 0.381)
		(layer "B.Cu")
		(net "DDR_VREF")
	)
	(segment
		(start 36.691316 -148.3868)
		(end 37.2745 -148.3868)
		(width 0.508)
		(layer "B.Cu")
		(net "DDR_VREF")
	)
	(segment
		(start 38.400228 -148.3868)
		(end 38.77056 -148.016468)
		(width 0.381)
		(layer "B.Cu")
		(net "DDR_VREF")
	)
	(segment
		(start 49.299622 -151.400002)
		(end 49.299622 -151.399748)
		(width 0.1778)
		(layer "F.Cu")
		(net "DACRSET")
	)
	(segment
		(start 49.299622 -151.399748)
		(end 48.899826 -150.999952)
		(width 0.1778)
		(layer "F.Cu")
		(net "DACRSET")
	)
	(segment
		(start 49.3014 -164.7698)
		(end 49.6824 -164.3888)
		(width 0.1778)
		(layer "F.Cu")
		(net "DACRSET")
	)
	(segment
		(start 49.022 -164.7698)
		(end 49.3014 -164.7698)
		(width 0.1778)
		(layer "F.Cu")
		(net "DACRSET")
	)
	(segment
		(start 49.6824 -164.3888)
		(end 49.6824 -164.084)
		(width 0.1778)
		(layer "F.Cu")
		(net "DACRSET")
	)
	(segment
		(start 48.660812 -163.566602)
		(end 48.660812 -164.408612)
		(width 0.1778)
		(layer "F.Cu")
		(net "DACRSET")
	)
	(segment
		(start 48.660812 -164.408612)
		(end 49.022 -164.7698)
		(width 0.1778)
		(layer "F.Cu")
		(net "DACRSET")
	)
	(via
		(at 49.022 -164.7698)
		(size 0.6604)
		(drill 0.3302)
		(layers "F.Cu" "B.Cu")
		(net "DACRSET")
	)
	(via
		(at 49.299622 -151.400002)
		(size 0.4572)
		(drill 0.2032)
		(layers "F.Cu" "B.Cu")
		(net "DACRSET")
	)
	(via
		(at 49.6824 -164.084)
		(size 0.508)
		(drill 0.254)
		(layers "F.Cu" "B.Cu")
		(net "DACRSET")
	)
	(segment
		(start 51.539902 -162.226498)
		(end 51.539902 -160.709102)
		(width 0.1778)
		(layer "In2.Cu")
		(net "DACRSET")
	)
	(segment
		(start 51.1429 -158.2039)
		(end 51.2318 -158.115)
		(width 0.1778)
		(layer "In2.Cu")
		(net "DACRSET")
	)
	(segment
		(start 51.1429 -160.3121)
		(end 51.1429 -158.2039)
		(width 0.1778)
		(layer "In2.Cu")
		(net "DACRSET")
	)
	(segment
		(start 51.2318 -158.115)
		(end 51.2318 -155.4226)
		(width 0.1778)
		(layer "In2.Cu")
		(net "DACRSET")
	)
	(segment
		(start 49.299622 -151.607012)
		(end 49.299622 -151.400002)
		(width 0.1778)
		(layer "In2.Cu")
		(net "DACRSET")
	)
	(segment
		(start 51.539902 -160.709102)
		(end 51.1429 -160.3121)
		(width 0.1778)
		(layer "In2.Cu")
		(net "DACRSET")
	)
	(segment
		(start 49.7586 -152.06599)
		(end 49.299622 -151.607012)
		(width 0.1778)
		(layer "In2.Cu")
		(net "DACRSET")
	)
	(segment
		(start 51.2318 -155.4226)
		(end 49.7586 -153.9494)
		(width 0.1778)
		(layer "In2.Cu")
		(net "DACRSET")
	)
	(segment
		(start 49.7586 -153.9494)
		(end 49.7586 -152.06599)
		(width 0.1778)
		(layer "In2.Cu")
		(net "DACRSET")
	)
	(segment
		(start 49.6824 -164.084)
		(end 51.539902 -162.226498)
		(width 0.1778)
		(layer "In2.Cu")
		(net "DACRSET")
	)
	(segment
		(start 66.21907 -151.79167)
		(end 65.7098 -151.2824)
		(width 0.127)
		(layer "F.Cu")
		(net "CLK_50M_BMC_NCSI")
	)
	(segment
		(start 55.700676 -151.400764)
		(end 55.299864 -150.999952)
		(width 0.127)
		(layer "F.Cu")
		(net "CLK_50M_BMC_NCSI")
	)
	(segment
		(start 66.21907 -151.983186)
		(end 66.21907 -151.79167)
		(width 0.127)
		(layer "F.Cu")
		(net "CLK_50M_BMC_NCSI")
	)
	(segment
		(start 65.7098 -151.2824)
		(end 64.90589 -151.2824)
		(width 0.127)
		(layer "F.Cu")
		(net "CLK_50M_BMC_NCSI")
	)
	(segment
		(start 59.155584 -155.90393)
		(end 58.052462 -154.800808)
		(width 0.127)
		(layer "F.Cu")
		(net "CLK_50M_BMC_NCSI")
	)
	(segment
		(start 64.90589 -151.2824)
		(end 64.39154 -150.76805)
		(width 0.127)
		(layer "F.Cu")
		(net "CLK_50M_BMC_NCSI")
	)
	(segment
		(start 56.22163 -151.400764)
		(end 55.700676 -151.400764)
		(width 0.127)
		(layer "F.Cu")
		(net "CLK_50M_BMC_NCSI")
	)
	(segment
		(start 58.052462 -154.800808)
		(end 58.052462 -153.231596)
		(width 0.127)
		(layer "F.Cu")
		(net "CLK_50M_BMC_NCSI")
	)
	(segment
		(start 58.052462 -153.231596)
		(end 56.22163 -151.400764)
		(width 0.127)
		(layer "F.Cu")
		(net "CLK_50M_BMC_NCSI")
	)
	(via
		(at 59.155584 -155.90393)
		(size 0.508)
		(drill 0.254)
		(layers "F.Cu" "B.Cu")
		(net "CLK_50M_BMC_NCSI")
	)
	(via
		(at 63.7794 -151.13)
		(size 0.6096)
		(drill 0.3048)
		(layers "F.Cu" "B.Cu")
		(net "CLK_50M_BMC_NCSI")
	)
	(via
		(at 66.21907 -151.983186)
		(size 0.508)
		(drill 0.254)
		(layers "F.Cu" "B.Cu")
		(net "CLK_50M_BMC_NCSI")
	)
	(segment
		(start 62.1411 -152.918414)
		(end 62.1411 -152.840182)
		(width 0.127)
		(layer "B.Cu")
		(net "CLK_50M_BMC_NCSI")
	)
	(segment
		(start 65.365884 -151.13)
		(end 63.7794 -151.13)
		(width 0.127)
		(layer "B.Cu")
		(net "CLK_50M_BMC_NCSI")
	)
	(segment
		(start 62.416182 -152.5651)
		(end 62.494414 -152.5651)
		(width 0.127)
		(layer "B.Cu")
		(net "CLK_50M_BMC_NCSI")
	)
	(segment
		(start 66.21907 -151.983186)
		(end 65.365884 -151.13)
		(width 0.127)
		(layer "B.Cu")
		(net "CLK_50M_BMC_NCSI")
	)
	(segment
		(start 62.494414 -152.5651)
		(end 63.7794 -151.280114)
		(width 0.127)
		(layer "B.Cu")
		(net "CLK_50M_BMC_NCSI")
	)
	(segment
		(start 63.7794 -151.280114)
		(end 63.7794 -151.13)
		(width 0.127)
		(layer "B.Cu")
		(net "CLK_50M_BMC_NCSI")
	)
	(segment
		(start 59.155584 -155.90393)
		(end 62.1411 -152.918414)
		(width 0.127)
		(layer "B.Cu")
		(net "CLK_50M_BMC_NCSI")
	)
	(segment
		(start 62.1411 -152.840182)
		(end 62.416182 -152.5651)
		(width 0.127)
		(layer "B.Cu")
		(net "CLK_50M_BMC_NCSI")
	)
	(segment
		(start 43.299888 -139.799822)
		(end 42.900092 -139.400026)
		(width 0.127)
		(layer "F.Cu")
		(net "BMC0_SRST_N")
	)
	(segment
		(start 43.299888 -139.800076)
		(end 43.299888 -139.799822)
		(width 0.127)
		(layer "F.Cu")
		(net "BMC0_SRST_N")
	)
	(via
		(at 42.900092 -139.400026)
		(size 0.4572)
		(drill 0.2032)
		(layers "F.Cu" "B.Cu")
		(net "BMC0_SRST_N")
	)
	(via
		(at 42.59072 -129.70256)
		(size 0.508)
		(drill 0.254)
		(layers "F.Cu" "B.Cu")
		(net "BMC0_SRST_N")
	)
	(segment
		(start 42.351198 -128.423416)
		(end 42.351198 -129.463038)
		(width 0.127)
		(layer "B.Cu")
		(net "BMC0_SRST_N")
	)
	(segment
		(start 42.351198 -129.463038)
		(end 42.59072 -129.70256)
		(width 0.127)
		(layer "B.Cu")
		(net "BMC0_SRST_N")
	)
	(segment
		(start 42.7863 -137.129012)
		(end 43.293792 -137.636504)
		(width 0.127)
		(layer "In2.Cu")
		(net "BMC0_SRST_N")
	)
	(segment
		(start 43.293792 -137.636504)
		(end 43.293792 -139.006326)
		(width 0.127)
		(layer "In2.Cu")
		(net "BMC0_SRST_N")
	)
	(segment
		(start 43.293792 -139.006326)
		(end 42.900092 -139.400026)
		(width 0.127)
		(layer "In2.Cu")
		(net "BMC0_SRST_N")
	)
	(segment
		(start 42.59072 -129.70256)
		(end 42.59072 -132.50672)
		(width 0.127)
		(layer "In2.Cu")
		(net "BMC0_SRST_N")
	)
	(segment
		(start 42.7863 -132.7023)
		(end 42.7863 -137.129012)
		(width 0.127)
		(layer "In2.Cu")
		(net "BMC0_SRST_N")
	)
	(segment
		(start 42.59072 -132.50672)
		(end 42.7863 -132.7023)
		(width 0.127)
		(layer "In2.Cu")
		(net "BMC0_SRST_N")
	)
	(segment
		(start 54.899814 -147.40001)
		(end 54.500018 -147.000214)
		(width 0.127)
		(layer "F.Cu")
		(net "BMC0_JTAG_RTCK")
	)
	(segment
		(start 54.500018 -147.000214)
		(end 54.500018 -146.99996)
		(width 0.127)
		(layer "F.Cu")
		(net "BMC0_JTAG_RTCK")
	)
	(via
		(at 54.899814 -147.40001)
		(size 0.4572)
		(drill 0.2032)
		(layers "F.Cu" "B.Cu")
		(net "BMC0_JTAG_RTCK")
	)
	(segment
		(start 56.920892 -147.743164)
		(end 56.909462 -147.754594)
		(width 0.127)
		(layer "B.Cu")
		(net "BMC0_JTAG_RTCK")
	)
	(segment
		(start 56.909462 -147.754594)
		(end 55.72125 -147.754594)
		(width 0.127)
		(layer "B.Cu")
		(net "BMC0_JTAG_RTCK")
	)
	(segment
		(start 55.366666 -147.40001)
		(end 55.72125 -147.754594)
		(width 0.127)
		(layer "B.Cu")
		(net "BMC0_JTAG_RTCK")
	)
	(segment
		(start 54.899814 -147.40001)
		(end 55.366666 -147.40001)
		(width 0.127)
		(layer "B.Cu")
		(net "BMC0_JTAG_RTCK")
	)
	(segment
		(start 152.374092 -10.671556)
		(end 152.374092 -9.807194)
		(width 0.254)
		(layer "F.Cu")
		(net "AGND_P1V8_STBY")
	)
	(segment
		(start 152.210516 -9.643618)
		(end 150.808182 -9.643618)
		(width 0.254)
		(layer "F.Cu")
		(net "AGND_P1V8_STBY")
	)
	(segment
		(start 150.363682 -10.088118)
		(end 149.632416 -10.088118)
		(width 0.254)
		(layer "F.Cu")
		(net "AGND_P1V8_STBY")
	)
	(segment
		(start 149.516338 -9.120378)
		(end 149.516338 -9.97204)
		(width 0.254)
		(layer "F.Cu")
		(net "AGND_P1V8_STBY")
	)
	(segment
		(start 148.83638 -12.81049)
		(end 147.985226 -12.81049)
		(width 0.254)
		(layer "F.Cu")
		(net "AGND_P1V8_STBY")
	)
	(segment
		(start 150.808182 -9.643618)
		(end 150.363682 -10.088118)
		(width 0.254)
		(layer "F.Cu")
		(net "AGND_P1V8_STBY")
	)
	(segment
		(start 149.516338 -9.97204)
		(end 149.632416 -10.088118)
		(width 0.254)
		(layer "F.Cu")
		(net "AGND_P1V8_STBY")
	)
	(segment
		(start 147.985226 -12.81049)
		(end 147.941538 -12.854178)
		(width 0.254)
		(layer "F.Cu")
		(net "AGND_P1V8_STBY")
	)
	(segment
		(start 152.374092 -9.807194)
		(end 152.210516 -9.643618)
		(width 0.254)
		(layer "F.Cu")
		(net "AGND_P1V8_STBY")
	)
	(via
		(at 147.941538 -12.854178)
		(size 0.508)
		(drill 0.254)
		(layers "F.Cu" "B.Cu")
		(net "AGND_P1V8_STBY")
	)
	(via
		(at 152.210516 -9.643618)
		(size 0.508)
		(drill 0.254)
		(layers "F.Cu" "B.Cu")
		(net "AGND_P1V8_STBY")
	)
	(via
		(at 149.4028 -11.3792)
		(size 0.6096)
		(drill 0.3048)
		(layers "F.Cu" "B.Cu")
		(net "AGND_P1V8_STBY")
	)
	(segment
		(start 149.381464 -11.414252)
		(end 147.941538 -12.854178)
		(width 0.254)
		(layer "B.Cu")
		(net "AGND_P1V8_STBY")
	)
	(segment
		(start 149.381464 -11.400536)
		(end 149.381464 -11.414252)
		(width 0.254)
		(layer "B.Cu")
		(net "AGND_P1V8_STBY")
	)
	(segment
		(start 149.4028 -11.3792)
		(end 149.381464 -11.400536)
		(width 0.254)
		(layer "B.Cu")
		(net "AGND_P1V8_STBY")
	)
	(segment
		(start 151.138382 -9.643618)
		(end 152.210516 -9.643618)
		(width 0.254)
		(layer "B.Cu")
		(net "AGND_P1V8_STBY")
	)
	(segment
		(start 149.4028 -11.3792)
		(end 151.138382 -9.643618)
		(width 0.254)
		(layer "B.Cu")
		(net "AGND_P1V8_STBY")
	)
	(segment
		(start 51.7144 -150.599648)
		(end 51.7144 -150.585424)
		(width 0.127)
		(layer "F.Cu")
		(net "ADC_P5V_STBY")
	)
	(segment
		(start 51.7144 -150.585424)
		(end 52.099972 -150.199852)
		(width 0.127)
		(layer "F.Cu")
		(net "ADC_P5V_STBY")
	)
	(segment
		(start 51.6763 -150.599648)
		(end 51.7144 -150.599648)
		(width 0.127)
		(layer "F.Cu")
		(net "ADC_P5V_STBY")
	)
	(via
		(at 55.744364 -159.549084)
		(size 0.6096)
		(drill 0.3048)
		(layers "F.Cu" "B.Cu")
		(net "ADC_P5V_STBY")
	)
	(via
		(at 51.6763 -150.599648)
		(size 0.4572)
		(drill 0.2032)
		(layers "F.Cu" "B.Cu")
		(net "ADC_P5V_STBY")
	)
	(segment
		(start 56.405526 -161.083752)
		(end 56.392826 -161.083752)
		(width 0.127)
		(layer "B.Cu")
		(net "ADC_P5V_STBY")
	)
	(segment
		(start 55.744364 -160.43529)
		(end 55.744364 -159.549084)
		(width 0.127)
		(layer "B.Cu")
		(net "ADC_P5V_STBY")
	)
	(segment
		(start 55.744364 -159.122364)
		(end 55.744364 -159.549084)
		(width 0.127)
		(layer "B.Cu")
		(net "ADC_P5V_STBY")
	)
	(segment
		(start 54.759352 -154.28722)
		(end 54.774084 -154.301952)
		(width 0.127)
		(layer "B.Cu")
		(net "ADC_P5V_STBY")
	)
	(segment
		(start 54.911752 -156.280612)
		(end 54.911752 -156.672788)
		(width 0.127)
		(layer "B.Cu")
		(net "ADC_P5V_STBY")
	)
	(segment
		(start 53.856382 -153.63698)
		(end 54.109112 -153.63698)
		(width 0.127)
		(layer "B.Cu")
		(net "ADC_P5V_STBY")
	)
	(segment
		(start 52.65039 -150.993602)
		(end 52.893468 -151.23668)
		(width 0.127)
		(layer "B.Cu")
		(net "ADC_P5V_STBY")
	)
	(segment
		(start 54.625748 -154.153362)
		(end 54.759352 -154.286966)
		(width 0.127)
		(layer "B.Cu")
		(net "ADC_P5V_STBY")
	)
	(segment
		(start 54.109112 -153.63698)
		(end 54.625494 -154.153362)
		(width 0.127)
		(layer "B.Cu")
		(net "ADC_P5V_STBY")
	)
	(segment
		(start 56.392826 -161.083752)
		(end 55.744364 -160.43529)
		(width 0.127)
		(layer "B.Cu")
		(net "ADC_P5V_STBY")
	)
	(segment
		(start 51.942492 -150.599648)
		(end 52.336446 -150.993602)
		(width 0.127)
		(layer "B.Cu")
		(net "ADC_P5V_STBY")
	)
	(segment
		(start 54.774084 -156.142944)
		(end 54.911752 -156.280612)
		(width 0.127)
		(layer "B.Cu")
		(net "ADC_P5V_STBY")
	)
	(segment
		(start 56.398668 -163.069524)
		(end 56.402732 -163.06546)
		(width 0.127)
		(layer "B.Cu")
		(net "ADC_P5V_STBY")
	)
	(segment
		(start 54.625494 -154.153362)
		(end 54.625748 -154.153362)
		(width 0.127)
		(layer "B.Cu")
		(net "ADC_P5V_STBY")
	)
	(segment
		(start 52.336446 -150.993602)
		(end 52.65039 -150.993602)
		(width 0.127)
		(layer "B.Cu")
		(net "ADC_P5V_STBY")
	)
	(segment
		(start 54.774084 -158.152084)
		(end 55.744364 -159.122364)
		(width 0.127)
		(layer "B.Cu")
		(net "ADC_P5V_STBY")
	)
	(segment
		(start 56.402732 -162.025076)
		(end 56.405526 -162.022282)
		(width 0.127)
		(layer "B.Cu")
		(net "ADC_P5V_STBY")
	)
	(segment
		(start 54.759352 -154.286966)
		(end 54.759352 -154.28722)
		(width 0.127)
		(layer "B.Cu")
		(net "ADC_P5V_STBY")
	)
	(segment
		(start 56.402732 -163.06546)
		(end 56.402732 -162.025076)
		(width 0.127)
		(layer "B.Cu")
		(net "ADC_P5V_STBY")
	)
	(segment
		(start 51.6763 -150.599648)
		(end 51.942492 -150.599648)
		(width 0.127)
		(layer "B.Cu")
		(net "ADC_P5V_STBY")
	)
	(segment
		(start 54.911752 -156.672788)
		(end 54.774084 -156.810456)
		(width 0.127)
		(layer "B.Cu")
		(net "ADC_P5V_STBY")
	)
	(segment
		(start 54.774084 -154.301952)
		(end 54.774084 -156.142944)
		(width 0.127)
		(layer "B.Cu")
		(net "ADC_P5V_STBY")
	)
	(segment
		(start 52.893468 -152.674066)
		(end 53.856382 -153.63698)
		(width 0.127)
		(layer "B.Cu")
		(net "ADC_P5V_STBY")
	)
	(segment
		(start 56.405526 -162.022282)
		(end 56.405526 -161.083752)
		(width 0.127)
		(layer "B.Cu")
		(net "ADC_P5V_STBY")
	)
	(segment
		(start 52.893468 -151.23668)
		(end 52.893468 -152.674066)
		(width 0.127)
		(layer "B.Cu")
		(net "ADC_P5V_STBY")
	)
	(segment
		(start 54.774084 -156.810456)
		(end 54.774084 -158.152084)
		(width 0.127)
		(layer "B.Cu")
		(net "ADC_P5V_STBY")
	)
	(segment
		(start 54.670706 -157.921706)
		(end 54.670706 -156.75356)
		(width 0.127)
		(layer "F.Cu")
		(net "ADC_P3V3_STBY")
	)
	(segment
		(start 56.792622 -161.059114)
		(end 56.055514 -161.059114)
		(width 0.127)
		(layer "F.Cu")
		(net "ADC_P3V3_STBY")
	)
	(segment
		(start 58.928 -162.3441)
		(end 57.9628 -162.3441)
		(width 0.127)
		(layer "F.Cu")
		(net "ADC_P3V3_STBY")
	)
	(segment
		(start 59.944 -162.3441)
		(end 58.928 -162.3441)
		(width 0.127)
		(layer "F.Cu")
		(net "ADC_P3V3_STBY")
	)
	(segment
		(start 55.7022 -158.9532)
		(end 54.670706 -157.921706)
		(width 0.127)
		(layer "F.Cu")
		(net "ADC_P3V3_STBY")
	)
	(segment
		(start 56.792622 -161.173922)
		(end 56.792622 -161.059114)
		(width 0.127)
		(layer "F.Cu")
		(net "ADC_P3V3_STBY")
	)
	(segment
		(start 57.9628 -162.3441)
		(end 56.792622 -161.173922)
		(width 0.127)
		(layer "F.Cu")
		(net "ADC_P3V3_STBY")
	)
	(segment
		(start 54.670706 -156.75356)
		(end 54.8894 -156.534866)
		(width 0.127)
		(layer "F.Cu")
		(net "ADC_P3V3_STBY")
	)
	(segment
		(start 53.304948 -153.005028)
		(end 52.899818 -152.599898)
		(width 0.127)
		(layer "F.Cu")
		(net "ADC_P3V3_STBY")
	)
	(segment
		(start 55.7022 -160.7058)
		(end 55.7022 -158.9532)
		(width 0.127)
		(layer "F.Cu")
		(net "ADC_P3V3_STBY")
	)
	(segment
		(start 54.8894 -156.534866)
		(end 54.8894 -155.7782)
		(width 0.127)
		(layer "F.Cu")
		(net "ADC_P3V3_STBY")
	)
	(segment
		(start 54.8894 -155.7782)
		(end 53.304948 -154.193748)
		(width 0.127)
		(layer "F.Cu")
		(net "ADC_P3V3_STBY")
	)
	(segment
		(start 56.055514 -161.059114)
		(end 55.7022 -160.7058)
		(width 0.127)
		(layer "F.Cu")
		(net "ADC_P3V3_STBY")
	)
	(segment
		(start 53.304948 -154.193748)
		(end 53.304948 -153.005028)
		(width 0.127)
		(layer "F.Cu")
		(net "ADC_P3V3_STBY")
	)
	(via
		(at 56.792622 -161.059114)
		(size 0.6604)
		(drill 0.3302)
		(layers "F.Cu" "B.Cu")
		(net "ADC_P3V3_STBY")
	)
	(segment
		(start 54.501542 -155.771342)
		(end 54.501542 -156.383736)
		(width 0.127)
		(layer "F.Cu")
		(net "ADC_P1V8_STBY")
	)
	(segment
		(start 54.704742 -162.028886)
		(end 54.713124 -162.037268)
		(width 0.127)
		(layer "F.Cu")
		(net "ADC_P1V8_STBY")
	)
	(segment
		(start 54.501542 -156.383736)
		(end 54.0385 -156.846778)
		(width 0.127)
		(layer "F.Cu")
		(net "ADC_P1V8_STBY")
	)
	(segment
		(start 55.6768 -162.2425)
		(end 55.219854 -162.2425)
		(width 0.127)
		(layer "F.Cu")
		(net "ADC_P1V8_STBY")
	)
	(segment
		(start 52.899818 -153.399998)
		(end 52.899818 -154.169618)
		(width 0.127)
		(layer "F.Cu")
		(net "ADC_P1V8_STBY")
	)
	(segment
		(start 52.899818 -154.169618)
		(end 54.501542 -155.771342)
		(width 0.127)
		(layer "F.Cu")
		(net "ADC_P1V8_STBY")
	)
	(segment
		(start 55.023004 -162.04565)
		(end 54.721506 -162.04565)
		(width 0.127)
		(layer "F.Cu")
		(net "ADC_P1V8_STBY")
	)
	(segment
		(start 54.0385 -156.846778)
		(end 54.0385 -157.1498)
		(width 0.127)
		(layer "F.Cu")
		(net "ADC_P1V8_STBY")
	)
	(segment
		(start 54.721506 -162.04565)
		(end 54.713124 -162.037268)
		(width 0.127)
		(layer "F.Cu")
		(net "ADC_P1V8_STBY")
	)
	(segment
		(start 54.704742 -161.64814)
		(end 54.704742 -162.028886)
		(width 0.127)
		(layer "F.Cu")
		(net "ADC_P1V8_STBY")
	)
	(segment
		(start 54.0385 -157.832298)
		(end 55.3212 -159.114998)
		(width 0.127)
		(layer "F.Cu")
		(net "ADC_P1V8_STBY")
	)
	(segment
		(start 56.7436 -162.0393)
		(end 56.3372 -162.0393)
		(width 0.127)
		(layer "F.Cu")
		(net "ADC_P1V8_STBY")
	)
	(segment
		(start 54.0385 -157.1498)
		(end 54.0385 -157.832298)
		(width 0.127)
		(layer "F.Cu")
		(net "ADC_P1V8_STBY")
	)
	(segment
		(start 55.219854 -162.2425)
		(end 55.023004 -162.04565)
		(width 0.127)
		(layer "F.Cu")
		(net "ADC_P1V8_STBY")
	)
	(segment
		(start 56.134 -162.2425)
		(end 55.6768 -162.2425)
		(width 0.127)
		(layer "F.Cu")
		(net "ADC_P1V8_STBY")
	)
	(segment
		(start 55.3212 -161.031682)
		(end 54.704742 -161.64814)
		(width 0.127)
		(layer "F.Cu")
		(net "ADC_P1V8_STBY")
	)
	(segment
		(start 55.3212 -159.114998)
		(end 55.3212 -161.031682)
		(width 0.127)
		(layer "F.Cu")
		(net "ADC_P1V8_STBY")
	)
	(segment
		(start 56.3372 -162.0393)
		(end 56.134 -162.2425)
		(width 0.127)
		(layer "F.Cu")
		(net "ADC_P1V8_STBY")
	)
	(via
		(at 54.0385 -157.1498)
		(size 0.6604)
		(drill 0.3302)
		(layers "F.Cu" "B.Cu")
		(net "ADC_P1V8_STBY")
	)
	(segment
		(start 52.099972 -151.000206)
		(end 52.499768 -151.400002)
		(width 0.127)
		(layer "F.Cu")
		(net "ADC_12V")
	)
	(segment
		(start 52.099972 -150.999952)
		(end 52.099972 -151.000206)
		(width 0.127)
		(layer "F.Cu")
		(net "ADC_12V")
	)
	(via
		(at 52.499768 -151.400002)
		(size 0.4572)
		(drill 0.2032)
		(layers "F.Cu" "B.Cu")
		(net "ADC_12V")
	)
	(via
		(at 54.2036 -157.7594)
		(size 0.6096)
		(drill 0.3048)
		(layers "F.Cu" "B.Cu")
		(net "ADC_12V")
	)
	(segment
		(start 54.014624 -153.865834)
		(end 53.761894 -153.865834)
		(width 0.127)
		(layer "B.Cu")
		(net "ADC_12V")
	)
	(segment
		(start 53.7591 -163.1188)
		(end 53.7591 -162.179)
		(width 0.127)
		(layer "B.Cu")
		(net "ADC_12V")
	)
	(segment
		(start 53.7845 -161.163)
		(end 53.7845 -159.34436)
		(width 0.127)
		(layer "B.Cu")
		(net "ADC_12V")
	)
	(segment
		(start 53.7845 -162.1536)
		(end 53.7845 -161.163)
		(width 0.127)
		(layer "B.Cu")
		(net "ADC_12V")
	)
	(segment
		(start 54.2036 -156.841952)
		(end 54.530752 -156.5148)
		(width 0.127)
		(layer "B.Cu")
		(net "ADC_12V")
	)
	(segment
		(start 54.2036 -158.92526)
		(end 54.2036 -157.7594)
		(width 0.127)
		(layer "B.Cu")
		(net "ADC_12V")
	)
	(segment
		(start 52.499768 -152.603708)
		(end 52.499768 -151.400002)
		(width 0.127)
		(layer "B.Cu")
		(net "ADC_12V")
	)
	(segment
		(start 54.530752 -156.5148)
		(end 54.530752 -154.381962)
		(width 0.127)
		(layer "B.Cu")
		(net "ADC_12V")
	)
	(segment
		(start 53.7591 -162.179)
		(end 53.7845 -162.1536)
		(width 0.127)
		(layer "B.Cu")
		(net "ADC_12V")
	)
	(segment
		(start 53.761894 -153.865834)
		(end 52.499768 -152.603708)
		(width 0.127)
		(layer "B.Cu")
		(net "ADC_12V")
	)
	(segment
		(start 54.2036 -157.7594)
		(end 54.2036 -156.841952)
		(width 0.127)
		(layer "B.Cu")
		(net "ADC_12V")
	)
	(segment
		(start 54.530752 -154.381962)
		(end 54.014624 -153.865834)
		(width 0.127)
		(layer "B.Cu")
		(net "ADC_12V")
	)
	(segment
		(start 53.7845 -159.34436)
		(end 54.2036 -158.92526)
		(width 0.127)
		(layer "B.Cu")
		(net "ADC_12V")
	)
	(segment
		(start 49.299876 -152.999948)
		(end 49.699926 -153.399998)
		(width 0.1778)
		(layer "F.Cu")
		(net "ADCVREXT")
	)
	(via
		(at 49.299876 -152.999948)
		(size 0.4572)
		(drill 0.2032)
		(layers "F.Cu" "B.Cu")
		(net "ADCVREXT")
	)
	(via
		(at 50.587148 -153.1112)
		(size 0.6096)
		(drill 0.3048)
		(layers "F.Cu" "B.Cu")
		(net "ADCVREXT")
	)
	(segment
		(start 50.587148 -153.1112)
		(end 50.6984 -153.1112)
		(width 0.1778)
		(layer "B.Cu")
		(net "ADCVREXT")
	)
	(segment
		(start 50.9397 -153.3525)
		(end 50.9397 -154.6352)
		(width 0.1778)
		(layer "B.Cu")
		(net "ADCVREXT")
	)
	(segment
		(start 50.475896 -152.999948)
		(end 50.587148 -153.1112)
		(width 0.1778)
		(layer "B.Cu")
		(net "ADCVREXT")
	)
	(segment
		(start 49.299876 -152.999948)
		(end 50.475896 -152.999948)
		(width 0.1778)
		(layer "B.Cu")
		(net "ADCVREXT")
	)
	(segment
		(start 50.6984 -153.1112)
		(end 50.9397 -153.3525)
		(width 0.1778)
		(layer "B.Cu")
		(net "ADCVREXT")
	)
	(segment
		(start 51.2826 -155.7274)
		(end 50.1142 -154.559)
		(width 0.1778)
		(layer "F.Cu")
		(net "ADCVREFFP")
	)
	(segment
		(start 50.8 -156.6672)
		(end 51.2826 -156.1846)
		(width 0.1778)
		(layer "F.Cu")
		(net "ADCVREFFP")
	)
	(segment
		(start 50.8 -157.2006)
		(end 50.8 -159.862774)
		(width 0.1778)
		(layer "F.Cu")
		(net "ADCVREFFP")
	)
	(segment
		(start 51.312826 -160.3756)
		(end 52.24272 -160.3756)
		(width 0.1778)
		(layer "F.Cu")
		(net "ADCVREFFP")
	)
	(segment
		(start 52.8828 -161.0614)
		(end 52.5653 -160.7439)
		(width 0.1778)
		(layer "F.Cu")
		(net "ADCVREFFP")
	)
	(segment
		(start 50.8 -159.862774)
		(end 51.312826 -160.3756)
		(width 0.1778)
		(layer "F.Cu")
		(net "ADCVREFFP")
	)
	(segment
		(start 50.8 -157.2006)
		(end 50.8 -156.6672)
		(width 0.1778)
		(layer "F.Cu")
		(net "ADCVREFFP")
	)
	(segment
		(start 52.5653 -160.7439)
		(end 52.5653 -160.1724)
		(width 0.1778)
		(layer "F.Cu")
		(net "ADCVREFFP")
	)
	(segment
		(start 52.44592 -160.1724)
		(end 52.5653 -160.1724)
		(width 0.1778)
		(layer "F.Cu")
		(net "ADCVREFFP")
	)
	(segment
		(start 50.1142 -152.985724)
		(end 50.500026 -152.599898)
		(width 0.1778)
		(layer "F.Cu")
		(net "ADCVREFFP")
	)
	(segment
		(start 50.1142 -154.559)
		(end 50.1142 -152.985724)
		(width 0.1778)
		(layer "F.Cu")
		(net "ADCVREFFP")
	)
	(segment
		(start 51.2826 -156.1846)
		(end 51.2826 -155.7274)
		(width 0.1778)
		(layer "F.Cu")
		(net "ADCVREFFP")
	)
	(segment
		(start 52.24272 -160.3756)
		(end 52.44592 -160.1724)
		(width 0.1778)
		(layer "F.Cu")
		(net "ADCVREFFP")
	)
	(via
		(at 50.8 -157.2006)
		(size 0.6604)
		(drill 0.3302)
		(layers "F.Cu" "B.Cu")
		(net "ADCVREFFP")
	)
	(segment
		(start 53.7845 -159.2326)
		(end 53.7845 -159.7787)
		(width 0.1778)
		(layer "F.Cu")
		(net "ADCVREFFN")
	)
	(segment
		(start 53.4543 -160.1089)
		(end 53.4543 -160.1724)
		(width 0.1778)
		(layer "F.Cu")
		(net "ADCVREFFN")
	)
	(segment
		(start 52.030122 -158.3182)
		(end 51.7398 -158.027878)
		(width 0.1778)
		(layer "F.Cu")
		(net "ADCVREFFN")
	)
	(segment
		(start 51.7398 -156.66085)
		(end 52.2351 -156.16555)
		(width 0.1778)
		(layer "F.Cu")
		(net "ADCVREFFN")
	)
	(segment
		(start 52.2351 -156.16555)
		(end 52.2351 -155.7655)
		(width 0.1778)
		(layer "F.Cu")
		(net "ADCVREFFN")
	)
	(segment
		(start 52.8701 -158.3182)
		(end 53.7845 -159.2326)
		(width 0.1778)
		(layer "F.Cu")
		(net "ADCVREFFN")
	)
	(segment
		(start 52.030122 -158.3182)
		(end 52.8701 -158.3182)
		(width 0.1778)
		(layer "F.Cu")
		(net "ADCVREFFN")
	)
	(segment
		(start 51.7398 -158.027878)
		(end 51.7398 -156.66085)
		(width 0.1778)
		(layer "F.Cu")
		(net "ADCVREFFN")
	)
	(segment
		(start 50.500026 -154.030426)
		(end 50.500026 -153.399998)
		(width 0.1778)
		(layer "F.Cu")
		(net "ADCVREFFN")
	)
	(segment
		(start 52.2351 -155.7655)
		(end 50.500026 -154.030426)
		(width 0.1778)
		(layer "F.Cu")
		(net "ADCVREFFN")
	)
	(segment
		(start 53.7845 -159.7787)
		(end 53.4543 -160.1089)
		(width 0.1778)
		(layer "F.Cu")
		(net "ADCVREFFN")
	)
	(via
		(at 52.030122 -158.3182)
		(size 0.6604)
		(drill 0.3302)
		(layers "F.Cu" "B.Cu")
		(net "ADCVREFFN")
	)
	(segment
		(start 54.483 -160.3248)
		(end 54.8132 -160.3248)
		(width 0.508)
		(layer "F.Cu")
		(net "ADCAV33")
	)
	(segment
		(start 49.699926 -149.40026)
		(end 49.699926 -149.400006)
		(width 0.3048)
		(layer "F.Cu")
		(net "ADCAV33")
	)
	(segment
		(start 53.7718 -161.0614)
		(end 54.2798 -160.5534)
		(width 0.508)
		(layer "F.Cu")
		(net "ADCAV33")
	)
	(segment
		(start 54.2798 -160.528)
		(end 54.483 -160.3248)
		(width 0.508)
		(layer "F.Cu")
		(net "ADCAV33")
	)
	(segment
		(start 50.099722 -149.800056)
		(end 49.699926 -149.40026)
		(width 0.3048)
		(layer "F.Cu")
		(net "ADCAV33")
	)
	(segment
		(start 50.099722 -149.8346)
		(end 50.099722 -149.800056)
		(width 0.3048)
		(layer "F.Cu")
		(net "ADCAV33")
	)
	(segment
		(start 54.2798 -160.5534)
		(end 54.2798 -160.528)
		(width 0.508)
		(layer "F.Cu")
		(net "ADCAV33")
	)
	(via
		(at 61.029596 -159.946086)
		(size 0.6096)
		(drill 0.3048)
		(layers "F.Cu" "B.Cu")
		(net "ADCAV33")
	)
	(via
		(at 63.6016 -161.791904)
		(size 0.508)
		(drill 0.254)
		(layers "F.Cu" "B.Cu")
		(net "ADCAV33")
	)
	(via
		(at 54.8132 -160.3248)
		(size 0.508)
		(drill 0.254)
		(layers "F.Cu" "B.Cu")
		(net "ADCAV33")
	)
	(via
		(at 50.099722 -149.8346)
		(size 0.4572)
		(drill 0.2032)
		(layers "F.Cu" "B.Cu")
		(net "ADCAV33")
	)
	(segment
		(start 61.029596 -159.946086)
		(end 61.029596 -158.883604)
		(width 0.508)
		(layer "B.Cu")
		(net "ADCAV33")
	)
	(segment
		(start 63.6016 -161.442654)
		(end 63.5762 -161.417254)
		(width 0.508)
		(layer "B.Cu")
		(net "ADCAV33")
	)
	(segment
		(start 62.2554 -160.02)
		(end 62.181486 -159.946086)
		(width 0.508)
		(layer "B.Cu")
		(net "ADCAV33")
	)
	(segment
		(start 63.6016 -161.791904)
		(end 63.6016 -161.442654)
		(width 0.508)
		(layer "B.Cu")
		(net "ADCAV33")
	)
	(segment
		(start 63.1571 -160.9217)
		(end 63.5762 -160.9217)
		(width 0.508)
		(layer "B.Cu")
		(net "ADCAV33")
	)
	(segment
		(start 62.2554 -160.02)
		(end 63.1571 -160.9217)
		(width 0.508)
		(layer "B.Cu")
		(net "ADCAV33")
	)
	(segment
		(start 61.029596 -158.883604)
		(end 61.4172 -158.496)
		(width 0.508)
		(layer "B.Cu")
		(net "ADCAV33")
	)
	(segment
		(start 62.181486 -159.946086)
		(end 61.029596 -159.946086)
		(width 0.508)
		(layer "B.Cu")
		(net "ADCAV33")
	)
	(segment
		(start 63.5762 -161.417254)
		(end 63.5762 -160.9217)
		(width 0.508)
		(layer "B.Cu")
		(net "ADCAV33")
	)
	(segment
		(start 54.8132 -160.3248)
		(end 54.8132 -161.6964)
		(width 0.508)
		(layer "In2.Cu")
		(net "ADCAV33")
	)
	(segment
		(start 55.571644 -159.566356)
		(end 54.8132 -160.3248)
		(width 0.508)
		(layer "In2.Cu")
		(net "ADCAV33")
	)
	(segment
		(start 58.120788 -160.5788)
		(end 62.872112 -160.5788)
		(width 0.508)
		(layer "In2.Cu")
		(net "ADCAV33")
	)
	(segment
		(start 50.099722 -149.8346)
		(end 50.099722 -151.699722)
		(width 0.508)
		(layer "In2.Cu")
		(net "ADCAV33")
	)
	(segment
		(start 50.2666 -153.2636)
		(end 52.525422 -155.522422)
		(width 0.508)
		(layer "In2.Cu")
		(net "ADCAV33")
	)
	(segment
		(start 54.8132 -161.6964)
		(end 55.3466 -162.2298)
		(width 0.508)
		(layer "In2.Cu")
		(net "ADCAV33")
	)
	(segment
		(start 54.356 -157.5308)
		(end 55.571644 -158.746444)
		(width 0.508)
		(layer "In2.Cu")
		(net "ADCAV33")
	)
	(segment
		(start 55.571644 -158.746444)
		(end 55.571644 -159.566356)
		(width 0.508)
		(layer "In2.Cu")
		(net "ADCAV33")
	)
	(segment
		(start 62.872112 -160.5788)
		(end 63.6016 -161.308288)
		(width 0.508)
		(layer "In2.Cu")
		(net "ADCAV33")
	)
	(segment
		(start 55.3466 -162.2298)
		(end 56.469788 -162.2298)
		(width 0.508)
		(layer "In2.Cu")
		(net "ADCAV33")
	)
	(segment
		(start 56.469788 -162.2298)
		(end 58.120788 -160.5788)
		(width 0.508)
		(layer "In2.Cu")
		(net "ADCAV33")
	)
	(segment
		(start 50.099722 -151.699722)
		(end 50.2666 -151.8666)
		(width 0.508)
		(layer "In2.Cu")
		(net "ADCAV33")
	)
	(segment
		(start 63.6016 -161.308288)
		(end 63.6016 -161.791904)
		(width 0.508)
		(layer "In2.Cu")
		(net "ADCAV33")
	)
	(segment
		(start 53.5686 -157.5308)
		(end 54.356 -157.5308)
		(width 0.508)
		(layer "In2.Cu")
		(net "ADCAV33")
	)
	(segment
		(start 52.525422 -156.487622)
		(end 53.5686 -157.5308)
		(width 0.508)
		(layer "In2.Cu")
		(net "ADCAV33")
	)
	(segment
		(start 52.525422 -155.522422)
		(end 52.525422 -156.487622)
		(width 0.508)
		(layer "In2.Cu")
		(net "ADCAV33")
	)
	(segment
		(start 50.2666 -151.8666)
		(end 50.2666 -153.2636)
		(width 0.508)
		(layer "In2.Cu")
		(net "ADCAV33")
	)
	(zone
		(net "GND")
		(layer "F.Cu")
		(hatch none 0.5)
		(connect_pads
			(clearance 0.5)
		)
		(min_thickness 0.25)
		(fill yes
			(thermal_gap 0.5)
			(thermal_bridge_width 0.5)
			(island_removal_mode 0)
		)
		(polygon
			(pts
				(xy 156.983938 -15.419578) (xy 156.641038 -15.762478) (xy 156.641038 -20.715478) (xy 157.185868 -21.260308)
				(xy 159.751268 -21.260308) (xy 160.362138 -20.649438) (xy 160.362138 -15.927578) (xy 159.854138 -15.419578)
			)
		)
		(polygon
			(pts
				(xy 157.339538 -16.232378) (xy 157.136338 -16.232378) (xy 157.136338 -16.435578) (xy 157.339538 -16.435578)
			)
		)
		(polygon
			(pts
				(xy 157.339538 -15.622778) (xy 157.136338 -15.622778) (xy 157.136338 -15.825978) (xy 157.339538 -15.825978)
			)
		)
	)
	(zone
		(net "P5V_STBY")
		(layer "F.Cu")
		(hatch none 0.5)
		(connect_pads
			(clearance 0.5)
		)
		(min_thickness 0.25)
		(fill yes
			(thermal_gap 0.5)
			(thermal_bridge_width 0.5)
			(island_removal_mode 0)
		)
		(polygon
			(pts
				(xy 93.2942 -30.0228) (xy 93.218 -30.099) (xy 91.44 -30.099) (xy 91.44 -31.369) (xy 91.9988 -31.9278)
				(xy 94.2848 -31.9278) (xy 94.5134 -31.6992) (xy 94.5134 -30.1752) (xy 94.361 -30.0228)
			)
		)
		(polygon
			(pts
				(xy 94.234 -30.5562) (xy 94.0308 -30.5562) (xy 94.0308 -30.7594) (xy 94.234 -30.7594)
			)
		)
		(polygon
			(pts
				(xy 93.6244 -30.5562) (xy 93.4212 -30.5562) (xy 93.4212 -30.7594) (xy 93.6244 -30.7594)
			)
		)
	)
	(zone
		(layer "F.Cu")
		(hatch none 0.5)
		(connect_pads
			(clearance 0)
		)
		(min_thickness 0.25)
		(keepout
			(tracks allowed)
			(vias allowed)
			(pads allowed)
			(copperpour allowed)
			(footprints allowed)
		)
		(placement
			(enabled no)
			(sheetname "")
		)
		(fill
			(thermal_gap 0.5)
			(thermal_bridge_width 0.5)
			(island_removal_mode 0)
		)
		(polygon
			(pts
				(xy 211.991956 -96.184974) (xy 214.277956 -96.184974) (xy 214.430356 -96.032574) (xy 214.430356 -94.914974)
				(xy 214.277956 -94.762574) (xy 212.195156 -94.762574) (xy 211.839556 -95.118174) (xy 211.839556 -96.032574)
			)
		)
	)
	(zone
		(layer "F.Cu")
		(hatch none 0.5)
		(connect_pads
			(clearance 0)
		)
		(min_thickness 0.25)
		(keepout
			(tracks allowed)
			(vias allowed)
			(pads allowed)
			(copperpour allowed)
			(footprints not_allowed)
		)
		(placement
			(enabled no)
			(sheetname "")
		)
		(fill
			(thermal_gap 0.5)
			(thermal_bridge_width 0.5)
			(island_removal_mode 0)
		)
		(polygon
			(pts
				(arc
					(start 78.550008 -100.300028)
					(mid 73.799954 -105.050082)
					(end 78.550008 -109.799882)
				)
				(xy 92.700094 -109.799882) (xy 92.700094 -100.300028)
			)
		)
	)
	(zone
		(layer "F.Cu")
		(hatch none 0.5)
		(connect_pads
			(clearance 0)
		)
		(min_thickness 0.25)
		(keepout
			(tracks not_allowed)
			(vias allowed)
			(pads allowed)
			(copperpour not_allowed)
			(footprints allowed)
		)
		(placement
			(enabled no)
			(sheetname "")
		)
		(fill
			(thermal_gap 0.5)
			(thermal_bridge_width 0.5)
			(island_removal_mode 0)
		)
		(polygon
			(pts
				(arc
					(start 77.054456 -87.263224)
					(mid 76.981581 -87.225803)
					(end 76.902818 -87.20328)
				)
				(arc
					(start 76.902818 -87.399368)
					(mid 77.283818 -87.780368)
					(end 77.664818 -87.399368)
				)
				(arc
					(start 77.664818 -86.510622)
					(mid 77.283945 -86.129368)
					(end 76.902818 -86.510368)
				)
				(arc
					(start 76.902818 -86.70671)
					(mid 76.98159 -86.684203)
					(end 77.054456 -86.646766)
				)
				(arc
					(start 77.054456 -86.646766)
					(mid 77.454178 -86.305041)
					(end 77.190854 -86.760304)
				)
				(arc
					(start 77.190854 -86.760304)
					(mid 77.054918 -86.83976)
					(end 76.902818 -86.880446)
				)
				(arc
					(start 76.902818 -87.029544)
					(mid 77.054745 -87.07019)
					(end 77.1906 -87.149432)
				)
				(arc
					(start 77.1906 -87.149432)
					(mid 77.454858 -87.60407)
					(end 77.054456 -87.263224)
				)
			)
		)
	)
	(zone
		(layer "F.Cu")
		(hatch none 0.5)
		(connect_pads
			(clearance 0)
		)
		(min_thickness 0.25)
		(keepout
			(tracks allowed)
			(vias allowed)
			(pads allowed)
			(copperpour allowed)
			(footprints allowed)
		)
		(placement
			(enabled no)
			(sheetname "")
		)
		(fill
			(thermal_gap 0.5)
			(thermal_bridge_width 0.5)
			(island_removal_mode 0)
		)
		(polygon
			(pts
				(xy 90.2208 -174.9044) (xy 90.2208 -177.1904) (xy 90.3732 -177.3428) (xy 91.4908 -177.3428) (xy 91.6432 -177.1904)
				(xy 91.6432 -175.1076) (xy 91.2876 -174.752) (xy 90.3732 -174.752)
			)
		)
	)
	(zone
		(layer "F.Cu")
		(hatch none 0.5)
		(connect_pads
			(clearance 0)
		)
		(min_thickness 0.25)
		(keepout
			(tracks allowed)
			(vias allowed)
			(pads allowed)
			(copperpour allowed)
			(footprints not_allowed)
		)
		(placement
			(enabled no)
			(sheetname "")
		)
		(fill
			(thermal_gap 0.5)
			(thermal_bridge_width 0.5)
			(island_removal_mode 0)
		)
		(polygon
			(pts
				(arc
					(start 78.49997 -44.800012)
					(mid 73.749916 -40.049958)
					(end 78.49997 -35.299904)
				)
				(xy 89.499948 -35.299904) (xy 89.499948 -44.800012)
			)
		)
	)
	(zone
		(layer "F.Cu")
		(hatch none 0.5)
		(connect_pads
			(clearance 0)
		)
		(min_thickness 0.25)
		(keepout
			(tracks allowed)
			(vias allowed)
			(pads allowed)
			(copperpour allowed)
			(footprints not_allowed)
		)
		(placement
			(enabled no)
			(sheetname "")
		)
		(fill
			(thermal_gap 0.5)
			(thermal_bridge_width 0.5)
			(island_removal_mode 0)
		)
		(polygon
			(pts
				(xy 215.000078 -172.500036) (xy 215.000078 -182.500016) (xy 225.000058 -182.500016) (xy 225.000058 -172.500036)
			)
		)
	)
	(zone
		(layer "F.Cu")
		(hatch none 0.5)
		(connect_pads
			(clearance 0)
		)
		(min_thickness 0.25)
		(keepout
			(tracks allowed)
			(vias allowed)
			(pads allowed)
			(copperpour allowed)
			(footprints allowed)
		)
		(placement
			(enabled no)
			(sheetname "")
		)
		(fill
			(thermal_gap 0.5)
			(thermal_bridge_width 0.5)
			(island_removal_mode 0)
		)
		(polygon
			(pts
				(xy 218.148408 -53.24221) (xy 220.612208 -53.24221) (xy 220.790008 -53.06441) (xy 220.790008 -51.23561)
				(xy 220.790008 -50.49901) (xy 220.663008 -50.37201) (xy 218.580208 -50.37201) (xy 218.046808 -50.90541)
				(xy 217.996008 -50.95621) (xy 217.996008 -53.08981)
			)
		)
	)
	(zone
		(net "P1V8_STBY")
		(layer "F.Cu")
		(hatch none 0.5)
		(connect_pads
			(clearance 0.5)
		)
		(min_thickness 0.25)
		(fill yes
			(thermal_gap 0.5)
			(thermal_bridge_width 0.5)
			(island_removal_mode 0)
		)
		(polygon
			(pts
				(xy 18.6436 -170.2562) (xy 18.5166 -170.3832) (xy 18.5166 -170.8023) (xy 18.2372 -171.0817) (xy 16.51 -171.0817)
				(xy 16.51 -172.535596) (xy 17.35074 -173.376336) (xy 19.713448 -173.376336) (xy 20.403566 -174.066454)
				(xy 22.932644 -174.066454) (xy 23.011892 -173.987206) (xy 23.011892 -170.554396) (xy 22.713696 -170.2562)
			)
		)
		(polygon
			(pts
				(xy 21.179536 -170.7642) (xy 20.976336 -170.7642) (xy 20.976336 -170.9674) (xy 21.179536 -170.9674)
			)
		)
		(polygon
			(pts
				(xy 20.569936 -170.7642) (xy 20.366736 -170.7642) (xy 20.366736 -170.9674) (xy 20.569936 -170.9674)
			)
		)
	)
	(zone
		(layer "F.Cu")
		(hatch none 0.5)
		(connect_pads
			(clearance 0)
		)
		(min_thickness 0.25)
		(keepout
			(tracks allowed)
			(vias allowed)
			(pads allowed)
			(copperpour allowed)
			(footprints not_allowed)
		)
		(placement
			(enabled no)
			(sheetname "")
		)
		(fill
			(thermal_gap 0.5)
			(thermal_bridge_width 0.5)
			(island_removal_mode 0)
		)
		(polygon
			(pts
				(arc
					(start 154.750008 -120.000014)
					(mid 149.999954 -124.750068)
					(end 145.2499 -120.000014)
				)
				(arc
					(start 145.2499 -120.000014)
					(mid 149.999954 -115.24996)
					(end 154.750008 -120.000014)
				)
			)
		)
	)
	(zone
		(layer "F.Cu")
		(hatch none 0.5)
		(connect_pads
			(clearance 0)
		)
		(min_thickness 0.25)
		(keepout
			(tracks allowed)
			(vias allowed)
			(pads allowed)
			(copperpour allowed)
			(footprints not_allowed)
		)
		(placement
			(enabled no)
			(sheetname "")
		)
		(fill
			(thermal_gap 0.5)
			(thermal_bridge_width 0.5)
			(island_removal_mode 0)
		)
		(polygon
			(pts
				(arc
					(start 234.00004 0)
					(mid 234.707145 -0.292893)
					(end 235.000038 -0.999998)
				)
				(arc
					(start 235.000038 -183.76392)
					(mid 234.973274 -183.993728)
					(end 234.894374 -184.211214)
				)
				(arc
					(start 230.2764 -193.447162)
					(mid 230.156976 -193.631987)
					(end 230.000048 -193.786252)
				)
				(xy 230.000048 0)
			)
		)
	)
	(zone
		(layer "F.Cu")
		(hatch none 0.5)
		(connect_pads
			(clearance 0)
		)
		(min_thickness 0.25)
		(keepout
			(tracks allowed)
			(vias allowed)
			(pads allowed)
			(copperpour allowed)
			(footprints allowed)
		)
		(placement
			(enabled no)
			(sheetname "")
		)
		(fill
			(thermal_gap 0.5)
			(thermal_bridge_width 0.5)
			(island_removal_mode 0)
		)
		(polygon
			(pts
				(xy 39.7764 -175.4124) (xy 37.4904 -175.4124) (xy 37.338 -175.5648) (xy 37.338 -176.6824) (xy 37.4904 -176.8348)
				(xy 39.5732 -176.8348) (xy 39.9288 -176.4792) (xy 39.9288 -175.5648)
			)
		)
	)
	(zone
		(net "GND")
		(layer "F.Cu")
		(hatch none 0.5)
		(connect_pads
			(clearance 0.5)
		)
		(min_thickness 0.25)
		(fill yes
			(thermal_gap 0.5)
			(thermal_bridge_width 0.5)
			(island_removal_mode 0)
		)
		(polygon
			(pts
				(xy 140.24991 -13.14831) (xy 140.1064 -13.29182) (xy 140.1064 -18.292064) (xy 139.856464 -18.542)
				(xy 131.122166 -18.542) (xy 130.9243 -18.739866) (xy 130.9243 -21.224748) (xy 131.518152 -21.8186)
				(xy 140.3858 -21.8186) (xy 141.743684 -20.460716) (xy 141.743684 -13.422884) (xy 141.46911 -13.14831)
			)
		)
		(polygon
			(pts
				(xy 137.466832 -19.339814) (xy 137.263632 -19.339814) (xy 137.263632 -19.543014) (xy 137.466832 -19.543014)
			)
		)
		(polygon
			(pts
				(xy 136.603232 -19.339814) (xy 136.400032 -19.339814) (xy 136.400032 -19.543014) (xy 136.603232 -19.543014)
			)
		)
		(polygon
			(pts
				(xy 140.8176 -15.748) (xy 140.6144 -15.748) (xy 140.6144 -15.9512) (xy 140.8176 -15.9512)
			)
		)
		(polygon
			(pts
				(xy 140.8176 -15.1384) (xy 140.6144 -15.1384) (xy 140.6144 -15.3416) (xy 140.8176 -15.3416)
			)
		)
	)
	(zone
		(layer "F.Cu")
		(hatch none 0.5)
		(connect_pads
			(clearance 0)
		)
		(min_thickness 0.25)
		(keepout
			(tracks not_allowed)
			(vias allowed)
			(pads allowed)
			(copperpour not_allowed)
			(footprints allowed)
		)
		(placement
			(enabled no)
			(sheetname "")
		)
		(fill
			(thermal_gap 0.5)
			(thermal_bridge_width 0.5)
			(island_removal_mode 0)
		)
		(polygon
			(pts
				(arc
					(start 84.749894 -120.000014)
					(mid 80.000094 -124.749814)
					(end 75.25004 -120.000014)
				)
				(arc
					(start 75.25004 -120.000014)
					(mid 80.000094 -115.24996)
					(end 84.749894 -120.000014)
				)
			)
		)
	)
	(zone
		(layer "F.Cu")
		(hatch none 0.5)
		(connect_pads
			(clearance 0)
		)
		(min_thickness 0.25)
		(keepout
			(tracks allowed)
			(vias allowed)
			(pads allowed)
			(copperpour allowed)
			(footprints not_allowed)
		)
		(placement
			(enabled no)
			(sheetname "")
		)
		(fill
			(thermal_gap 0.5)
			(thermal_bridge_width 0.5)
			(island_removal_mode 0)
		)
		(polygon
			(pts
				(arc
					(start 13.24991 -120.000014)
					(mid 17.999964 -115.24996)
					(end 22.750018 -120.000014)
				)
				(arc
					(start 22.750018 -120.000014)
					(mid 17.999964 -124.750068)
					(end 13.24991 -120.000014)
				)
			)
		)
	)
	(zone
		(layer "F.Cu")
		(hatch none 0.5)
		(connect_pads
			(clearance 0)
		)
		(min_thickness 0.25)
		(keepout
			(tracks allowed)
			(vias allowed)
			(pads allowed)
			(copperpour allowed)
			(footprints not_allowed)
		)
		(placement
			(enabled no)
			(sheetname "")
		)
		(fill
			(thermal_gap 0.5)
			(thermal_bridge_width 0.5)
			(island_removal_mode 0)
		)
		(polygon
			(pts
				(xy 173.399958 -40.25011)
				(arc
					(start 173.399958 -51.250088)
					(mid 179.399946 -57.250076)
					(end 185.399934 -51.250088)
				)
				(xy 185.399934 -40.25011)
			)
		)
	)
	(zone
		(layer "F.Cu")
		(hatch none 0.5)
		(connect_pads
			(clearance 0)
		)
		(min_thickness 0.25)
		(keepout
			(tracks allowed)
			(vias allowed)
			(pads allowed)
			(copperpour allowed)
			(footprints allowed)
		)
		(placement
			(enabled no)
			(sheetname "")
		)
		(fill
			(thermal_gap 0.5)
			(thermal_bridge_width 0.5)
			(island_removal_mode 0)
		)
		(polygon
			(pts
				(xy 59.0042 -137.0838) (xy 60.8584 -137.0838) (xy 60.8584 -137.8712) (xy 59.0042 -137.8712)
			)
		)
	)
	(zone
		(layer "F.Cu")
		(hatch none 0.5)
		(connect_pads
			(clearance 0)
		)
		(min_thickness 0.25)
		(keepout
			(tracks allowed)
			(vias allowed)
			(pads allowed)
			(copperpour allowed)
			(footprints allowed)
		)
		(placement
			(enabled no)
			(sheetname "")
		)
		(fill
			(thermal_gap 0.5)
			(thermal_bridge_width 0.5)
			(island_removal_mode 0)
		)
		(polygon
			(pts
				(xy 170.2816 -128.2446) (xy 172.7708 -128.2446) (xy 172.8724 -128.3462) (xy 174.8028 -128.3462)
				(xy 175.0822 -128.0668) (xy 175.0822 -126.3904) (xy 174.9044 -126.2126) (xy 170.3578 -126.2126)
				(xy 170.1546 -126.4158) (xy 170.1546 -128.1176)
			)
		)
	)
	(zone
		(net "AGND_P5V")
		(layer "F.Cu")
		(hatch none 0.5)
		(connect_pads
			(clearance 0.5)
		)
		(min_thickness 0.25)
		(fill yes
			(thermal_gap 0.5)
			(thermal_bridge_width 0.5)
			(island_removal_mode 0)
		)
		(polygon
			(pts
				(xy 213.230968 -47.60849) (xy 213.13775 -47.701708) (xy 213.13775 -54.18455) (xy 213.189312 -54.236112)
				(xy 215.856312 -54.236112) (xy 215.929972 -54.162452) (xy 215.929972 -51.489356) (xy 215.643968 -51.203352)
				(xy 215.643968 -47.73549) (xy 215.516968 -47.60849)
			)
		)
		(polygon
			(pts
				(xy 215.460072 -53.432456) (xy 215.256872 -53.432456) (xy 215.256872 -53.635656) (xy 215.460072 -53.635656)
			)
		)
		(polygon
			(pts
				(xy 215.460072 -52.975256) (xy 215.256872 -52.975256) (xy 215.256872 -53.178456) (xy 215.460072 -53.178456)
			)
		)
		(polygon
			(pts
				(xy 215.460072 -52.416456) (xy 215.256872 -52.416456) (xy 215.256872 -52.619656) (xy 215.460072 -52.619656)
			)
		)
		(polygon
			(pts
				(xy 215.460072 -51.959256) (xy 215.256872 -51.959256) (xy 215.256872 -52.162456) (xy 215.460072 -52.162456)
			)
		)
		(polygon
			(pts
				(xy 215.460072 -51.400456) (xy 215.256872 -51.400456) (xy 215.256872 -51.603656) (xy 215.460072 -51.603656)
			)
		)
		(polygon
			(pts
				(xy 214.291672 -48.085756) (xy 214.088472 -48.085756) (xy 214.088472 -48.288956) (xy 214.291672 -48.288956)
			)
		)
		(polygon
			(pts
				(xy 213.732872 -48.085756) (xy 213.529672 -48.085756) (xy 213.529672 -48.288956) (xy 213.732872 -48.288956)
			)
		)
	)
	(zone
		(layer "F.Cu")
		(hatch none 0.5)
		(connect_pads
			(clearance 0)
		)
		(min_thickness 0.25)
		(keepout
			(tracks allowed)
			(vias allowed)
			(pads allowed)
			(copperpour allowed)
			(footprints not_allowed)
		)
		(placement
			(enabled no)
			(sheetname "")
		)
		(fill
			(thermal_gap 0.5)
			(thermal_bridge_width 0.5)
			(island_removal_mode 0)
		)
		(polygon
			(pts
				(arc
					(start 22.750018 -24.99995)
					(mid 17.999964 -29.750004)
					(end 13.24991 -24.99995)
				)
				(arc
					(start 13.24991 -24.99995)
					(mid 17.999964 -20.249896)
					(end 22.750018 -24.99995)
				)
			)
		)
	)
	(zone
		(net "GND")
		(layer "F.Cu")
		(hatch none 0.5)
		(connect_pads
			(clearance 0.5)
		)
		(min_thickness 0.25)
		(fill yes
			(thermal_gap 0.5)
			(thermal_bridge_width 0.5)
			(island_removal_mode 0)
		)
		(polygon
			(pts
				(xy 33.108646 -177.09261) (xy 32.600646 -177.60061) (xy 32.600646 -178.828446) (xy 32.7406 -178.9684)
				(xy 32.7406 -186.5122) (xy 32.9692 -186.7408) (xy 34.3916 -186.7408) (xy 34.544 -186.5884) (xy 34.544 -184.4548)
				(xy 34.64814 -184.35066) (xy 35.2425 -184.35066) (xy 35.2425 -184.6199) (xy 35.5854 -184.6199) (xy 35.59048 -184.61482)
				(xy 35.59048 -184.37606) (xy 35.60572 -184.36082) (xy 35.60826 -184.36336) (xy 35.902646 -184.36336)
				(xy 35.902646 -177.60061) (xy 35.394646 -177.09261)
			)
		)
	)
	(zone
		(layer "F.Cu")
		(hatch none 0.5)
		(connect_pads
			(clearance 0)
		)
		(min_thickness 0.25)
		(keepout
			(tracks allowed)
			(vias allowed)
			(pads allowed)
			(copperpour allowed)
			(footprints allowed)
		)
		(placement
			(enabled no)
			(sheetname "")
		)
		(fill
			(thermal_gap 0.5)
			(thermal_bridge_width 0.5)
			(island_removal_mode 0)
		)
		(polygon
			(pts
				(xy 59.2836 -161.6202) (xy 60.0456 -161.6202) (xy 60.1218 -161.544) (xy 60.1218 -160.2486) (xy 59.9186 -160.0454)
				(xy 59.2582 -160.0454) (xy 59.1566 -160.147) (xy 59.1566 -161.4932)
			)
		)
	)
	(zone
		(layer "F.Cu")
		(hatch none 0.5)
		(connect_pads
			(clearance 0)
		)
		(min_thickness 0.25)
		(keepout
			(tracks allowed)
			(vias allowed)
			(pads allowed)
			(copperpour allowed)
			(footprints allowed)
		)
		(placement
			(enabled no)
			(sheetname "")
		)
		(fill
			(thermal_gap 0.5)
			(thermal_bridge_width 0.5)
			(island_removal_mode 0)
		)
		(polygon
			(pts
				(xy 195.2752 -136.525) (xy 209.55 -136.525) (xy 209.8802 -136.1948) (xy 209.8802 -134.4676) (xy 209.3214 -133.9088)
				(xy 195.58 -133.9088) (xy 195.072 -134.4168) (xy 195.072 -136.3218)
			)
		)
	)
	(zone
		(layer "F.Cu")
		(hatch none 0.5)
		(connect_pads
			(clearance 0)
		)
		(min_thickness 0.25)
		(keepout
			(tracks allowed)
			(vias allowed)
			(pads allowed)
			(copperpour allowed)
			(footprints not_allowed)
		)
		(placement
			(enabled no)
			(sheetname "")
		)
		(fill
			(thermal_gap 0.5)
			(thermal_bridge_width 0.5)
			(island_removal_mode 0)
		)
		(polygon
			(pts
				(arc
					(start 22.800056 -55.79999)
					(mid 27.55011 -60.550044)
					(end 22.800056 -65.300098)
				)
				(xy 8.64997 -65.300098) (xy 8.64997 -55.79999)
			)
		)
	)
	(zone
		(net "P12V_STBY")
		(layer "F.Cu")
		(hatch none 0.5)
		(connect_pads
			(clearance 0.5)
		)
		(min_thickness 0.25)
		(fill yes
			(thermal_gap 0.5)
			(thermal_bridge_width 0.5)
			(island_removal_mode 0)
		)
		(polygon
			(pts
				(xy 227.678742 -93.517466) (xy 227.259896 -93.936312) (xy 227.259896 -97.864676) (xy 227.807774 -98.412554)
				(xy 229.545388 -98.412554) (xy 229.749604 -98.208338) (xy 229.749604 -93.834966) (xy 229.432104 -93.517466)
			)
		)
		(polygon
			(pts
				(xy 229.297738 -98.096578) (xy 229.094538 -98.096578) (xy 229.094538 -98.299778) (xy 229.297738 -98.299778)
			)
		)
		(polygon
			(pts
				(xy 229.297738 -96.953578) (xy 229.094538 -96.953578) (xy 229.094538 -97.156778) (xy 229.297738 -97.156778)
			)
		)
		(polygon
			(pts
				(xy 227.900738 -96.953578) (xy 227.697538 -96.953578) (xy 227.697538 -97.156778) (xy 227.900738 -97.156778)
			)
		)
	)
	(zone
		(layer "F.Cu")
		(hatch none 0.5)
		(connect_pads
			(clearance 0)
		)
		(min_thickness 0.25)
		(keepout
			(tracks allowed)
			(vias allowed)
			(pads allowed)
			(copperpour allowed)
			(footprints allowed)
		)
		(placement
			(enabled no)
			(sheetname "")
		)
		(fill
			(thermal_gap 0.5)
			(thermal_bridge_width 0.5)
			(island_removal_mode 0)
		)
		(polygon
			(pts
				(xy 186.6646 -128.2192) (xy 188.7474 -128.2192) (xy 188.9506 -128.016) (xy 188.9506 -126.619) (xy 188.6966 -126.365)
				(xy 186.7154 -126.365) (xy 186.5376 -126.5428) (xy 186.5376 -128.0922)
			)
		)
	)
	(zone
		(net "P3V3")
		(layer "F.Cu")
		(hatch none 0.5)
		(connect_pads
			(clearance 0.5)
		)
		(min_thickness 0.25)
		(fill yes
			(thermal_gap 0.5)
			(thermal_bridge_width 0.5)
			(island_removal_mode 0)
		)
		(polygon
			(pts
				(xy 74.4982 -55.118) (xy 74.3966 -55.2196) (xy 74.3966 -57.9628) (xy 74.422 -57.9882) (xy 76.4794 -57.9882)
				(xy 77.2668 -57.2008) (xy 77.7748 -57.2008) (xy 78.3082 -57.7342) (xy 78.3082 -58.674) (xy 78.4352 -58.801)
				(xy 80.9752 -58.801) (xy 81.026 -58.7502) (xy 81.026 -55.9816) (xy 80.9498 -55.9054) (xy 78.5368 -55.9054)
				(xy 78.3336 -55.7022) (xy 78.3336 -55.2704) (xy 78.1812 -55.118)
			)
		)
	)
	(zone
		(net "GND")
		(layer "F.Cu")
		(hatch none 0.5)
		(connect_pads
			(clearance 0.5)
		)
		(min_thickness 0.25)
		(fill yes
			(thermal_gap 0.5)
			(thermal_bridge_width 0.5)
			(island_removal_mode 0)
		)
		(polygon
			(pts
				(xy 23.13559 -186.61761) (xy 22.7838 -186.9694) (xy 22.7838 -189.611) (xy 22.83841 -189.66561) (xy 31.965646 -189.66561)
				(xy 32.61614 -189.015116) (xy 32.61614 -187.47994) (xy 32.42564 -187.28944) (xy 30.9118 -187.28944)
				(xy 30.23997 -186.61761)
			)
		)
	)
	(zone
		(layer "F.Cu")
		(hatch none 0.5)
		(connect_pads
			(clearance 0)
		)
		(min_thickness 0.25)
		(keepout
			(tracks not_allowed)
			(vias allowed)
			(pads allowed)
			(copperpour not_allowed)
			(footprints allowed)
		)
		(placement
			(enabled no)
			(sheetname "")
		)
		(fill
			(thermal_gap 0.5)
			(thermal_bridge_width 0.5)
			(island_removal_mode 0)
		)
		(polygon
			(pts
				(arc
					(start 77.12583 -68.064888)
					(mid 77.052955 -68.027467)
					(end 76.974192 -68.004944)
				)
				(arc
					(start 76.974192 -68.201032)
					(mid 77.355192 -68.582032)
					(end 77.736192 -68.201032)
				)
				(arc
					(start 77.736192 -67.312286)
					(mid 77.355319 -66.931032)
					(end 76.974192 -67.312032)
				)
				(arc
					(start 76.974192 -67.508374)
					(mid 77.052964 -67.485867)
					(end 77.12583 -67.44843)
				)
				(arc
					(start 77.12583 -67.44843)
					(mid 77.525552 -67.106705)
					(end 77.262228 -67.561968)
				)
				(arc
					(start 77.262228 -67.561968)
					(mid 77.126292 -67.641424)
					(end 76.974192 -67.68211)
				)
				(arc
					(start 76.974192 -67.831208)
					(mid 77.126119 -67.871854)
					(end 77.261974 -67.951096)
				)
				(arc
					(start 77.261974 -67.951096)
					(mid 77.526232 -68.405734)
					(end 77.12583 -68.064888)
				)
			)
		)
	)
	(zone
		(layer "F.Cu")
		(hatch none 0.5)
		(connect_pads
			(clearance 0)
		)
		(min_thickness 0.25)
		(keepout
			(tracks allowed)
			(vias allowed)
			(pads allowed)
			(copperpour allowed)
			(footprints allowed)
		)
		(placement
			(enabled no)
			(sheetname "")
		)
		(fill
			(thermal_gap 0.5)
			(thermal_bridge_width 0.5)
			(island_removal_mode 0)
		)
		(polygon
			(pts
				(xy 215.976962 -45.635672) (xy 213.690962 -45.635672) (xy 213.538562 -45.788072) (xy 213.538562 -46.905672)
				(xy 213.690962 -47.058072) (xy 215.773762 -47.058072) (xy 216.129362 -46.702472) (xy 216.129362 -45.788072)
			)
		)
	)
	(zone
		(layer "F.Cu")
		(hatch none 0.5)
		(connect_pads
			(clearance 0)
		)
		(min_thickness 0.25)
		(keepout
			(tracks allowed)
			(vias allowed)
			(pads allowed)
			(copperpour allowed)
			(footprints allowed)
		)
		(placement
			(enabled no)
			(sheetname "")
		)
		(fill
			(thermal_gap 0.5)
			(thermal_bridge_width 0.5)
			(island_removal_mode 0)
		)
		(polygon
			(pts
				(xy 96.647 -130.2258) (xy 96.647 -131.0132) (xy 94.7928 -131.0132) (xy 94.6658 -130.8862) (xy 94.6658 -129.1336)
				(xy 94.9198 -128.8796) (xy 96.5454 -128.8796) (xy 96.6978 -129.032) (xy 96.6978 -129.2606) (xy 96.6978 -130.175)
			)
		)
	)
	(zone
		(net "P12V_STBY_VIN_PU4")
		(layer "F.Cu")
		(hatch none 0.5)
		(connect_pads
			(clearance 0.5)
		)
		(min_thickness 0.25)
		(fill yes
			(thermal_gap 0.5)
			(thermal_bridge_width 0.5)
			(island_removal_mode 0)
		)
		(polygon
			(pts
				(xy 154.052016 -12.437618) (xy 154.02687 -12.462764) (xy 154.02687 -14.698726) (xy 154.316938 -14.98854)
				(xy 154.316938 -18.416778) (xy 154.012138 -18.721578) (xy 153.097738 -18.721578) (xy 152.655016 -19.1643)
				(xy 152.655016 -20.692618) (xy 152.909016 -20.946618) (xy 156.084016 -20.946618) (xy 156.338016 -20.692618)
				(xy 156.338016 -13.961618) (xy 154.814016 -12.437618)
			)
		)
		(polygon
			(pts
				(xy 155.815538 -16.232378) (xy 155.612338 -16.232378) (xy 155.612338 -16.435578) (xy 155.815538 -16.435578)
			)
		)
		(polygon
			(pts
				(xy 155.815538 -15.622778) (xy 155.612338 -15.622778) (xy 155.612338 -15.825978) (xy 155.815538 -15.825978)
			)
		)
	)
	(zone
		(layer "F.Cu")
		(hatch none 0.5)
		(connect_pads
			(clearance 0)
		)
		(min_thickness 0.25)
		(keepout
			(tracks not_allowed)
			(vias allowed)
			(pads allowed)
			(copperpour not_allowed)
			(footprints allowed)
		)
		(placement
			(enabled no)
			(sheetname "")
		)
		(fill
			(thermal_gap 0.5)
			(thermal_bridge_width 0.5)
			(island_removal_mode 0)
		)
		(polygon
			(pts
				(arc
					(start 145.2499 -120.000014)
					(mid 149.999954 -115.24996)
					(end 154.750008 -120.000014)
				)
				(arc
					(start 154.750008 -120.000014)
					(mid 149.999954 -124.750068)
					(end 145.2499 -120.000014)
				)
			)
		)
	)
	(zone
		(net "P3V3_STBY_LL")
		(layer "F.Cu")
		(hatch none 0.5)
		(connect_pads
			(clearance 0.5)
		)
		(min_thickness 0.25)
		(fill yes
			(thermal_gap 0.5)
			(thermal_bridge_width 0.5)
			(island_removal_mode 0)
		)
		(polygon
			(pts
				(xy 36.410646 -181.53761) (xy 36.283646 -181.66461) (xy 36.283646 -185.14314) (xy 35.862006 -185.56478)
				(xy 35.862006 -186.92876) (xy 36.258246 -187.325) (xy 36.9824 -187.325) (xy 37.1602 -187.5028) (xy 37.1602 -188.337952)
				(xy 37.338 -188.515752) (xy 41.232328 -188.515752) (xy 41.80332 -187.94476) (xy 41.80332 -182.34025)
				(xy 41.00068 -181.53761)
			)
		)
		(polygon
			(pts
				(xy 37.850318 -188.175392) (xy 37.647118 -188.175392) (xy 37.647118 -188.378592) (xy 37.850318 -188.378592)
			)
		)
		(polygon
			(pts
				(xy 37.850318 -187.565792) (xy 37.647118 -187.565792) (xy 37.647118 -187.768992) (xy 37.850318 -187.768992)
			)
		)
	)
	(zone
		(net "GND")
		(layer "F.Cu")
		(hatch none 0.5)
		(connect_pads
			(clearance 0.5)
		)
		(min_thickness 0.25)
		(fill yes
			(thermal_gap 0.5)
			(thermal_bridge_width 0.5)
			(island_removal_mode 0)
		)
		(polygon
			(pts
				(xy 217.024458 -47.010574) (xy 216.246456 -47.788576) (xy 216.246456 -49.556924) (xy 217.002106 -50.312574)
				(xy 223.673162 -50.312574) (xy 223.774762 -50.210974) (xy 223.774762 -49.93894) (xy 223.800162 -49.91354)
				(xy 225.819462 -49.91354) (xy 226.039172 -49.69383) (xy 226.039172 -47.188374) (xy 225.868738 -47.01794)
				(xy 225.146362 -47.01794) (xy 225.140266 -47.024036) (xy 224.149666 -47.024036) (xy 224.136458 -47.010574)
			)
		)
	)
	(zone
		(net "GND")
		(layer "F.Cu")
		(hatch none 0.5)
		(connect_pads
			(clearance 0.5)
		)
		(min_thickness 0.25)
		(fill yes
			(thermal_gap 0.5)
			(thermal_bridge_width 0.5)
			(island_removal_mode 0)
		)
		(polygon
			(pts
				(xy 76.145644 -160.5788) (xy 76.145644 -161.2265) (xy 75.980544 -161.3916) (xy 74.295 -161.3916)
				(xy 74.0156 -161.671) (xy 74.0156 -162.814) (xy 74.2061 -163.0045) (xy 76.171044 -163.0045) (xy 76.196444 -163.0299)
				(xy 76.196444 -163.672774) (xy 76.35367 -163.83) (xy 79.26451 -163.83) (xy 79.422244 -163.672266)
				(xy 79.422244 -163.0807) (xy 79.473044 -163.0299) (xy 81.1276 -163.0299) (xy 81.4705 -163.3728)
				(xy 82.1309 -163.3728) (xy 82.4738 -163.0299) (xy 85.344 -163.0299) (xy 85.4964 -162.8775) (xy 85.4964 -162.3822)
				(xy 85.1408 -162.0266) (xy 85.1408 -160.7312) (xy 81.822544 -160.7312) (xy 81.174844 -161.3789)
				(xy 79.447644 -161.3789) (xy 79.447644 -161.3662) (xy 79.4258 -161.344356) (xy 79.4258 -160.595056)
				(xy 79.409544 -160.5788)
			)
		)
		(polygon
			(pts
				(xy 82.1944 -162.6616) (xy 81.9912 -162.6616) (xy 81.9912 -162.8648) (xy 82.1944 -162.8648)
			)
		)
		(polygon
			(pts
				(xy 81.5848 -162.6616) (xy 81.3816 -162.6616) (xy 81.3816 -162.8648) (xy 81.5848 -162.8648)
			)
		)
	)
	(zone
		(net "P3V3_M2")
		(layer "F.Cu")
		(hatch none 0.5)
		(connect_pads
			(clearance 0.5)
		)
		(min_thickness 0.25)
		(fill yes
			(thermal_gap 0.5)
			(thermal_bridge_width 0.5)
			(island_removal_mode 0)
		)
		(polygon
			(pts
				(xy 217.914728 -68.018406) (xy 217.368628 -68.564506) (xy 217.368628 -82.140552) (xy 218.950032 -83.721956)
				(xy 225.485706 -83.721956) (xy 226.292664 -82.914998) (xy 226.292664 -68.275962) (xy 226.035108 -68.018406)
			)
		)
	)
	(zone
		(layer "F.Cu")
		(hatch none 0.5)
		(connect_pads
			(clearance 0)
		)
		(min_thickness 0.25)
		(keepout
			(tracks allowed)
			(vias allowed)
			(pads allowed)
			(copperpour allowed)
			(footprints allowed)
		)
		(placement
			(enabled no)
			(sheetname "")
		)
		(fill
			(thermal_gap 0.5)
			(thermal_bridge_width 0.5)
			(island_removal_mode 0)
		)
		(polygon
			(pts
				(xy 73.6854 -135.6614) (xy 76.1492 -135.6614) (xy 76.2762 -135.5344) (xy 76.2762 -134.7724) (xy 76.2762 -134.2644)
				(xy 76.2762 -133.8072) (xy 76.1492 -133.6802) (xy 73.7362 -133.6802) (xy 73.5838 -133.8326) (xy 73.5838 -134.4422)
				(xy 73.5838 -134.7978) (xy 73.5838 -135.5598)
			)
		)
	)
	(zone
		(layer "F.Cu")
		(hatch none 0.5)
		(connect_pads
			(clearance 0)
		)
		(min_thickness 0.25)
		(keepout
			(tracks not_allowed)
			(vias allowed)
			(pads allowed)
			(copperpour not_allowed)
			(footprints allowed)
		)
		(placement
			(enabled no)
			(sheetname "")
		)
		(fill
			(thermal_gap 0.5)
			(thermal_bridge_width 0.5)
			(island_removal_mode 0)
		)
		(polygon
			(pts
				(arc
					(start 78.503018 -70.508622)
					(mid 78.122145 -70.127368)
					(end 77.741018 -70.508368)
				)
				(arc
					(start 77.741018 -70.65391)
					(mid 77.806337 -70.62647)
					(end 77.869288 -70.593966)
				)
				(arc
					(start 77.869288 -70.593966)
					(mid 78.332708 -70.344966)
					(end 77.975206 -70.730872)
				)
				(arc
					(start 77.975206 -70.730872)
					(mid 77.861247 -70.790104)
					(end 77.741018 -70.835266)
				)
				(arc
					(start 77.741018 -71.07047)
					(mid 77.861241 -71.115646)
					(end 77.975206 -71.174864)
				)
				(arc
					(start 77.975206 -71.174864)
					(mid 78.332687 -71.560754)
					(end 77.869288 -71.31177)
				)
				(arc
					(start 77.869288 -71.31177)
					(mid 77.80633 -71.279279)
					(end 77.741018 -71.251826)
				)
				(arc
					(start 77.741018 -71.397368)
					(mid 78.122018 -71.778368)
					(end 78.503018 -71.397368)
				)
			)
		)
	)
	(zone
		(layer "F.Cu")
		(hatch none 0.5)
		(connect_pads
			(clearance 0)
		)
		(min_thickness 0.25)
		(keepout
			(tracks allowed)
			(vias allowed)
			(pads allowed)
			(copperpour allowed)
			(footprints not_allowed)
		)
		(placement
			(enabled no)
			(sheetname "")
		)
		(fill
			(thermal_gap 0.5)
			(thermal_bridge_width 0.5)
			(island_removal_mode 0)
		)
		(polygon
			(pts
				(xy 210.399884 -40.25011) (xy 198.399908 -40.25011)
				(arc
					(start 198.399908 -51.250088)
					(mid 204.399896 -57.250076)
					(end 210.399884 -51.250088)
				)
			)
		)
	)
	(zone
		(net "TPS74801_P1V2_STBY_OUT")
		(layer "F.Cu")
		(hatch none 0.5)
		(connect_pads
			(clearance 0.5)
		)
		(min_thickness 0.25)
		(fill yes
			(thermal_gap 0.5)
			(thermal_bridge_width 0.5)
			(island_removal_mode 0)
		)
		(polygon
			(pts
				(xy 16.3322 -161.6202) (xy 16.2052 -161.7472) (xy 16.2052 -163.6014) (xy 16.21282 -163.60902) (xy 16.21282 -163.83762)
				(xy 16.32712 -163.95192) (xy 16.9164 -163.95192) (xy 17.0942 -164.12972) (xy 17.0942 -165.608) (xy 16.4846 -166.2176)
				(xy 16.4846 -167.1574) (xy 16.51 -167.1828) (xy 18.5674 -167.1828) (xy 18.6182 -167.2336) (xy 18.6182 -167.9956)
				(xy 19.812 -167.9956) (xy 19.9136 -167.894) (xy 19.9136 -167.5892) (xy 20.1676 -167.3352) (xy 23.622 -167.3352)
				(xy 23.9776 -166.9796) (xy 23.9776 -161.8742) (xy 23.7236 -161.6202)
			)
		)
		(polygon
			(pts
				(xy 16.886936 -163.1442) (xy 16.683736 -163.1442) (xy 16.683736 -163.3474) (xy 16.886936 -163.3474)
			)
		)
		(polygon
			(pts
				(xy 16.853916 -162.7251) (xy 16.650716 -162.7251) (xy 16.650716 -162.9283) (xy 16.853916 -162.9283)
			)
		)
		(polygon
			(pts
				(xy 22.098 -162.386264) (xy 21.8948 -162.386264) (xy 21.8948 -162.589464) (xy 22.098 -162.589464)
			)
		)
		(polygon
			(pts
				(xy 21.4884 -162.386264) (xy 21.2852 -162.386264) (xy 21.2852 -162.589464) (xy 21.4884 -162.589464)
			)
		)
		(polygon
			(pts
				(xy 16.853916 -162.1663) (xy 16.650716 -162.1663) (xy 16.650716 -162.3695) (xy 16.853916 -162.3695)
			)
		)
	)
	(zone
		(layer "F.Cu")
		(hatch none 0.5)
		(connect_pads
			(clearance 0)
		)
		(min_thickness 0.25)
		(keepout
			(tracks not_allowed)
			(vias allowed)
			(pads allowed)
			(copperpour not_allowed)
			(footprints allowed)
		)
		(placement
			(enabled no)
			(sheetname "")
		)
		(fill
			(thermal_gap 0.5)
			(thermal_bridge_width 0.5)
			(island_removal_mode 0)
		)
		(polygon
			(pts
				(arc
					(start 13.24991 -120.000014)
					(mid 17.999964 -115.24996)
					(end 22.750018 -120.000014)
				)
				(arc
					(start 22.750018 -120.000014)
					(mid 17.999964 -124.750068)
					(end 13.24991 -120.000014)
				)
			)
		)
	)
	(zone
		(net "MB0_CM_GATE_2")
		(layer "F.Cu")
		(hatch none 0.5)
		(connect_pads
			(clearance 0.5)
		)
		(min_thickness 0.25)
		(fill yes
			(thermal_gap 0.5)
			(thermal_bridge_width 0.5)
			(island_removal_mode 0)
		)
		(polygon
			(pts
				(xy 127.470154 -6.627368) (xy 126.7206 -7.376922) (xy 126.7206 -7.8232) (xy 126.1364 -8.4074) (xy 126.1364 -8.89)
				(xy 126.815088 -9.568688) (xy 128.47193 -9.568688) (xy 128.672336 -9.368282) (xy 128.672336 -7.829804)
				(xy 128.540256 -7.69747) (xy 128.540256 -6.686804) (xy 128.48082 -6.627368)
			)
		)
		(polygon
			(pts
				(xy 127.782574 -7.441946) (xy 127.579374 -7.441946) (xy 127.579374 -7.645146) (xy 127.782574 -7.645146)
			)
		)
	)
	(zone
		(net "P2V5_STBY")
		(layer "F.Cu")
		(hatch none 0.5)
		(connect_pads
			(clearance 0.5)
		)
		(min_thickness 0.25)
		(fill yes
			(thermal_gap 0.5)
			(thermal_bridge_width 0.5)
			(island_removal_mode 0)
		)
		(polygon
			(pts
				(xy 75.588876 -170.816524) (xy 75.565 -170.8404) (xy 75.565 -172.0088) (xy 75.70978 -172.15358)
				(xy 79.201264 -172.15358) (xy 79.307182 -172.047662) (xy 79.307182 -170.938698) (xy 79.185008 -170.816524)
			)
		)
	)
	(zone
		(layer "F.Cu")
		(hatch none 0.5)
		(connect_pads
			(clearance 0)
		)
		(min_thickness 0.25)
		(keepout
			(tracks allowed)
			(vias allowed)
			(pads allowed)
			(copperpour allowed)
			(footprints allowed)
		)
		(placement
			(enabled no)
			(sheetname "")
		)
		(fill
			(thermal_gap 0.5)
			(thermal_bridge_width 0.5)
			(island_removal_mode 0)
		)
		(polygon
			(pts
				(xy 65.278 -177.5714) (xy 65.278 -175.7172) (xy 66.6242 -175.7172) (xy 66.6242 -177.5714)
			)
		)
	)
	(zone
		(layer "F.Cu")
		(hatch none 0.5)
		(connect_pads
			(clearance 0)
		)
		(min_thickness 0.25)
		(keepout
			(tracks not_allowed)
			(vias allowed)
			(pads allowed)
			(copperpour not_allowed)
			(footprints allowed)
		)
		(placement
			(enabled no)
			(sheetname "")
		)
		(fill
			(thermal_gap 0.5)
			(thermal_bridge_width 0.5)
			(island_removal_mode 0)
		)
		(polygon
			(pts
				(arc
					(start 217.749882 -120.000014)
					(mid 222.499936 -115.24996)
					(end 227.24999 -120.000014)
				)
				(arc
					(start 227.24999 -120.000014)
					(mid 222.499936 -124.750068)
					(end 217.749882 -120.000014)
				)
			)
		)
	)
	(zone
		(net "GND")
		(layer "F.Cu")
		(hatch none 0.5)
		(connect_pads
			(clearance 0.5)
		)
		(min_thickness 0.25)
		(fill yes
			(thermal_gap 0.5)
			(thermal_bridge_width 0.5)
			(island_removal_mode 0)
		)
		(polygon
			(pts
				(xy 165.746938 -5.869178) (xy 165.492938 -6.123178) (xy 165.492938 -8.663178) (xy 165.79596 -8.9662)
				(xy 170.346116 -8.9662) (xy 170.420538 -8.891778) (xy 170.420538 -6.046978) (xy 170.242738 -5.869178)
			)
		)
		(polygon
			(pts
				(xy 169.836338 -8.256778) (xy 169.633138 -8.256778) (xy 169.633138 -8.459978) (xy 169.836338 -8.459978)
			)
		)
	)
	(zone
		(layer "F.Cu")
		(hatch none 0.5)
		(connect_pads
			(clearance 0)
		)
		(min_thickness 0.25)
		(keepout
			(tracks not_allowed)
			(vias allowed)
			(pads allowed)
			(copperpour not_allowed)
			(footprints allowed)
		)
		(placement
			(enabled no)
			(sheetname "")
		)
		(fill
			(thermal_gap 0.5)
			(thermal_bridge_width 0.5)
			(island_removal_mode 0)
		)
		(polygon
			(pts
				(arc
					(start 227.24999 -7.999984)
					(mid 222.499936 -12.750038)
					(end 217.749882 -7.999984)
				)
				(arc
					(start 217.749882 -7.999984)
					(mid 222.499936 -3.24993)
					(end 227.24999 -7.999984)
				)
			)
		)
	)
	(zone
		(layer "F.Cu")
		(hatch none 0.5)
		(connect_pads
			(clearance 0)
		)
		(min_thickness 0.25)
		(keepout
			(tracks allowed)
			(vias allowed)
			(pads allowed)
			(copperpour allowed)
			(footprints allowed)
		)
		(placement
			(enabled no)
			(sheetname "")
		)
		(fill
			(thermal_gap 0.5)
			(thermal_bridge_width 0.5)
			(island_removal_mode 0)
		)
		(polygon
			(pts
				(xy 115.131342 -6.644894) (xy 116.985542 -6.644894) (xy 116.985542 -10.8966) (xy 115.131342 -10.8966)
			)
		)
	)
	(zone
		(layer "F.Cu")
		(hatch none 0.5)
		(connect_pads
			(clearance 0)
		)
		(min_thickness 0.25)
		(keepout
			(tracks allowed)
			(vias allowed)
			(pads allowed)
			(copperpour allowed)
			(footprints allowed)
		)
		(placement
			(enabled no)
			(sheetname "")
		)
		(fill
			(thermal_gap 0.5)
			(thermal_bridge_width 0.5)
			(island_removal_mode 0)
		)
		(polygon
			(pts
				(xy 116.830094 -13.062458) (xy 116.830094 -11.208258) (xy 121.0818 -11.208258) (xy 121.0818 -13.062458)
			)
		)
	)
	(zone
		(net "GND")
		(layer "F.Cu")
		(hatch none 0.5)
		(connect_pads
			(clearance 0.5)
		)
		(min_thickness 0.25)
		(fill yes
			(thermal_gap 0.5)
			(thermal_bridge_width 0.5)
			(island_removal_mode 0)
		)
		(polygon
			(pts
				(xy 89.154 -47.371) (xy 88.9254 -47.5996) (xy 88.9254 -49.5808) (xy 88.9762 -49.6316) (xy 89.7128 -49.6316)
				(xy 90.2208 -49.1236) (xy 90.2208 -47.4472) (xy 90.1446 -47.371)
			)
		)
		(polygon
			(pts
				(xy 89.581228 -48.787812) (xy 89.378028 -48.787812) (xy 89.378028 -48.991012) (xy 89.581228 -48.991012)
			)
		)
		(polygon
			(pts
				(xy 89.632028 -48.406812) (xy 89.428828 -48.406812) (xy 89.428828 -48.610012) (xy 89.632028 -48.610012)
			)
		)
		(polygon
			(pts
				(xy 89.632028 -47.797212) (xy 89.428828 -47.797212) (xy 89.428828 -48.000412) (xy 89.632028 -48.000412)
			)
		)
	)
	(zone
		(layer "F.Cu")
		(hatch none 0.5)
		(connect_pads
			(clearance 0)
		)
		(min_thickness 0.25)
		(keepout
			(tracks not_allowed)
			(vias allowed)
			(pads allowed)
			(copperpour not_allowed)
			(footprints allowed)
		)
		(placement
			(enabled no)
			(sheetname "")
		)
		(fill
			(thermal_gap 0.5)
			(thermal_bridge_width 0.5)
			(island_removal_mode 0)
		)
		(polygon
			(pts
				(arc
					(start 85.367622 -78.50759)
					(mid 84.986749 -78.126336)
					(end 84.605622 -78.507336)
				)
				(arc
					(start 84.605622 -78.652878)
					(mid 84.670941 -78.625438)
					(end 84.733892 -78.592934)
				)
				(arc
					(start 84.733892 -78.592934)
					(mid 85.197312 -78.343934)
					(end 84.83981 -78.72984)
				)
				(arc
					(start 84.83981 -78.72984)
					(mid 84.725851 -78.789072)
					(end 84.605622 -78.834234)
				)
				(arc
					(start 84.605622 -79.069438)
					(mid 84.725845 -79.114614)
					(end 84.83981 -79.173832)
				)
				(arc
					(start 84.83981 -79.173832)
					(mid 85.197291 -79.559722)
					(end 84.733892 -79.310738)
				)
				(arc
					(start 84.733892 -79.310738)
					(mid 84.670934 -79.278247)
					(end 84.605622 -79.250794)
				)
				(arc
					(start 84.605622 -79.396336)
					(mid 84.986622 -79.777336)
					(end 85.367622 -79.396336)
				)
			)
		)
	)
	(zone
		(layer "F.Cu")
		(hatch none 0.5)
		(connect_pads
			(clearance 0)
		)
		(min_thickness 0.25)
		(keepout
			(tracks not_allowed)
			(vias allowed)
			(pads allowed)
			(copperpour not_allowed)
			(footprints allowed)
		)
		(placement
			(enabled no)
			(sheetname "")
		)
		(fill
			(thermal_gap 0.5)
			(thermal_bridge_width 0.5)
			(island_removal_mode 0)
		)
		(polygon
			(pts
				(arc
					(start 217.749882 -187.999878)
					(mid 222.499936 -183.249824)
					(end 227.24999 -187.999878)
				)
				(arc
					(start 227.24999 -187.999878)
					(mid 222.499936 -192.749932)
					(end 217.749882 -187.999878)
				)
			)
		)
	)
	(zone
		(layer "F.Cu")
		(hatch none 0.5)
		(connect_pads
			(clearance 0)
		)
		(min_thickness 0.25)
		(keepout
			(tracks allowed)
			(vias allowed)
			(pads allowed)
			(copperpour allowed)
			(footprints allowed)
		)
		(placement
			(enabled no)
			(sheetname "")
		)
		(fill
			(thermal_gap 0.5)
			(thermal_bridge_width 0.5)
			(island_removal_mode 0)
		)
		(polygon
			(pts
				(xy 170.3578 -136.5758) (xy 184.1754 -136.5758) (xy 184.531 -136.2202) (xy 184.531 -134.0612) (xy 184.404 -133.9342)
				(xy 170.2308 -133.9342) (xy 169.9006 -134.2644) (xy 169.9006 -136.1186)
			)
		)
	)
	(zone
		(layer "F.Cu")
		(hatch none 0.5)
		(connect_pads
			(clearance 0)
		)
		(min_thickness 0.25)
		(keepout
			(tracks allowed)
			(vias allowed)
			(pads allowed)
			(copperpour allowed)
			(footprints not_allowed)
		)
		(placement
			(enabled no)
			(sheetname "")
		)
		(fill
			(thermal_gap 0.5)
			(thermal_bridge_width 0.5)
			(island_removal_mode 0)
		)
		(polygon
			(pts
				(xy 225.000058 -172.500036) (xy 215.000078 -172.500036) (xy 215.000078 -182.500016) (xy 225.000058 -182.500016)
			)
		)
	)
	(zone
		(net "P1V15_STBY")
		(layer "F.Cu")
		(hatch none 0.5)
		(connect_pads
			(clearance 0.5)
		)
		(min_thickness 0.25)
		(fill yes
			(thermal_gap 0.5)
			(thermal_bridge_width 0.5)
			(island_removal_mode 0)
		)
		(polygon
			(pts
				(xy 33.2232 -163.2966) (xy 33.1724 -163.3474) (xy 33.1724 -164.5158) (xy 33.0454 -164.6428) (xy 33.0454 -165.3032)
				(xy 33.2486 -165.5064) (xy 34.7726 -165.5064) (xy 34.8996 -165.3794) (xy 34.8996 -164.5412) (xy 34.7472 -164.3888)
				(xy 34.7472 -163.3474) (xy 34.6964 -163.2966)
			)
		)
	)
	(zone
		(net "MB0_P12V_MAIN_R")
		(layer "F.Cu")
		(hatch none 0.5)
		(connect_pads
			(clearance 0.5)
		)
		(min_thickness 0.25)
		(fill yes
			(thermal_gap 0.5)
			(thermal_bridge_width 0.5)
			(island_removal_mode 0)
		)
		(polygon
			(pts
				(xy 136.144 -5.346192) (xy 135.9916 -5.498592) (xy 135.9916 -10.498836) (xy 136.045956 -10.553192)
				(xy 136.8044 -10.553192) (xy 137.140696 -10.889488) (xy 137.140696 -12.732766) (xy 137.195814 -12.787884)
				(xy 141.066012 -12.787884) (xy 142.197328 -11.656568) (xy 142.197328 -5.752592) (xy 141.790928 -5.346192)
			)
		)
	)
	(zone
		(layer "F.Cu")
		(hatch none 0.5)
		(connect_pads
			(clearance 0)
		)
		(min_thickness 0.25)
		(keepout
			(tracks allowed)
			(vias allowed)
			(pads allowed)
			(copperpour allowed)
			(footprints allowed)
		)
		(placement
			(enabled no)
			(sheetname "")
		)
		(fill
			(thermal_gap 0.5)
			(thermal_bridge_width 0.5)
			(island_removal_mode 0)
		)
		(polygon
			(pts
				(xy 77.0382 -135.6614) (xy 79.248 -135.6614) (xy 79.5528 -135.3566) (xy 79.5528 -134.5692) (xy 79.1972 -134.2136)
				(xy 77.1906 -134.2136) (xy 76.9874 -134.4168) (xy 76.9874 -135.6106)
			)
		)
	)
	(zone
		(net "GND")
		(layer "F.Cu")
		(hatch none 0.5)
		(connect_pads
			(clearance 0.5)
		)
		(min_thickness 0.25)
		(fill yes
			(thermal_gap 0.5)
			(thermal_bridge_width 0.5)
			(island_removal_mode 0)
		)
		(polygon
			(pts
				(xy 83.2104 -154.3558) (xy 83.0834 -154.4828) (xy 83.0834 -158.1658) (xy 83.2866 -158.369) (xy 85.4202 -158.369)
				(xy 85.6234 -158.1658) (xy 85.6234 -155.052268) (xy 84.926932 -154.3558)
			)
		)
	)
	(zone
		(net "P12V_STBY")
		(layer "F.Cu")
		(hatch none 0.5)
		(connect_pads
			(clearance 0.5)
		)
		(min_thickness 0.25)
		(fill yes
			(thermal_gap 0.5)
			(thermal_bridge_width 0.5)
			(island_removal_mode 0)
		)
		(polygon
			(pts
				(xy 20.713954 -182.340758) (xy 20.632928 -182.421784) (xy 20.632928 -183.958738) (xy 20.653756 -183.979312)
				(xy 20.653756 -184.21096) (xy 21.004022 -184.561226) (xy 22.987762 -184.561226) (xy 23.021798 -184.52719)
				(xy 23.021798 -182.509414) (xy 23.013162 -182.509414) (xy 22.844506 -182.340758)
			)
		)
		(polygon
			(pts
				(xy 21.8567 -184.1627) (xy 21.6535 -184.1627) (xy 21.6535 -184.3659) (xy 21.8567 -184.3659)
			)
		)
		(polygon
			(pts
				(xy 21.8567 -182.7657) (xy 21.6535 -182.7657) (xy 21.6535 -182.9689) (xy 21.8567 -182.9689)
			)
		)
	)
	(zone
		(layer "F.Cu")
		(hatch none 0.5)
		(connect_pads
			(clearance 0)
		)
		(min_thickness 0.25)
		(keepout
			(tracks not_allowed)
			(vias allowed)
			(pads allowed)
			(copperpour not_allowed)
			(footprints allowed)
		)
		(placement
			(enabled no)
			(sheetname "")
		)
		(fill
			(thermal_gap 0.5)
			(thermal_bridge_width 0.5)
			(island_removal_mode 0)
		)
		(polygon
			(pts
				(arc
					(start 22.800056 -55.79999)
					(mid 27.55011 -60.550044)
					(end 22.800056 -65.300098)
				)
				(xy 8.64997 -65.300098) (xy 8.64997 -55.79999)
			)
		)
	)
	(zone
		(net "GND")
		(layer "F.Cu")
		(hatch none 0.5)
		(connect_pads
			(clearance 0.5)
		)
		(min_thickness 0.25)
		(fill yes
			(thermal_gap 0.5)
			(thermal_bridge_width 0.5)
			(island_removal_mode 0)
		)
		(polygon
			(pts
				(xy 227.198682 -67.97294) (xy 226.877372 -68.29425) (xy 226.877372 -80.527906) (xy 227.247704 -80.898238)
				(xy 229.719124 -80.898238) (xy 229.998524 -80.618838) (xy 229.998524 -68.922138) (xy 229.998016 -68.92163)
				(xy 229.998016 -68.301108) (xy 229.669848 -67.97294)
			)
		)
	)
	(zone
		(net "P12V_STBY_VIN_PU2")
		(layer "F.Cu")
		(hatch none 0.5)
		(connect_pads
			(clearance 0.5)
		)
		(min_thickness 0.25)
		(fill yes
			(thermal_gap 0.5)
			(thermal_bridge_width 0.5)
			(island_removal_mode 0)
		)
		(polygon
			(pts
				(xy 24.268176 -181.53761) (xy 23.687532 -182.118254) (xy 23.687532 -184.555638) (xy 23.173944 -185.069226)
				(xy 23.173944 -186.18962) (xy 23.135082 -186.228482) (xy 25.099518 -186.228482) (xy 25.107646 -186.23661)
				(xy 30.40507 -186.23661) (xy 31.0134 -186.84494) (xy 32.27578 -186.84494) (xy 32.42564 -186.69508)
				(xy 32.42564 -184.912254) (xy 32.346646 -184.83326) (xy 32.346646 -181.79161) (xy 32.092646 -181.53761)
			)
		)
		(polygon
			(pts
				(xy 24.9301 -184.1627) (xy 24.7269 -184.1627) (xy 24.7269 -184.3659) (xy 24.9301 -184.3659)
			)
		)
		(polygon
			(pts
				(xy 24.9301 -182.7657) (xy 24.7269 -182.7657) (xy 24.7269 -182.9689) (xy 24.9301 -182.9689)
			)
		)
	)
	(zone
		(net "P3V3_STBY")
		(layer "F.Cu")
		(hatch none 0.5)
		(connect_pads
			(clearance 0.5)
		)
		(min_thickness 0.25)
		(fill yes
			(thermal_gap 0.5)
			(thermal_bridge_width 0.5)
			(island_removal_mode 0)
		)
		(polygon
			(pts
				(xy 94.81058 -46.596046) (xy 94.711774 -46.694852) (xy 94.711774 -50.477928) (xy 94.344744 -50.844958)
				(xy 94.344744 -51.692302) (xy 94.589854 -51.937412) (xy 95.449644 -51.937412) (xy 95.647256 -51.7398)
				(xy 95.647256 -46.714918) (xy 95.528384 -46.596046)
			)
		)
		(polygon
			(pts
				(xy 95.428816 -50.315114) (xy 95.225616 -50.315114) (xy 95.225616 -50.518314) (xy 95.428816 -50.518314)
			)
		)
		(polygon
			(pts
				(xy 95.428816 -49.705514) (xy 95.225616 -49.705514) (xy 95.225616 -49.908714) (xy 95.428816 -49.908714)
			)
		)
		(polygon
			(pts
				(xy 95.042482 -47.054262) (xy 94.839282 -47.054262) (xy 94.839282 -47.257462) (xy 95.042482 -47.257462)
			)
		)
	)
	(zone
		(net "GND")
		(layer "F.Cu")
		(hatch none 0.5)
		(connect_pads
			(clearance 0.5)
		)
		(min_thickness 0.25)
		(fill yes
			(thermal_gap 0.5)
			(thermal_bridge_width 0.5)
			(island_removal_mode 0)
		)
		(polygon
			(pts
				(xy 92.1004 -39.751) (xy 89.9414 -41.91) (xy 89.9414 -44.2722) (xy 90.0176 -44.3484) (xy 90.8812 -44.3484)
				(xy 92.2782 -42.9514) (xy 94.361 -42.9514) (xy 94.7166 -42.5958) (xy 94.7166 -39.9288) (xy 94.5388 -39.751)
			)
		)
	)
	(zone
		(layer "F.Cu")
		(hatch none 0.5)
		(connect_pads
			(clearance 0)
		)
		(min_thickness 0.25)
		(keepout
			(tracks allowed)
			(vias allowed)
			(pads allowed)
			(copperpour allowed)
			(footprints allowed)
		)
		(placement
			(enabled no)
			(sheetname "")
		)
		(fill
			(thermal_gap 0.5)
			(thermal_bridge_width 0.5)
			(island_removal_mode 0)
		)
		(polygon
			(pts
				(xy 212.170518 -39.803324) (xy 212.170518 -41.315894) (xy 212.170518 -41.41343) (xy 212.331808 -41.57472)
				(xy 213.408006 -41.57472) (xy 213.784688 -41.198038) (xy 213.784688 -39.26078) (xy 213.364826 -38.840918)
				(xy 212.310218 -38.840918) (xy 212.170518 -38.980618)
			)
		)
	)
	(zone
		(layer "F.Cu")
		(hatch none 0.5)
		(connect_pads
			(clearance 0)
		)
		(min_thickness 0.25)
		(keepout
			(tracks not_allowed)
			(vias allowed)
			(pads allowed)
			(copperpour not_allowed)
			(footprints allowed)
		)
		(placement
			(enabled no)
			(sheetname "")
		)
		(fill
			(thermal_gap 0.5)
			(thermal_bridge_width 0.5)
			(island_removal_mode 0)
		)
		(polygon
			(pts
				(arc
					(start 77.054456 -74.461624)
					(mid 76.981581 -74.424203)
					(end 76.902818 -74.40168)
				)
				(arc
					(start 76.902818 -74.597768)
					(mid 77.283818 -74.978768)
					(end 77.664818 -74.597768)
				)
				(arc
					(start 77.664818 -73.709022)
					(mid 77.283945 -73.327768)
					(end 76.902818 -73.708768)
				)
				(arc
					(start 76.902818 -73.90511)
					(mid 76.98159 -73.882603)
					(end 77.054456 -73.845166)
				)
				(arc
					(start 77.054456 -73.845166)
					(mid 77.454178 -73.503441)
					(end 77.190854 -73.958704)
				)
				(arc
					(start 77.190854 -73.958704)
					(mid 77.054918 -74.03816)
					(end 76.902818 -74.078846)
				)
				(arc
					(start 76.902818 -74.227944)
					(mid 77.054745 -74.26859)
					(end 77.1906 -74.347832)
				)
				(arc
					(start 77.1906 -74.347832)
					(mid 77.454858 -74.80247)
					(end 77.054456 -74.461624)
				)
			)
		)
	)
	(zone
		(net "P1V8_STBY_SW")
		(layer "F.Cu")
		(hatch none 0.5)
		(connect_pads
			(clearance 0.5)
		)
		(min_thickness 0.25)
		(fill yes
			(thermal_gap 0.5)
			(thermal_bridge_width 0.5)
			(island_removal_mode 0)
		)
		(polygon
			(pts
				(xy 157.3911 -8.467344) (xy 155.385516 -10.472928) (xy 155.070302 -10.472928) (xy 155.06827 -10.474706)
				(xy 155.0416 -10.474706) (xy 155.0162 -10.500106) (xy 155.0162 -10.991088) (xy 155.005786 -11.001502)
				(xy 155.003246 -11.001502) (xy 154.991562 -11.013186) (xy 154.991562 -11.8237) (xy 154.998674 -11.830812)
				(xy 156.11221 -11.830812) (xy 156.460698 -12.1793) (xy 158.313882 -12.1793) (xy 159.758126 -13.623544)
				(xy 159.758126 -15.00378) (xy 159.84474 -15.090394) (xy 160.835086 -15.090394) (xy 160.970722 -14.954758)
				(xy 160.970722 -13.567156) (xy 161.301938 -13.23594) (xy 161.301938 -8.830818) (xy 160.938464 -8.467344)
			)
		)
		(polygon
			(pts
				(xy 160.142174 -14.048994) (xy 159.938974 -14.048994) (xy 159.938974 -14.252194) (xy 160.142174 -14.252194)
			)
		)
		(polygon
			(pts
				(xy 158.530798 -8.972804) (xy 158.327598 -8.972804) (xy 158.327598 -9.176004) (xy 158.530798 -9.176004)
			)
		)
		(polygon
			(pts
				(xy 157.921198 -8.972804) (xy 157.717998 -8.972804) (xy 157.717998 -9.176004) (xy 157.921198 -9.176004)
			)
		)
	)
	(zone
		(net "AGND_CURRENT_MON")
		(layer "F.Cu")
		(hatch none 0.5)
		(connect_pads
			(clearance 0.5)
		)
		(min_thickness 0.25)
		(fill yes
			(thermal_gap 0.5)
			(thermal_bridge_width 0.5)
			(island_removal_mode 0)
		)
		(polygon
			(pts
				(xy 124.994162 -9.2964) (xy 124.994162 -10.922762) (xy 125.5776 -11.505438) (xy 125.5776 -12.7508)
				(xy 125.7554 -12.9286) (xy 127.249936 -12.9286) (xy 127.3556 -12.822936) (xy 127.3556 -11.950954)
				(xy 126.668784 -11.264138) (xy 126.668784 -9.906762) (xy 125.982222 -9.2202) (xy 125.070362 -9.2202)
			)
		)
		(polygon
			(pts
				(xy 126.47549 -12.384278) (xy 126.27229 -12.384278) (xy 126.27229 -12.587478) (xy 126.47549 -12.587478)
			)
		)
		(polygon
			(pts
				(xy 126.47549 -11.520678) (xy 126.27229 -11.520678) (xy 126.27229 -11.723878) (xy 126.47549 -11.723878)
			)
		)
		(polygon
			(pts
				(xy 125.6538 -10.8458) (xy 125.4506 -10.8458) (xy 125.4506 -11.049) (xy 125.6538 -11.049)
			)
		)
		(polygon
			(pts
				(xy 125.6538 -10.287) (xy 125.4506 -10.287) (xy 125.4506 -10.4902) (xy 125.6538 -10.4902)
			)
		)
		(polygon
			(pts
				(xy 125.7046 -9.8552) (xy 125.5014 -9.8552) (xy 125.5014 -10.0584) (xy 125.7046 -10.0584)
			)
		)
	)
	(zone
		(layer "F.Cu")
		(hatch none 0.5)
		(connect_pads
			(clearance 0)
		)
		(min_thickness 0.25)
		(keepout
			(tracks not_allowed)
			(vias allowed)
			(pads allowed)
			(copperpour not_allowed)
			(footprints allowed)
		)
		(placement
			(enabled no)
			(sheetname "")
		)
		(fill
			(thermal_gap 0.5)
			(thermal_bridge_width 0.5)
			(island_removal_mode 0)
		)
		(polygon
			(pts
				(arc
					(start 77.054456 -93.664024)
					(mid 76.981581 -93.626603)
					(end 76.902818 -93.60408)
				)
				(arc
					(start 76.902818 -93.800168)
					(mid 77.283818 -94.181168)
					(end 77.664818 -93.800168)
				)
				(arc
					(start 77.664818 -92.911422)
					(mid 77.283945 -92.530168)
					(end 76.902818 -92.911168)
				)
				(arc
					(start 76.902818 -93.10751)
					(mid 76.98159 -93.085003)
					(end 77.054456 -93.047566)
				)
				(arc
					(start 77.054456 -93.047566)
					(mid 77.454178 -92.705841)
					(end 77.190854 -93.161104)
				)
				(arc
					(start 77.190854 -93.161104)
					(mid 77.054918 -93.24056)
					(end 76.902818 -93.281246)
				)
				(arc
					(start 76.902818 -93.430344)
					(mid 77.054745 -93.47099)
					(end 77.1906 -93.550232)
				)
				(arc
					(start 77.1906 -93.550232)
					(mid 77.454858 -94.00487)
					(end 77.054456 -93.664024)
				)
			)
		)
	)
	(zone
		(layer "F.Cu")
		(hatch none 0.5)
		(connect_pads
			(clearance 0)
		)
		(min_thickness 0.25)
		(keepout
			(tracks allowed)
			(vias allowed)
			(pads allowed)
			(copperpour allowed)
			(footprints not_allowed)
		)
		(placement
			(enabled no)
			(sheetname "")
		)
		(fill
			(thermal_gap 0.5)
			(thermal_bridge_width 0.5)
			(island_removal_mode 0)
		)
		(polygon
			(pts
				(xy 5.500116 -31.999936) (xy 5.500116 -43.999912) (xy 29.500068 -43.999912) (xy 29.500068 -32.100012)
				(xy 30.530038 -32.100012) (xy 30.530038 -48.600106) (xy 6.700012 -48.600106) (xy 6.700012 -55.79999)
				(xy 8.64997 -55.79999) (xy 8.64997 -65.300098) (xy 6.700012 -65.300098) (xy 6.700012 -103.799894)
				(xy 11.8999 -103.799894) (xy 11.8999 -109.799882) (xy 6.700012 -109.799882) (xy 6.700012 -113.050066)
				(xy 85.700108 -113.050066) (xy 85.700108 -109.799882) (xy 92.700094 -109.799882) (xy 92.700094 -100.300028)
				(xy 85.700108 -100.300028) (xy 85.700108 -44.800012) (xy 89.499948 -44.800012) (xy 89.499948 -35.299904)
				(xy 85.700108 -35.299904) (xy 85.700108 -31.049976) (xy 82.300064 -31.049976) (xy 82.300064 0) (xy 230.000048 0)
				(arc
					(start 230.000048 -193.786252)
					(mid 229.70903 -193.945107)
					(end 229.382066 -194.00012)
				)
				(arc
					(start 216.000076 -194.00012)
					(mid 215.292971 -193.707227)
					(end 215.000078 -193.000122)
				)
				(arc
					(start 215.000078 -160.999932)
					(mid 214.707185 -160.292827)
					(end 214.00008 -159.999934)
				)
				(arc
					(start 149.917912 -159.999934)
					(mid 149.39223 -159.850615)
					(end 149.023578 -159.44723)
				)
				(arc
					(start 144.405604 -150.211028)
					(mid 144.326777 -149.993655)
					(end 144.29994 -149.763988)
				)
				(arc
					(start 144.29994 -47.999904)
					(mid 143.800068 -47.500032)
					(end 143.299942 -47.999904)
				)
				(arc
					(start 104.70007 -47.999904)
					(mid 104.200198 -47.500032)
					(end 103.700072 -47.999904)
				)
				(xy 103.700072 -129.420112) (xy 73.429876 -129.420112) (xy 73.429876 -113.199926) (xy 24.5999 -113.199926)
				(xy 24.5999 -129.519934) (xy 73.429876 -129.519934) (xy 103.700072 -129.519934)
				(arc
					(start 103.700072 -183.76392)
					(mid 103.673308 -183.993728)
					(end 103.594408 -184.211214)
				)
				(arc
					(start 98.976434 -193.447162)
					(mid 98.607709 -193.850769)
					(end 98.081846 -194.00012)
				)
				(arc
					(start 5.617972 -194.00012)
					(mid 5.290993 -193.945151)
					(end 4.99999 -193.786252)
				)
				(xy 4.99999 0)
				(arc
					(start 29.53004 0)
					(mid 30.237145 -0.292893)
					(end 30.530038 -0.999998)
				)
				(xy 30.530038 -31.999936) (xy 29.500068 -31.999936)
			)
		)
	)
	(zone
		(layer "F.Cu")
		(hatch none 0.5)
		(connect_pads
			(clearance 0)
		)
		(min_thickness 0.25)
		(keepout
			(tracks not_allowed)
			(vias allowed)
			(pads allowed)
			(copperpour not_allowed)
			(footprints allowed)
		)
		(placement
			(enabled no)
			(sheetname "")
		)
		(fill
			(thermal_gap 0.5)
			(thermal_bridge_width 0.5)
			(island_removal_mode 0)
		)
		(polygon
			(pts
				(xy 185.399934 -40.25011) (xy 173.399958 -40.25011)
				(arc
					(start 173.399958 -51.250088)
					(mid 179.399946 -57.250076)
					(end 185.399934 -51.250088)
				)
			)
		)
	)
	(zone
		(layer "F.Cu")
		(hatch none 0.5)
		(connect_pads
			(clearance 0)
		)
		(min_thickness 0.25)
		(keepout
			(tracks allowed)
			(vias allowed)
			(pads allowed)
			(copperpour allowed)
			(footprints allowed)
		)
		(placement
			(enabled no)
			(sheetname "")
		)
		(fill
			(thermal_gap 0.5)
			(thermal_bridge_width 0.5)
			(island_removal_mode 0)
		)
		(polygon
			(pts
				(xy 80.7466 -53.9242) (xy 78.8924 -53.9242) (xy 76.454 -53.9242) (xy 76.439522 -53.909722) (xy 75.432158 -53.909722)
				(xy 75.15606 -53.633624) (xy 75.15606 -51.923442) (xy 75.29703 -51.782472) (xy 77.535024 -51.782472)
				(xy 77.771752 -52.0192) (xy 80.1878 -52.0192) (xy 80.7466 -52.578)
			)
		)
	)
	(zone
		(layer "F.Cu")
		(hatch none 0.5)
		(connect_pads
			(clearance 0)
		)
		(min_thickness 0.25)
		(keepout
			(tracks allowed)
			(vias allowed)
			(pads allowed)
			(copperpour allowed)
			(footprints not_allowed)
		)
		(placement
			(enabled no)
			(sheetname "")
		)
		(fill
			(thermal_gap 0.5)
			(thermal_bridge_width 0.5)
			(island_removal_mode 0)
		)
		(polygon
			(pts
				(xy 185.399934 -10.249916) (xy 173.399958 -10.249916)
				(arc
					(start 173.399958 -21.249894)
					(mid 179.399946 -27.249882)
					(end 185.399934 -21.249894)
				)
			)
		)
	)
	(zone
		(layer "F.Cu")
		(hatch none 0.5)
		(connect_pads
			(clearance 0)
		)
		(min_thickness 0.25)
		(keepout
			(tracks allowed)
			(vias allowed)
			(pads allowed)
			(copperpour allowed)
			(footprints not_allowed)
		)
		(placement
			(enabled no)
			(sheetname "")
		)
		(fill
			(thermal_gap 0.5)
			(thermal_bridge_width 0.5)
			(island_removal_mode 0)
		)
		(polygon
			(pts
				(arc
					(start 0 -0.999998)
					(mid 0.292893 -0.292893)
					(end 0.999998 0)
				)
				(xy 4.99999 0)
				(arc
					(start 4.99999 -193.786252)
					(mid 4.843029 -193.632013)
					(end 4.723638 -193.447162)
				)
				(arc
					(start 0.105664 -184.211214)
					(mid 0.026808 -183.993717)
					(end 0 -183.76392)
				)
			)
		)
	)
	(zone
		(net "P1V8_STBY")
		(layer "F.Cu")
		(hatch none 0.5)
		(connect_pads
			(clearance 0.5)
		)
		(min_thickness 0.25)
		(fill yes
			(thermal_gap 0.5)
			(thermal_bridge_width 0.5)
			(island_removal_mode 0)
		)
		(polygon
			(pts
				(xy 171.665646 -9.273286) (xy 163.58616 -9.274556) (xy 163.343844 -9.274556) (xy 162.9156 -9.7028)
				(xy 162.9156 -12.002262) (xy 164.705538 -13.7922) (xy 164.705538 -16.411956) (xy 164.910008 -16.616426)
				(xy 170.568874 -16.616426) (xy 170.915838 -16.269462) (xy 170.915838 -11.393678) (xy 171.868338 -10.441178)
				(xy 171.868338 -9.475978)
			)
		)
		(polygon
			(pts
				(xy 170.445938 -9.780778) (xy 170.242738 -9.780778) (xy 170.242738 -9.983978) (xy 170.445938 -9.983978)
			)
		)
		(polygon
			(pts
				(xy 169.836338 -9.780778) (xy 169.633138 -9.780778) (xy 169.633138 -9.983978) (xy 169.836338 -9.983978)
			)
		)
	)
	(zone
		(net "MB0_CM_GATE_R")
		(layer "F.Cu")
		(hatch none 0.5)
		(connect_pads
			(clearance 0.5)
		)
		(min_thickness 0.25)
		(fill yes
			(thermal_gap 0.5)
			(thermal_bridge_width 0.5)
			(island_removal_mode 0)
		)
		(polygon
			(pts
				(xy 130.347974 -4.9149) (xy 130.076702 -5.186172) (xy 130.076702 -6.43382) (xy 129.82956 -6.680962)
				(xy 128.90754 -6.680962) (xy 128.863344 -6.725158) (xy 128.863344 -7.50443) (xy 128.962404 -7.603236)
				(xy 129.030476 -7.671308) (xy 129.030476 -11.335766) (xy 129.15646 -11.46175) (xy 130.440176 -11.46175)
				(xy 130.577844 -11.324082) (xy 130.577844 -7.836916) (xy 130.922776 -7.491984) (xy 131.5339 -7.491984)
				(xy 131.6482 -7.377684) (xy 131.6482 -5.128514) (xy 131.434586 -4.9149)
			)
		)
		(polygon
			(pts
				(xy 129.83337 -7.442708) (xy 129.63017 -7.442708) (xy 129.63017 -7.645908) (xy 129.83337 -7.645908)
			)
		)
	)
	(zone
		(layer "F.Cu")
		(hatch none 0.5)
		(connect_pads
			(clearance 0)
		)
		(min_thickness 0.25)
		(keepout
			(tracks allowed)
			(vias allowed)
			(pads allowed)
			(copperpour allowed)
			(footprints allowed)
		)
		(placement
			(enabled no)
			(sheetname "")
		)
		(fill
			(thermal_gap 0.5)
			(thermal_bridge_width 0.5)
			(island_removal_mode 0)
		)
		(polygon
			(pts
				(xy 94.0562 -18.7198) (xy 94.0562 -15.4432) (xy 95.5802 -15.4432) (xy 95.5802 -18.7198)
			)
		)
	)
	(zone
		(layer "F.Cu")
		(hatch none 0.5)
		(connect_pads
			(clearance 0)
		)
		(min_thickness 0.25)
		(keepout
			(tracks allowed)
			(vias allowed)
			(pads allowed)
			(copperpour allowed)
			(footprints allowed)
		)
		(placement
			(enabled no)
			(sheetname "")
		)
		(fill
			(thermal_gap 0.5)
			(thermal_bridge_width 0.5)
			(island_removal_mode 0)
		)
		(polygon
			(pts
				(xy 62.9412 -145.1356) (xy 64.7954 -145.1356) (xy 64.7954 -145.7452) (xy 62.9412 -145.7452)
			)
		)
	)
	(zone
		(net "P12V_STBY_VIN_U81")
		(layer "F.Cu")
		(hatch none 0.5)
		(connect_pads
			(clearance 0.5)
		)
		(min_thickness 0.25)
		(fill yes
			(thermal_gap 0.5)
			(thermal_bridge_width 0.5)
			(island_removal_mode 0)
		)
		(polygon
			(pts
				(xy 224.311972 -98.161602) (xy 223.081088 -99.392486) (xy 220.10116 -99.392486) (xy 219.956126 -99.53752)
				(xy 219.956126 -101.83749) (xy 220.257878 -102.139242) (xy 229.335838 -102.139242) (xy 229.808024 -101.66731)
				(xy 229.808024 -99.01174) (xy 229.521512 -98.725228) (xy 227.609146 -98.725228) (xy 227.04552 -98.161602)
			)
		)
		(polygon
			(pts
				(xy 223.529906 -101.428042) (xy 223.326706 -101.428042) (xy 223.326706 -101.631242) (xy 223.529906 -101.631242)
			)
		)
		(polygon
			(pts
				(xy 222.920306 -101.428042) (xy 222.717106 -101.428042) (xy 222.717106 -101.631242) (xy 222.920306 -101.631242)
			)
		)
		(polygon
			(pts
				(xy 229.297738 -100.026978) (xy 229.094538 -100.026978) (xy 229.094538 -100.230178) (xy 229.297738 -100.230178)
			)
		)
		(polygon
			(pts
				(xy 227.900738 -100.026978) (xy 227.697538 -100.026978) (xy 227.697538 -100.230178) (xy 227.900738 -100.230178)
			)
		)
		(polygon
			(pts
				(xy 229.297738 -98.883978) (xy 229.094538 -98.883978) (xy 229.094538 -99.087178) (xy 229.297738 -99.087178)
			)
		)
		(polygon
			(pts
				(xy 227.900738 -98.883978) (xy 227.697538 -98.883978) (xy 227.697538 -99.087178) (xy 227.900738 -99.087178)
			)
		)
	)
	(zone
		(layer "F.Cu")
		(hatch none 0.5)
		(connect_pads
			(clearance 0)
		)
		(min_thickness 0.25)
		(keepout
			(tracks allowed)
			(vias allowed)
			(pads allowed)
			(copperpour allowed)
			(footprints not_allowed)
		)
		(placement
			(enabled no)
			(sheetname "")
		)
		(fill
			(thermal_gap 0.5)
			(thermal_bridge_width 0.5)
			(island_removal_mode 0)
		)
		(polygon
			(pts
				(arc
					(start 217.749882 -120.000014)
					(mid 222.499936 -115.24996)
					(end 227.24999 -120.000014)
				)
				(arc
					(start 227.24999 -120.000014)
					(mid 222.499936 -124.750068)
					(end 217.749882 -120.000014)
				)
			)
		)
	)
	(zone
		(net "GND")
		(layer "F.Cu")
		(hatch none 0.5)
		(connect_pads
			(clearance 0.5)
		)
		(min_thickness 0.25)
		(fill yes
			(thermal_gap 0.5)
			(thermal_bridge_width 0.5)
			(island_removal_mode 0)
		)
		(polygon
			(pts
				(xy 168.1226 -131.4704) (xy 167.8432 -131.7498) (xy 167.8432 -135.169148) (xy 168.156128 -135.482076)
				(xy 169.61358 -135.482076) (xy 169.7482 -135.347202) (xy 169.7482 -131.5466) (xy 169.672 -131.4704)
			)
		)
	)
	(zone
		(net "TPS74801_P2V5_STBY_OUT")
		(layer "F.Cu")
		(hatch none 0.5)
		(connect_pads
			(clearance 0.5)
		)
		(min_thickness 0.25)
		(fill yes
			(thermal_gap 0.5)
			(thermal_bridge_width 0.5)
			(island_removal_mode 0)
		)
		(polygon
			(pts
				(xy 74.73188 -172.85208) (xy 74.57313 -173.01083) (xy 74.57313 -175.03013) (xy 74.661776 -175.118776)
				(xy 75.251056 -175.118776) (xy 75.49388 -175.3616) (xy 75.49388 -176.83988) (xy 74.88428 -177.44948)
				(xy 74.88428 -178.38928) (xy 74.90968 -178.41468) (xy 76.96708 -178.41468) (xy 77.01788 -178.46548)
				(xy 77.01788 -179.22748) (xy 78.14945 -179.22748) (xy 78.227428 -179.149502) (xy 78.227428 -178.67503)
				(xy 78.763114 -178.139344) (xy 82.26171 -178.139344) (xy 82.37728 -178.023774) (xy 82.37728 -173.10608)
				(xy 82.12328 -172.85208)
			)
		)
		(polygon
			(pts
				(xy 75.286616 -174.37608) (xy 75.083416 -174.37608) (xy 75.083416 -174.57928) (xy 75.286616 -174.57928)
			)
		)
		(polygon
			(pts
				(xy 75.239372 -173.952662) (xy 75.036172 -173.952662) (xy 75.036172 -174.155862) (xy 75.239372 -174.155862)
			)
		)
		(polygon
			(pts
				(xy 75.239372 -173.393862) (xy 75.036172 -173.393862) (xy 75.036172 -173.597062) (xy 75.239372 -173.597062)
			)
		)
		(polygon
			(pts
				(xy 80.34528 -173.38548) (xy 80.14208 -173.38548) (xy 80.14208 -173.58868) (xy 80.34528 -173.58868)
			)
		)
		(polygon
			(pts
				(xy 79.73568 -173.38548) (xy 79.53248 -173.38548) (xy 79.53248 -173.58868) (xy 79.73568 -173.58868)
			)
		)
	)
	(zone
		(layer "F.Cu")
		(hatch none 0.5)
		(connect_pads
			(clearance 0)
		)
		(min_thickness 0.25)
		(keepout
			(tracks allowed)
			(vias allowed)
			(pads allowed)
			(copperpour allowed)
			(footprints not_allowed)
		)
		(placement
			(enabled no)
			(sheetname "")
		)
		(fill
			(thermal_gap 0.5)
			(thermal_bridge_width 0.5)
			(island_removal_mode 0)
		)
		(polygon
			(pts
				(arc
					(start 7.750048 -187.999878)
					(mid 12.500102 -183.249824)
					(end 17.249902 -187.999878)
				)
				(arc
					(start 17.249902 -187.999878)
					(mid 12.500102 -192.749678)
					(end 7.750048 -187.999878)
				)
			)
		)
	)
	(zone
		(layer "F.Cu")
		(hatch none 0.5)
		(connect_pads
			(clearance 0)
		)
		(min_thickness 0.25)
		(keepout
			(tracks not_allowed)
			(vias allowed)
			(pads allowed)
			(copperpour not_allowed)
			(footprints allowed)
		)
		(placement
			(enabled no)
			(sheetname "")
		)
		(fill
			(thermal_gap 0.5)
			(thermal_bridge_width 0.5)
			(island_removal_mode 0)
		)
		(polygon
			(pts
				(xy 185.399934 -10.249916) (xy 173.399958 -10.249916)
				(arc
					(start 173.399958 -21.249894)
					(mid 179.399946 -27.249882)
					(end 185.399934 -21.249894)
				)
			)
		)
	)
	(zone
		(net "DACAV33")
		(layer "F.Cu")
		(hatch none 0.5)
		(connect_pads
			(clearance 0.5)
		)
		(min_thickness 0.25)
		(fill yes
			(thermal_gap 0.5)
			(thermal_bridge_width 0.5)
			(island_removal_mode 0)
		)
		(polygon
			(pts
				(xy 30.17266 -159.4104) (xy 30.099 -159.48406) (xy 30.099 -160.147) (xy 30.8356 -160.8836) (xy 35.0012 -160.8836)
				(xy 35.052 -160.8328) (xy 35.3822 -160.8328) (xy 35.5854 -160.6296) (xy 35.5854 -159.6898) (xy 35.306 -159.4104)
			)
		)
		(polygon
			(pts
				(xy 34.036 -160.3248) (xy 33.8328 -160.3248) (xy 33.8328 -160.528) (xy 34.036 -160.528)
			)
		)
		(polygon
			(pts
				(xy 33.1724 -160.3248) (xy 32.9692 -160.3248) (xy 32.9692 -160.528) (xy 33.1724 -160.528)
			)
		)
		(polygon
			(pts
				(xy 34.9504 -159.9438) (xy 34.7472 -159.9438) (xy 34.7472 -160.147) (xy 34.9504 -160.147)
			)
		)
		(polygon
			(pts
				(xy 34.3408 -159.9438) (xy 34.1376 -159.9438) (xy 34.1376 -160.147) (xy 34.3408 -160.147)
			)
		)
		(polygon
			(pts
				(xy 30.7594 -159.893) (xy 30.5562 -159.893) (xy 30.5562 -160.0962) (xy 30.7594 -160.0962)
			)
		)
	)
	(zone
		(net "MB0_12V_CTRL_GATE1")
		(layer "F.Cu")
		(hatch none 0.5)
		(connect_pads
			(clearance 0.5)
		)
		(min_thickness 0.25)
		(fill yes
			(thermal_gap 0.5)
			(thermal_bridge_width 0.5)
			(island_removal_mode 0)
		)
		(polygon
			(pts
				(xy 132.255514 -4.100068) (xy 131.960112 -4.39547) (xy 131.960112 -7.356348) (xy 132.092954 -7.48919)
				(xy 133.375654 -7.48919) (xy 133.489954 -7.37489) (xy 133.489954 -6.965696) (xy 133.785356 -6.670294)
				(xy 135.60298 -6.670294) (xy 135.70966 -6.563614) (xy 135.70966 -4.298188) (xy 135.51154 -4.100068)
			)
		)
	)
	(zone
		(net "P1V15_STBY")
		(layer "F.Cu")
		(hatch none 0.5)
		(connect_pads
			(clearance 0.5)
		)
		(min_thickness 0.25)
		(fill yes
			(thermal_gap 0.5)
			(thermal_bridge_width 0.5)
			(island_removal_mode 0)
		)
		(polygon
			(pts
				(xy 77.292708 -151.9428) (xy 77.279754 -151.955754) (xy 76.441046 -151.955754) (xy 75.8952 -152.5016)
				(xy 75.8952 -153.4922) (xy 76.1746 -153.7716) (xy 77.957426 -153.7716) (xy 78.236826 -153.4922)
				(xy 79.87792 -153.4922) (xy 79.88046 -153.49474) (xy 79.982568 -153.392632) (xy 79.982568 -152.042368)
				(xy 79.883 -151.9428)
			)
		)
	)
	(zone
		(layer "F.Cu")
		(hatch none 0.5)
		(connect_pads
			(clearance 0)
		)
		(min_thickness 0.25)
		(keepout
			(tracks allowed)
			(vias allowed)
			(pads allowed)
			(copperpour allowed)
			(footprints not_allowed)
		)
		(placement
			(enabled no)
			(sheetname "")
		)
		(fill
			(thermal_gap 0.5)
			(thermal_bridge_width 0.5)
			(island_removal_mode 0)
		)
		(polygon
			(pts
				(xy 29.500068 -31.999936) (xy 5.500116 -31.999936) (xy 5.500116 -43.999912) (xy 29.500068 -43.999912)
			)
		)
	)
	(zone
		(layer "F.Cu")
		(hatch none 0.5)
		(connect_pads
			(clearance 0)
		)
		(min_thickness 0.25)
		(keepout
			(tracks allowed)
			(vias allowed)
			(pads allowed)
			(copperpour allowed)
			(footprints not_allowed)
		)
		(placement
			(enabled no)
			(sheetname "")
		)
		(fill
			(thermal_gap 0.5)
			(thermal_bridge_width 0.5)
			(island_removal_mode 0)
		)
		(polygon
			(pts
				(arc
					(start 217.749882 -187.999878)
					(mid 222.499936 -183.249824)
					(end 227.24999 -187.999878)
				)
				(arc
					(start 227.24999 -187.999878)
					(mid 222.499936 -192.749932)
					(end 217.749882 -187.999878)
				)
			)
		)
	)
	(zone
		(layer "F.Cu")
		(hatch none 0.5)
		(connect_pads
			(clearance 0)
		)
		(min_thickness 0.25)
		(keepout
			(tracks allowed)
			(vias allowed)
			(pads allowed)
			(copperpour allowed)
			(footprints not_allowed)
		)
		(placement
			(enabled no)
			(sheetname "")
		)
		(fill
			(thermal_gap 0.5)
			(thermal_bridge_width 0.5)
			(island_removal_mode 0)
		)
		(polygon
			(pts
				(arc
					(start 17.249902 -187.999878)
					(mid 12.500102 -192.749678)
					(end 7.750048 -187.999878)
				)
				(arc
					(start 7.750048 -187.999878)
					(mid 12.500102 -183.249824)
					(end 17.249902 -187.999878)
				)
			)
		)
	)
	(zone
		(net "P3V3_M2")
		(layer "F.Cu")
		(hatch none 0.5)
		(connect_pads
			(clearance 0.5)
		)
		(min_thickness 0.25)
		(fill yes
			(thermal_gap 0.5)
			(thermal_bridge_width 0.5)
			(island_removal_mode 0)
		)
		(polygon
			(pts
				(xy 170.607228 -120.928892) (xy 170.1038 -121.43232) (xy 170.1038 -126.4158) (xy 170.2308 -126.5428)
				(xy 170.2308 -128.1176) (xy 171.0436 -128.1176) (xy 171.0944 -128.0668) (xy 171.0944 -126.2888)
				(xy 171.2214 -126.1618) (xy 172.593 -126.1618) (xy 172.7454 -126.3142) (xy 172.7454 -128.0922) (xy 172.7708 -128.1176)
				(xy 174.5742 -128.1176) (xy 174.5996 -128.0922) (xy 174.5996 -126.111) (xy 174.8028 -125.9078) (xy 174.8028 -121.503186)
				(xy 174.228506 -120.928892)
			)
		)
	)
	(zone
		(layer "F.Cu")
		(hatch none 0.5)
		(connect_pads
			(clearance 0)
		)
		(min_thickness 0.25)
		(keepout
			(tracks allowed)
			(vias allowed)
			(pads allowed)
			(copperpour allowed)
			(footprints allowed)
		)
		(placement
			(enabled no)
			(sheetname "")
		)
		(fill
			(thermal_gap 0.5)
			(thermal_bridge_width 0.5)
			(island_removal_mode 0)
		)
		(polygon
			(pts
				(xy 152.878282 -14.776196) (xy 153.81605 -14.776196) (xy 154.977084 -13.615162) (xy 154.977084 -12.522962)
				(xy 154.900884 -12.446762) (xy 153.097484 -12.446762) (xy 152.613106 -12.93114) (xy 152.613106 -14.51102)
			)
		)
	)
	(zone
		(net "P3V3_STBY")
		(layer "F.Cu")
		(hatch none 0.5)
		(connect_pads
			(clearance 0.5)
		)
		(min_thickness 0.25)
		(fill yes
			(thermal_gap 0.5)
			(thermal_bridge_width 0.5)
			(island_removal_mode 0)
		)
		(polygon
			(pts
				(xy 77.04328 -181.48808) (xy 76.91628 -181.61508) (xy 76.91628 -182.03418) (xy 76.63688 -182.31358)
				(xy 74.90968 -182.31358) (xy 74.90968 -185.95848) (xy 74.93 -185.9788) (xy 74.93 -186.2328) (xy 75.0824 -186.3852)
				(xy 78.994 -186.3852) (xy 79.58328 -185.79592) (xy 79.58328 -181.58968) (xy 79.48168 -181.48808)
			)
		)
		(polygon
			(pts
				(xy 78.969616 -181.99608) (xy 78.766416 -181.99608) (xy 78.766416 -182.19928) (xy 78.969616 -182.19928)
			)
		)
	)
	(zone
		(layer "F.Cu")
		(hatch none 0.5)
		(connect_pads
			(clearance 0)
		)
		(min_thickness 0.25)
		(keepout
			(tracks allowed)
			(vias allowed)
			(pads allowed)
			(copperpour allowed)
			(footprints not_allowed)
		)
		(placement
			(enabled no)
			(sheetname "")
		)
		(fill
			(thermal_gap 0.5)
			(thermal_bridge_width 0.5)
			(island_removal_mode 0)
		)
		(polygon
			(pts
				(arc
					(start 154.049984 -78.000098)
					(mid 149.29993 -82.750152)
					(end 144.549876 -78.000098)
				)
				(arc
					(start 144.549876 -78.000098)
					(mid 149.29993 -73.250044)
					(end 154.049984 -78.000098)
				)
			)
		)
	)
	(zone
		(net "TPS74801_P1V15_STBY_OUT")
		(layer "F.Cu")
		(hatch none 0.5)
		(connect_pads
			(clearance 0.5)
		)
		(min_thickness 0.25)
		(fill yes
			(thermal_gap 0.5)
			(thermal_bridge_width 0.5)
			(island_removal_mode 0)
		)
		(polygon
			(pts
				(xy 78.037944 -154.1018) (xy 77.314044 -154.8257) (xy 77.314044 -156.6799) (xy 77.321664 -156.68752)
				(xy 77.321664 -156.7434) (xy 77.423264 -156.845) (xy 78.1304 -156.845) (xy 78.5368 -157.2514) (xy 78.5368 -158.3944)
				(xy 78.240128 -158.691072) (xy 78.198472 -158.691072) (xy 77.593444 -159.2961) (xy 77.593444 -160.2359)
				(xy 77.618844 -160.2613) (xy 79.676244 -160.2613) (xy 79.727044 -160.3121) (xy 79.727044 -161.0741)
				(xy 80.920844 -161.0741) (xy 81.022444 -160.9725) (xy 81.022444 -160.6677) (xy 81.276444 -160.4137)
				(xy 85.0519 -160.4137) (xy 85.1916 -160.274) (xy 85.1916 -158.8516) (xy 85.1408 -158.8008) (xy 82.804 -158.8008)
				(xy 82.5754 -158.5722) (xy 82.5754 -154.5844) (xy 81.2419 -154.5844) (xy 81.1276 -154.6987) (xy 80.0608 -154.6987)
				(xy 79.9846 -154.6225) (xy 79.9846 -154.178) (xy 79.9084 -154.1018)
			)
		)
		(polygon
			(pts
				(xy 77.9526 -156.180536) (xy 77.7494 -156.180536) (xy 77.7494 -156.383736) (xy 77.9526 -156.383736)
			)
		)
		(polygon
			(pts
				(xy 78.04658 -155.7401) (xy 77.84338 -155.7401) (xy 77.84338 -155.9433) (xy 78.04658 -155.9433)
			)
		)
		(polygon
			(pts
				(xy 81.0768 -155.2448) (xy 80.8736 -155.2448) (xy 80.8736 -155.448) (xy 81.0768 -155.448)
			)
		)
		(polygon
			(pts
				(xy 80.4672 -155.2448) (xy 80.264 -155.2448) (xy 80.264 -155.448) (xy 80.4672 -155.448)
			)
		)
		(polygon
			(pts
				(xy 78.04658 -155.1305) (xy 77.84338 -155.1305) (xy 77.84338 -155.3337) (xy 78.04658 -155.3337)
			)
		)
	)
	(zone
		(layer "F.Cu")
		(hatch none 0.5)
		(connect_pads
			(clearance 0)
		)
		(min_thickness 0.25)
		(keepout
			(tracks allowed)
			(vias allowed)
			(pads allowed)
			(copperpour allowed)
			(footprints allowed)
		)
		(placement
			(enabled no)
			(sheetname "")
		)
		(fill
			(thermal_gap 0.5)
			(thermal_bridge_width 0.5)
			(island_removal_mode 0)
		)
		(polygon
			(pts
				(xy 204.724 -128.143) (xy 205.9432 -128.143) (xy 206.0448 -128.0414) (xy 206.0448 -125.603) (xy 205.8416 -125.3998)
				(xy 205.1558 -125.3998) (xy 204.597 -125.9586) (xy 204.597 -128.016)
			)
		)
	)
	(zone
		(net "P3V3_M2")
		(layer "F.Cu")
		(hatch none 0.5)
		(connect_pads
			(clearance 0.5)
		)
		(min_thickness 0.25)
		(fill yes
			(thermal_gap 0.5)
			(thermal_bridge_width 0.5)
			(island_removal_mode 0)
		)
		(polygon
			(pts
				(xy 186.81192 -124.73559) (xy 186.605164 -124.942346) (xy 186.605164 -125.568964) (xy 187.24245 -126.20625)
				(xy 187.24245 -128.0668) (xy 187.26785 -128.0922) (xy 188.6204 -128.0922) (xy 188.7728 -127.9398)
				(xy 188.7728 -124.950982) (xy 188.557408 -124.73559)
			)
		)
	)
	(zone
		(layer "F.Cu")
		(hatch none 0.5)
		(connect_pads
			(clearance 0)
		)
		(min_thickness 0.25)
		(keepout
			(tracks allowed)
			(vias allowed)
			(pads allowed)
			(copperpour allowed)
			(footprints allowed)
		)
		(placement
			(enabled no)
			(sheetname "")
		)
		(fill
			(thermal_gap 0.5)
			(thermal_bridge_width 0.5)
			(island_removal_mode 0)
		)
		(polygon
			(pts
				(xy 63.6016 -148.1836) (xy 65.4558 -148.1836) (xy 65.4558 -148.971) (xy 63.6016 -148.971)
			)
		)
	)
	(zone
		(layer "F.Cu")
		(hatch none 0.5)
		(connect_pads
			(clearance 0)
		)
		(min_thickness 0.25)
		(keepout
			(tracks allowed)
			(vias allowed)
			(pads allowed)
			(copperpour allowed)
			(footprints allowed)
		)
		(placement
			(enabled no)
			(sheetname "")
		)
		(fill
			(thermal_gap 0.5)
			(thermal_bridge_width 0.5)
			(island_removal_mode 0)
		)
		(polygon
			(pts
				(xy 67.3608 -139.8016) (xy 67.3608 -141.6558) (xy 66.5734 -141.6558) (xy 66.5734 -139.8016)
			)
		)
	)
	(zone
		(net "P1V8_STBY")
		(layer "F.Cu")
		(hatch none 0.5)
		(connect_pads
			(clearance 0.5)
		)
		(min_thickness 0.25)
		(fill yes
			(thermal_gap 0.5)
			(thermal_bridge_width 0.5)
			(island_removal_mode 0)
		)
		(polygon
			(pts
				(xy 79.752444 -163.3347) (xy 79.625444 -163.4617) (xy 79.625444 -163.8808) (xy 79.346044 -164.1602)
				(xy 77.618844 -164.1602) (xy 77.618844 -167.8051) (xy 77.822044 -168.0083) (xy 81.38922 -168.0083)
				(xy 81.64576 -167.75176) (xy 81.64576 -166.993824) (xy 82.292444 -166.34714) (xy 82.292444 -163.8808)
				(xy 82.089244 -163.6776) (xy 81.3562 -163.6776) (xy 81.0133 -163.3347)
			)
		)
		(polygon
			(pts
				(xy 81.5848 -164.1856) (xy 81.3816 -164.1856) (xy 81.3816 -164.3888) (xy 81.5848 -164.3888)
			)
		)
	)
	(zone
		(net "GND")
		(layer "F.Cu")
		(hatch none 0.5)
		(connect_pads
			(clearance 0.5)
		)
		(min_thickness 0.25)
		(fill yes
			(thermal_gap 0.5)
			(thermal_bridge_width 0.5)
			(island_removal_mode 0)
		)
		(polygon
			(pts
				(xy 11.864594 -127.1778) (xy 6.341364 -132.70103) (xy 6.341364 -145.125186) (xy 7.09168 -145.875502)
				(xy 10.923524 -145.875502) (xy 11.3284 -145.470626) (xy 11.3284 -142.779242) (xy 10.651744 -142.102586)
				(xy 9.125966 -142.102586) (xy 8.729472 -141.706092) (xy 8.729472 -136.071864) (xy 8.733028 -136.068308)
				(xy 8.733028 -134.695438) (xy 14.447266 -128.9812) (xy 17.145 -128.9812) (xy 17.1958 -128.9304)
				(xy 21.7424 -128.9304) (xy 21.7551 -128.9431) (xy 22.4155 -128.9431) (xy 22.4536 -128.905) (xy 22.4536 -127.3302)
				(xy 22.3012 -127.1778)
			)
		)
		(polygon
			(pts
				(xy 8.277098 -141.186662) (xy 8.073898 -141.186662) (xy 8.073898 -141.389862) (xy 8.277098 -141.389862)
			)
		)
		(polygon
			(pts
				(xy 8.277098 -140.627862) (xy 8.073898 -140.627862) (xy 8.073898 -140.831062) (xy 8.277098 -140.831062)
			)
		)
		(polygon
			(pts
				(xy 8.2296 -139.7508) (xy 8.0264 -139.7508) (xy 8.0264 -139.954) (xy 8.2296 -139.954)
			)
		)
		(polygon
			(pts
				(xy 8.2296 -139.192) (xy 8.0264 -139.192) (xy 8.0264 -139.3952) (xy 8.2296 -139.3952)
			)
		)
		(polygon
			(pts
				(xy 8.295132 -138.323574) (xy 8.091932 -138.323574) (xy 8.091932 -138.526774) (xy 8.295132 -138.526774)
			)
		)
		(polygon
			(pts
				(xy 8.295132 -137.764774) (xy 8.091932 -137.764774) (xy 8.091932 -137.967974) (xy 8.295132 -137.967974)
			)
		)
		(polygon
			(pts
				(xy 8.269732 -136.894316) (xy 8.066532 -136.894316) (xy 8.066532 -137.097516) (xy 8.269732 -137.097516)
			)
		)
		(polygon
			(pts
				(xy 8.269732 -136.335516) (xy 8.066532 -136.335516) (xy 8.066532 -136.538716) (xy 8.269732 -136.538716)
			)
		)
		(polygon
			(pts
				(xy 8.27151 -135.467852) (xy 8.06831 -135.467852) (xy 8.06831 -135.671052) (xy 8.27151 -135.671052)
			)
		)
		(polygon
			(pts
				(xy 8.27151 -134.909052) (xy 8.06831 -134.909052) (xy 8.06831 -135.112252) (xy 8.27151 -135.112252)
			)
		)
		(polygon
			(pts
				(xy 21.837142 -128.2954) (xy 21.633942 -128.2954) (xy 21.633942 -128.4986) (xy 21.837142 -128.4986)
			)
		)
		(polygon
			(pts
				(xy 18.1356 -128.2954) (xy 17.9324 -128.2954) (xy 17.9324 -128.4986) (xy 18.1356 -128.4986)
			)
		)
		(polygon
			(pts
				(xy 17.5768 -128.2954) (xy 17.3736 -128.2954) (xy 17.3736 -128.4986) (xy 17.5768 -128.4986)
			)
		)
		(polygon
			(pts
				(xy 19.525742 -128.264666) (xy 19.322542 -128.264666) (xy 19.322542 -128.467866) (xy 19.525742 -128.467866)
			)
		)
		(polygon
			(pts
				(xy 18.966942 -128.264666) (xy 18.763742 -128.264666) (xy 18.763742 -128.467866) (xy 18.966942 -128.467866)
			)
		)
		(polygon
			(pts
				(xy 20.972272 -128.261364) (xy 20.769072 -128.261364) (xy 20.769072 -128.464564) (xy 20.972272 -128.464564)
			)
		)
		(polygon
			(pts
				(xy 20.413472 -128.261364) (xy 20.210272 -128.261364) (xy 20.210272 -128.464564) (xy 20.413472 -128.464564)
			)
		)
	)
	(zone
		(net "GND")
		(layer "F.Cu")
		(hatch none 0.5)
		(connect_pads
			(clearance 0.5)
		)
		(min_thickness 0.25)
		(fill yes
			(thermal_gap 0.5)
			(thermal_bridge_width 0.5)
			(island_removal_mode 0)
		)
		(polygon
			(pts
				(xy 29.845 -157.1752) (xy 29.7688 -157.2514) (xy 29.7688 -158.115) (xy 29.8704 -158.2166) (xy 30.756098 -158.2166)
				(xy 30.996636 -158.457138) (xy 30.996636 -158.829502) (xy 31.167578 -159.000444) (xy 33.016444 -159.000444)
				(xy 33.1724 -159.1564) (xy 34.8488 -159.1564) (xy 34.9504 -159.0548) (xy 34.9504 -157.7848) (xy 34.544 -157.3784)
				(xy 31.3944 -157.3784) (xy 31.1912 -157.1752)
			)
		)
		(polygon
			(pts
				(xy 34.3408 -158.4198) (xy 34.1376 -158.4198) (xy 34.1376 -158.623) (xy 34.3408 -158.623)
			)
		)
		(polygon
			(pts
				(xy 34.036 -158.0388) (xy 33.8328 -158.0388) (xy 33.8328 -158.242) (xy 34.036 -158.242)
			)
		)
		(polygon
			(pts
				(xy 33.1724 -158.0388) (xy 32.9692 -158.0388) (xy 32.9692 -158.242) (xy 33.1724 -158.242)
			)
		)
	)
	(zone
		(layer "F.Cu")
		(hatch none 0.5)
		(connect_pads
			(clearance 0)
		)
		(min_thickness 0.25)
		(keepout
			(tracks not_allowed)
			(vias allowed)
			(pads allowed)
			(copperpour not_allowed)
			(footprints allowed)
		)
		(placement
			(enabled no)
			(sheetname "")
		)
		(fill
			(thermal_gap 0.5)
			(thermal_bridge_width 0.5)
			(island_removal_mode 0)
		)
		(polygon
			(pts
				(arc
					(start 227.24999 -153.999946)
					(mid 222.499936 -158.75)
					(end 217.749882 -153.999946)
				)
				(arc
					(start 217.749882 -153.999946)
					(mid 222.499936 -149.249892)
					(end 227.24999 -153.999946)
				)
			)
		)
	)
	(zone
		(net "GND")
		(layer "F.Cu")
		(hatch none 0.5)
		(connect_pads
			(clearance 0.5)
		)
		(min_thickness 0.25)
		(fill yes
			(thermal_gap 0.5)
			(thermal_bridge_width 0.5)
			(island_removal_mode 0)
		)
		(polygon
			(pts
				(xy 48.3108 -178.5112) (xy 47.879 -178.943) (xy 47.879 -181.7116) (xy 48.387 -182.2196) (xy 51.689 -182.2196)
				(xy 52.5272 -181.3814) (xy 57.912 -181.3814) (xy 58.1406 -181.1528) (xy 58.1406 -179.0446) (xy 57.6072 -178.5112)
			)
		)
		(polygon
			(pts
				(xy 57.658 -180.6956) (xy 57.4548 -180.6956) (xy 57.4548 -180.8988) (xy 57.658 -180.8988)
			)
		)
		(polygon
			(pts
				(xy 57.0484 -180.6956) (xy 56.8452 -180.6956) (xy 56.8452 -180.8988) (xy 57.0484 -180.8988)
			)
		)
	)
	(zone
		(layer "F.Cu")
		(hatch none 0.5)
		(connect_pads
			(clearance 0)
		)
		(min_thickness 0.25)
		(keepout
			(tracks not_allowed)
			(vias allowed)
			(pads allowed)
			(copperpour not_allowed)
			(footprints allowed)
		)
		(placement
			(enabled no)
			(sheetname "")
		)
		(fill
			(thermal_gap 0.5)
			(thermal_bridge_width 0.5)
			(island_removal_mode 0)
		)
		(polygon
			(pts
				(arc
					(start 78.49997 -44.800012)
					(mid 73.749916 -40.049958)
					(end 78.49997 -35.299904)
				)
				(xy 89.499948 -35.299904) (xy 89.499948 -44.800012)
			)
		)
	)
	(zone
		(net "P12V_STBY_VIN_PU1")
		(layer "F.Cu")
		(hatch none 0.5)
		(connect_pads
			(clearance 0.5)
		)
		(min_thickness 0.25)
		(fill yes
			(thermal_gap 0.5)
			(thermal_bridge_width 0.5)
			(island_removal_mode 0)
		)
		(polygon
			(pts
				(xy 224.672906 -50.384456) (xy 224.553272 -50.50409) (xy 220.86951 -50.50409) (xy 220.7006 -50.673)
				(xy 220.7006 -55.55361) (xy 221.229174 -56.082184) (xy 225.692462 -56.082184) (xy 225.905568 -55.869078)
				(xy 225.905568 -52.23256) (xy 226.305872 -51.832256) (xy 226.305872 -50.460656) (xy 226.229672 -50.384456)
			)
		)
	)
	(zone
		(layer "F.Cu")
		(hatch none 0.5)
		(connect_pads
			(clearance 0)
		)
		(min_thickness 0.25)
		(keepout
			(tracks not_allowed)
			(vias allowed)
			(pads allowed)
			(copperpour not_allowed)
			(footprints allowed)
		)
		(placement
			(enabled no)
			(sheetname "")
		)
		(fill
			(thermal_gap 0.5)
			(thermal_bridge_width 0.5)
			(island_removal_mode 0)
		)
		(polygon
			(pts
				(arc
					(start 85.364828 -91.30665)
					(mid 84.983955 -90.925396)
					(end 84.602828 -91.306396)
				)
				(arc
					(start 84.602828 -91.451938)
					(mid 84.668147 -91.424498)
					(end 84.731098 -91.391994)
				)
				(arc
					(start 84.731098 -91.391994)
					(mid 85.194518 -91.142994)
					(end 84.837016 -91.5289)
				)
				(arc
					(start 84.837016 -91.5289)
					(mid 84.723057 -91.588132)
					(end 84.602828 -91.633294)
				)
				(arc
					(start 84.602828 -91.868498)
					(mid 84.723051 -91.913674)
					(end 84.837016 -91.972892)
				)
				(arc
					(start 84.837016 -91.972892)
					(mid 85.194497 -92.358782)
					(end 84.731098 -92.109798)
				)
				(arc
					(start 84.731098 -92.109798)
					(mid 84.66814 -92.077307)
					(end 84.602828 -92.049854)
				)
				(arc
					(start 84.602828 -92.195396)
					(mid 84.983828 -92.576396)
					(end 85.364828 -92.195396)
				)
			)
		)
	)
	(zone
		(layer "F.Cu")
		(hatch none 0.5)
		(connect_pads
			(clearance 0)
		)
		(min_thickness 0.25)
		(keepout
			(tracks allowed)
			(vias allowed)
			(pads allowed)
			(copperpour allowed)
			(footprints not_allowed)
		)
		(placement
			(enabled no)
			(sheetname "")
		)
		(fill
			(thermal_gap 0.5)
			(thermal_bridge_width 0.5)
			(island_removal_mode 0)
		)
		(polygon
			(pts
				(xy 210.399884 -10.249916) (xy 198.399908 -10.249916)
				(arc
					(start 198.399908 -21.249894)
					(mid 204.399896 -27.249882)
					(end 210.399884 -21.249894)
				)
			)
		)
	)
	(zone
		(layer "F.Cu")
		(hatch none 0.5)
		(connect_pads
			(clearance 0)
		)
		(min_thickness 0.25)
		(keepout
			(tracks not_allowed)
			(vias allowed)
			(pads allowed)
			(copperpour not_allowed)
			(footprints allowed)
		)
		(placement
			(enabled no)
			(sheetname "")
		)
		(fill
			(thermal_gap 0.5)
			(thermal_bridge_width 0.5)
			(island_removal_mode 0)
		)
		(polygon
			(pts
				(xy 210.399884 -10.249916) (xy 198.399908 -10.249916)
				(arc
					(start 198.399908 -21.249894)
					(mid 204.399896 -27.249882)
					(end 210.399884 -21.249894)
				)
			)
		)
	)
	(zone
		(layer "F.Cu")
		(hatch none 0.5)
		(connect_pads
			(clearance 0)
		)
		(min_thickness 0.25)
		(keepout
			(tracks allowed)
			(vias allowed)
			(pads allowed)
			(copperpour allowed)
			(footprints allowed)
		)
		(placement
			(enabled no)
			(sheetname "")
		)
		(fill
			(thermal_gap 0.5)
			(thermal_bridge_width 0.5)
			(island_removal_mode 0)
		)
		(polygon
			(pts
				(xy 212.5726 -136.6266) (xy 215.4936 -136.6266) (xy 215.6968 -136.4234) (xy 215.6968 -132.7658)
				(xy 215.392 -132.461) (xy 212.8266 -132.461) (xy 212.6996 -132.461) (xy 211.9757 -133.1849) (xy 211.9757 -136.0297)
				(xy 212.1662 -136.2202)
			)
		)
	)
	(zone
		(layer "F.Cu")
		(hatch none 0.5)
		(connect_pads
			(clearance 0)
		)
		(min_thickness 0.25)
		(keepout
			(tracks allowed)
			(vias allowed)
			(pads allowed)
			(copperpour allowed)
			(footprints allowed)
		)
		(placement
			(enabled no)
			(sheetname "")
		)
		(fill
			(thermal_gap 0.5)
			(thermal_bridge_width 0.5)
			(island_removal_mode 0)
		)
		(polygon
			(pts
				(xy 161.046922 -16.053816) (xy 162.215322 -16.053816) (xy 162.367722 -15.901416) (xy 162.367722 -15.101316)
				(xy 162.189922 -14.923516) (xy 160.958022 -14.923516) (xy 160.894522 -14.987016) (xy 160.894522 -15.901416)
			)
		)
	)
	(zone
		(net "TPS74801_P1V2_STBY_FB")
		(layer "F.Cu")
		(hatch none 0.5)
		(connect_pads
			(clearance 0.5)
		)
		(min_thickness 0.25)
		(fill yes
			(thermal_gap 0.5)
			(thermal_bridge_width 0.5)
			(island_removal_mode 0)
		)
		(polygon
			(pts
				(xy 14.151356 -161.798) (xy 13.824204 -162.125152) (xy 13.824204 -166.920164) (xy 14.08684 -167.1828)
				(xy 15.494 -167.1828) (xy 15.5448 -167.132) (xy 15.5448 -165.7096) (xy 15.8623 -165.3921) (xy 15.8623 -161.8615)
				(xy 15.7988 -161.798)
			)
		)
		(polygon
			(pts
				(xy 15.404084 -164.7317) (xy 15.200884 -164.7317) (xy 15.200884 -164.9349) (xy 15.404084 -164.9349)
			)
		)
		(polygon
			(pts
				(xy 15.404084 -164.1729) (xy 15.200884 -164.1729) (xy 15.200884 -164.3761) (xy 15.404084 -164.3761)
			)
		)
		(polygon
			(pts
				(xy 15.362936 -163.7538) (xy 15.159736 -163.7538) (xy 15.159736 -163.957) (xy 15.362936 -163.957)
			)
		)
		(polygon
			(pts
				(xy 15.362936 -163.1442) (xy 15.159736 -163.1442) (xy 15.159736 -163.3474) (xy 15.362936 -163.3474)
			)
		)
		(polygon
			(pts
				(xy 15.431516 -162.7251) (xy 15.228316 -162.7251) (xy 15.228316 -162.9283) (xy 15.431516 -162.9283)
			)
		)
		(polygon
			(pts
				(xy 15.431516 -162.1663) (xy 15.228316 -162.1663) (xy 15.228316 -162.3695) (xy 15.431516 -162.3695)
			)
		)
	)
	(zone
		(layer "F.Cu")
		(hatch none 0.5)
		(connect_pads
			(clearance 0)
		)
		(min_thickness 0.25)
		(keepout
			(tracks allowed)
			(vias allowed)
			(pads allowed)
			(copperpour allowed)
			(footprints allowed)
		)
		(placement
			(enabled no)
			(sheetname "")
		)
		(fill
			(thermal_gap 0.5)
			(thermal_bridge_width 0.5)
			(island_removal_mode 0)
		)
		(polygon
			(pts
				(xy 30.1498 -181.1782) (xy 30.1498 -179.2478) (xy 32.131 -179.2478) (xy 32.131 -181.1782)
			)
		)
	)
	(zone
		(net "P12V_STBY")
		(layer "F.Cu")
		(hatch none 0.5)
		(connect_pads
			(clearance 0.5)
		)
		(min_thickness 0.25)
		(fill yes
			(thermal_gap 0.5)
			(thermal_bridge_width 0.5)
			(island_removal_mode 0)
		)
		(polygon
			(pts
				(xy 134.089394 -7.013956) (xy 133.315202 -7.788148) (xy 131.249166 -7.788148) (xy 131.026662 -8.010652)
				(xy 131.026662 -11.979402) (xy 131.21259 -12.16533) (xy 133.816598 -12.16533) (xy 134.953248 -11.02868)
				(xy 135.551672 -11.02868) (xy 135.733028 -10.847578) (xy 135.733028 -7.036054) (xy 135.71093 -7.013956)
			)
		)
	)
	(zone
		(layer "F.Cu")
		(hatch none 0.5)
		(connect_pads
			(clearance 0)
		)
		(min_thickness 0.25)
		(keepout
			(tracks allowed)
			(vias allowed)
			(pads allowed)
			(copperpour allowed)
			(footprints allowed)
		)
		(placement
			(enabled no)
			(sheetname "")
		)
		(fill
			(thermal_gap 0.5)
			(thermal_bridge_width 0.5)
			(island_removal_mode 0)
		)
		(polygon
			(pts
				(xy 218.207082 -46.703996) (xy 220.315282 -46.703996) (xy 220.518482 -46.500796) (xy 220.518482 -44.468796)
				(xy 220.213682 -44.163996) (xy 218.334082 -44.163996) (xy 218.003882 -44.494196) (xy 218.003882 -46.500796)
			)
		)
	)
	(zone
		(net "P3V3_M2_LL")
		(layer "F.Cu")
		(hatch none 0.5)
		(connect_pads
			(clearance 0.5)
		)
		(min_thickness 0.25)
		(fill yes
			(thermal_gap 0.5)
			(thermal_bridge_width 0.5)
			(island_removal_mode 0)
		)
		(polygon
			(pts
				(xy 220.368622 -88.377776) (xy 220.364304 -88.382348) (xy 218.10218 -88.382348) (xy 217.779854 -88.704674)
				(xy 217.779854 -91.882722) (xy 218.167458 -92.270326) (xy 219.456508 -92.270326) (xy 219.951046 -92.764864)
				(xy 219.951046 -95.282512) (xy 220.078046 -95.409512) (xy 222.94215 -95.409512) (xy 223.769174 -94.582488)
				(xy 224.114868 -94.582488) (xy 225.032316 -93.66504) (xy 226.818952 -93.66504) (xy 227.084382 -93.39961)
				(xy 227.084382 -88.893142) (xy 226.569016 -88.377776)
			)
		)
		(polygon
			(pts
				(xy 226.628706 -92.95384) (xy 226.425506 -92.95384) (xy 226.425506 -93.15704) (xy 226.628706 -93.15704)
			)
		)
		(polygon
			(pts
				(xy 226.019106 -92.95384) (xy 225.815906 -92.95384) (xy 225.815906 -93.15704) (xy 226.019106 -93.15704)
			)
		)
	)
	(zone
		(layer "F.Cu")
		(hatch none 0.5)
		(connect_pads
			(clearance 0)
		)
		(min_thickness 0.25)
		(keepout
			(tracks allowed)
			(vias allowed)
			(pads allowed)
			(copperpour allowed)
			(footprints not_allowed)
		)
		(placement
			(enabled no)
			(sheetname "")
		)
		(fill
			(thermal_gap 0.5)
			(thermal_bridge_width 0.5)
			(island_removal_mode 0)
		)
		(polygon
			(pts
				(xy 11.8999 -109.799882) (xy 11.8999 -103.799894)
				(arc
					(start 18.317464 -103.799894)
					(mid 20.016891 -101.275181)
					(end 22.899878 -100.300028)
				)
				(arc
					(start 22.899878 -100.300028)
					(mid 27.649932 -105.050082)
					(end 22.899878 -109.799882)
				)
			)
		)
	)
	(zone
		(layer "F.Cu")
		(hatch none 0.5)
		(connect_pads
			(clearance 0)
		)
		(min_thickness 0.25)
		(keepout
			(tracks allowed)
			(vias allowed)
			(pads allowed)
			(copperpour allowed)
			(footprints allowed)
		)
		(placement
			(enabled no)
			(sheetname "")
		)
		(fill
			(thermal_gap 0.5)
			(thermal_bridge_width 0.5)
			(island_removal_mode 0)
		)
		(polygon
			(pts
				(xy 219.555314 -92.887292) (xy 218.285314 -92.887292) (xy 218.056714 -92.658692) (xy 217.574114 -92.658692)
				(xy 217.345514 -92.887292) (xy 217.345514 -92.963492) (xy 216.888314 -93.420692) (xy 216.888314 -95.325692)
				(xy 217.218514 -95.655892) (xy 219.275914 -95.655892) (xy 219.631514 -95.300292) (xy 219.631514 -92.963492)
			)
		)
	)
	(zone
		(layer "F.Cu")
		(hatch none 0.5)
		(connect_pads
			(clearance 0)
		)
		(min_thickness 0.25)
		(keepout
			(tracks allowed)
			(vias allowed)
			(pads allowed)
			(copperpour allowed)
			(footprints allowed)
		)
		(placement
			(enabled no)
			(sheetname "")
		)
		(fill
			(thermal_gap 0.5)
			(thermal_bridge_width 0.5)
			(island_removal_mode 0)
		)
		(polygon
			(pts
				(xy 63.3222 -141.0208) (xy 65.1764 -141.0208) (xy 65.1764 -141.8082) (xy 63.3222 -141.8082)
			)
		)
	)
	(zone
		(layer "F.Cu")
		(hatch none 0.5)
		(connect_pads
			(clearance 0)
		)
		(min_thickness 0.25)
		(keepout
			(tracks not_allowed)
			(vias allowed)
			(pads allowed)
			(copperpour not_allowed)
			(footprints allowed)
		)
		(placement
			(enabled no)
			(sheetname "")
		)
		(fill
			(thermal_gap 0.5)
			(thermal_bridge_width 0.5)
			(island_removal_mode 0)
		)
		(polygon
			(pts
				(arc
					(start 198.399908 -51.250088)
					(mid 204.399896 -57.250076)
					(end 210.399884 -51.250088)
				)
				(xy 210.399884 -40.25011) (xy 198.399908 -40.25011)
			)
		)
	)
	(zone
		(layer "F.Cu")
		(hatch none 0.5)
		(connect_pads
			(clearance 0)
		)
		(min_thickness 0.25)
		(keepout
			(tracks allowed)
			(vias allowed)
			(pads allowed)
			(copperpour allowed)
			(footprints not_allowed)
		)
		(placement
			(enabled no)
			(sheetname "")
		)
		(fill
			(thermal_gap 0.5)
			(thermal_bridge_width 0.5)
			(island_removal_mode 0)
		)
		(polygon
			(pts
				(arc
					(start 145.2499 -120.000014)
					(mid 149.999954 -115.24996)
					(end 154.750008 -120.000014)
				)
				(arc
					(start 154.750008 -120.000014)
					(mid 149.999954 -124.750068)
					(end 145.2499 -120.000014)
				)
			)
		)
	)
	(zone
		(layer "F.Cu")
		(hatch none 0.5)
		(connect_pads
			(clearance 0)
		)
		(min_thickness 0.25)
		(keepout
			(tracks allowed)
			(vias allowed)
			(pads allowed)
			(copperpour allowed)
			(footprints not_allowed)
		)
		(placement
			(enabled no)
			(sheetname "")
		)
		(fill
			(thermal_gap 0.5)
			(thermal_bridge_width 0.5)
			(island_removal_mode 0)
		)
		(polygon
			(pts
				(arc
					(start 227.24999 -120.000014)
					(mid 222.499936 -124.750068)
					(end 217.749882 -120.000014)
				)
				(arc
					(start 217.749882 -120.000014)
					(mid 222.499936 -115.24996)
					(end 227.24999 -120.000014)
				)
			)
		)
	)
	(zone
		(layer "F.Cu")
		(hatch none 0.5)
		(connect_pads
			(clearance 0)
		)
		(min_thickness 0.25)
		(keepout
			(tracks allowed)
			(vias allowed)
			(pads allowed)
			(copperpour allowed)
			(footprints not_allowed)
		)
		(placement
			(enabled no)
			(sheetname "")
		)
		(fill
			(thermal_gap 0.5)
			(thermal_bridge_width 0.5)
			(island_removal_mode 0)
		)
		(polygon
			(pts
				(arc
					(start 22.750018 -120.000014)
					(mid 17.999964 -124.750068)
					(end 13.24991 -120.000014)
				)
				(arc
					(start 13.24991 -120.000014)
					(mid 17.999964 -115.24996)
					(end 22.750018 -120.000014)
				)
			)
		)
	)
	(zone
		(layer "F.Cu")
		(hatch none 0.5)
		(connect_pads
			(clearance 0)
		)
		(min_thickness 0.25)
		(keepout
			(tracks allowed)
			(vias allowed)
			(pads allowed)
			(copperpour allowed)
			(footprints allowed)
		)
		(placement
			(enabled no)
			(sheetname "")
		)
		(fill
			(thermal_gap 0.5)
			(thermal_bridge_width 0.5)
			(island_removal_mode 0)
		)
		(polygon
			(pts
				(xy 91.2368 -160.02) (xy 91.2368 -158.369) (xy 94.615 -158.369) (xy 94.615 -159.1056) (xy 95.123 -159.6136)
				(xy 95.5294 -160.02) (xy 95.5294 -160.2994) (xy 95.1992 -160.6296) (xy 94.615 -160.6296) (xy 93.5228 -160.6296)
				(xy 92.2528 -161.8996) (xy 92.0496 -161.8996) (xy 91.5924 -161.4424) (xy 91.5924 -160.3756)
			)
		)
	)
	(zone
		(layer "F.Cu")
		(hatch none 0.5)
		(connect_pads
			(clearance 0)
		)
		(min_thickness 0.25)
		(keepout
			(tracks not_allowed)
			(vias allowed)
			(pads allowed)
			(copperpour not_allowed)
			(footprints allowed)
		)
		(placement
			(enabled no)
			(sheetname "")
		)
		(fill
			(thermal_gap 0.5)
			(thermal_bridge_width 0.5)
			(island_removal_mode 0)
		)
		(polygon
			(pts
				(arc
					(start 83.740498 -88.091518)
					(mid 83.359625 -87.710264)
					(end 82.978498 -88.091264)
				)
				(arc
					(start 82.978498 -88.236806)
					(mid 83.043817 -88.209366)
					(end 83.106768 -88.176862)
				)
				(arc
					(start 83.106768 -88.176862)
					(mid 83.570188 -87.927862)
					(end 83.212686 -88.313768)
				)
				(arc
					(start 83.212686 -88.313768)
					(mid 83.098727 -88.373)
					(end 82.978498 -88.418162)
				)
				(arc
					(start 82.978498 -88.653366)
					(mid 83.098721 -88.698542)
					(end 83.212686 -88.75776)
				)
				(arc
					(start 83.212686 -88.75776)
					(mid 83.570167 -89.14365)
					(end 83.106768 -88.894666)
				)
				(arc
					(start 83.106768 -88.894666)
					(mid 83.04381 -88.862175)
					(end 82.978498 -88.834722)
				)
				(arc
					(start 82.978498 -88.980264)
					(mid 83.359498 -89.361264)
					(end 83.740498 -88.980264)
				)
			)
		)
	)
	(zone
		(layer "F.Cu")
		(hatch none 0.5)
		(connect_pads
			(clearance 0)
		)
		(min_thickness 0.25)
		(keepout
			(tracks not_allowed)
			(vias allowed)
			(pads allowed)
			(copperpour not_allowed)
			(footprints allowed)
		)
		(placement
			(enabled no)
			(sheetname "")
		)
		(fill
			(thermal_gap 0.5)
			(thermal_bridge_width 0.5)
			(island_removal_mode 0)
		)
		(polygon
			(pts
				(arc
					(start 7.750048 -187.999878)
					(mid 12.500102 -183.249824)
					(end 17.249902 -187.999878)
				)
				(arc
					(start 17.249902 -187.999878)
					(mid 12.500102 -192.749678)
					(end 7.750048 -187.999878)
				)
			)
		)
	)
	(zone
		(layer "F.Cu")
		(hatch none 0.5)
		(connect_pads
			(clearance 0)
		)
		(min_thickness 0.25)
		(keepout
			(tracks allowed)
			(vias allowed)
			(pads allowed)
			(copperpour allowed)
			(footprints allowed)
		)
		(placement
			(enabled no)
			(sheetname "")
		)
		(fill
			(thermal_gap 0.5)
			(thermal_bridge_width 0.5)
			(island_removal_mode 0)
		)
		(polygon
			(pts
				(xy 95.4024 -154.94) (xy 97.2566 -154.94) (xy 97.2566 -156.2862) (xy 95.4024 -156.2862)
			)
		)
	)
	(zone
		(net "P12V_STBY")
		(layer "F.Cu")
		(hatch none 0.5)
		(connect_pads
			(clearance 0.5)
		)
		(min_thickness 0.25)
		(fill yes
			(thermal_gap 0.5)
			(thermal_bridge_width 0.5)
			(island_removal_mode 0)
		)
		(polygon
			(pts
				(xy 74.5236 -47.879) (xy 74.3966 -48.006) (xy 74.3966 -50.7238) (xy 74.4728 -50.8) (xy 76.835 -50.8)
				(xy 76.962 -50.673) (xy 76.962 -50.1904) (xy 77.089 -50.0634) (xy 77.9272 -50.0634) (xy 78.105 -49.8856)
				(xy 78.105 -47.9806) (xy 78.0034 -47.879)
			)
		)
	)
	(zone
		(net "TPS74801_P2V5_STBY_FB")
		(layer "F.Cu")
		(hatch none 0.5)
		(connect_pads
			(clearance 0.5)
		)
		(min_thickness 0.25)
		(fill yes
			(thermal_gap 0.5)
			(thermal_bridge_width 0.5)
			(island_removal_mode 0)
		)
		(polygon
			(pts
				(xy 72.648572 -173.02988) (xy 72.410828 -173.267624) (xy 72.410828 -174.585884) (xy 72.406764 -174.585884)
				(xy 72.29729 -174.695358) (xy 72.29729 -178.101498) (xy 72.610472 -178.41468) (xy 73.89368 -178.41468)
				(xy 73.94448 -178.36388) (xy 73.94448 -176.736756) (xy 74.28992 -176.391316) (xy 74.28992 -173.12132)
				(xy 74.19848 -173.02988)
			)
		)
		(polygon
			(pts
				(xy 73.833228 -175.932338) (xy 73.630028 -175.932338) (xy 73.630028 -176.135538) (xy 73.833228 -176.135538)
			)
		)
		(polygon
			(pts
				(xy 73.833228 -175.373538) (xy 73.630028 -175.373538) (xy 73.630028 -175.576738) (xy 73.833228 -175.576738)
			)
		)
		(polygon
			(pts
				(xy 73.762616 -174.98568) (xy 73.559416 -174.98568) (xy 73.559416 -175.18888) (xy 73.762616 -175.18888)
			)
		)
		(polygon
			(pts
				(xy 73.762616 -174.37608) (xy 73.559416 -174.37608) (xy 73.559416 -174.57928) (xy 73.762616 -174.57928)
			)
		)
		(polygon
			(pts
				(xy 73.816972 -173.952662) (xy 73.613772 -173.952662) (xy 73.613772 -174.155862) (xy 73.816972 -174.155862)
			)
		)
		(polygon
			(pts
				(xy 73.816972 -173.393862) (xy 73.613772 -173.393862) (xy 73.613772 -173.597062) (xy 73.816972 -173.597062)
			)
		)
	)
	(zone
		(net "GND")
		(layer "F.Cu")
		(hatch none 0.5)
		(connect_pads
			(clearance 0.5)
		)
		(min_thickness 0.25)
		(fill yes
			(thermal_gap 0.5)
			(thermal_bridge_width 0.5)
			(island_removal_mode 0)
		)
		(polygon
			(pts
				(xy 222.279972 -102.443788) (xy 221.75724 -102.96652) (xy 221.75724 -104.013) (xy 222.13824 -104.394)
				(xy 223.0628 -104.394) (xy 223.4184 -104.7496) (xy 229.785672 -104.7496) (xy 229.875842 -104.65943)
				(xy 229.875842 -102.697026) (xy 229.622604 -102.443788)
			)
		)
		(polygon
			(pts
				(xy 223.529906 -102.952042) (xy 223.326706 -102.952042) (xy 223.326706 -103.155242) (xy 223.529906 -103.155242)
			)
		)
		(polygon
			(pts
				(xy 222.920306 -102.952042) (xy 222.717106 -102.952042) (xy 222.717106 -103.155242) (xy 222.920306 -103.155242)
			)
		)
	)
	(zone
		(layer "F.Cu")
		(hatch none 0.5)
		(connect_pads
			(clearance 0)
		)
		(min_thickness 0.25)
		(keepout
			(tracks not_allowed)
			(vias allowed)
			(pads allowed)
			(copperpour not_allowed)
			(footprints allowed)
		)
		(placement
			(enabled no)
			(sheetname "")
		)
		(fill
			(thermal_gap 0.5)
			(thermal_bridge_width 0.5)
			(island_removal_mode 0)
		)
		(polygon
			(pts
				(arc
					(start 85.244178 -72.09917)
					(mid 84.863305 -71.717916)
					(end 84.482178 -72.098916)
				)
				(arc
					(start 84.482178 -72.244458)
					(mid 84.547497 -72.217018)
					(end 84.610448 -72.184514)
				)
				(arc
					(start 84.610448 -72.184514)
					(mid 85.073868 -71.935514)
					(end 84.716366 -72.32142)
				)
				(arc
					(start 84.716366 -72.32142)
					(mid 84.602407 -72.380652)
					(end 84.482178 -72.425814)
				)
				(arc
					(start 84.482178 -72.661018)
					(mid 84.602401 -72.706194)
					(end 84.716366 -72.765412)
				)
				(arc
					(start 84.716366 -72.765412)
					(mid 85.073847 -73.151302)
					(end 84.610448 -72.902318)
				)
				(arc
					(start 84.610448 -72.902318)
					(mid 84.54749 -72.869827)
					(end 84.482178 -72.842374)
				)
				(arc
					(start 84.482178 -72.987916)
					(mid 84.863178 -73.368916)
					(end 85.244178 -72.987916)
				)
			)
		)
	)
	(zone
		(layer "F.Cu")
		(hatch none 0.5)
		(connect_pads
			(clearance 0)
		)
		(min_thickness 0.25)
		(keepout
			(tracks allowed)
			(vias allowed)
			(pads allowed)
			(copperpour allowed)
			(footprints not_allowed)
		)
		(placement
			(enabled no)
			(sheetname "")
		)
		(fill
			(thermal_gap 0.5)
			(thermal_bridge_width 0.5)
			(island_removal_mode 0)
		)
		(polygon
			(pts
				(arc
					(start 227.24999 -187.999878)
					(mid 222.499936 -192.749932)
					(end 217.749882 -187.999878)
				)
				(arc
					(start 217.749882 -187.999878)
					(mid 222.499936 -183.249824)
					(end 227.24999 -187.999878)
				)
			)
		)
	)
	(zone
		(net "P5V_LL")
		(layer "F.Cu")
		(hatch none 0.5)
		(connect_pads
			(clearance 0.5)
		)
		(min_thickness 0.25)
		(fill yes
			(thermal_gap 0.5)
			(thermal_bridge_width 0.5)
			(island_removal_mode 0)
		)
		(polygon
			(pts
				(xy 221.65818 -38.847014) (xy 221.643956 -38.861492) (xy 220.38945 -38.861492) (xy 219.624656 -39.626286)
				(xy 219.624656 -42.290238) (xy 220.628718 -43.2943) (xy 220.628718 -46.662848) (xy 220.755718 -46.789848)
				(xy 223.52127 -46.789848) (xy 223.52127 -46.590458) (xy 223.71304 -46.398688) (xy 225.973386 -46.398688)
				(xy 225.975418 -46.40072) (xy 226.055936 -46.40072) (xy 226.526598 -45.930058) (xy 227.353622 -45.930058)
				(xy 227.836222 -45.447458) (xy 227.836222 -39.618158) (xy 227.065078 -38.847014)
			)
		)
		(polygon
			(pts
				(xy 227.475796 -45.09389) (xy 227.272596 -45.09389) (xy 227.272596 -45.29709) (xy 227.475796 -45.29709)
			)
		)
		(polygon
			(pts
				(xy 226.866196 -45.09389) (xy 226.662996 -45.09389) (xy 226.662996 -45.29709) (xy 226.866196 -45.29709)
			)
		)
	)
	(zone
		(layer "F.Cu")
		(hatch none 0.5)
		(connect_pads
			(clearance 0)
		)
		(min_thickness 0.25)
		(keepout
			(tracks allowed)
			(vias allowed)
			(pads allowed)
			(copperpour allowed)
			(footprints allowed)
		)
		(placement
			(enabled no)
			(sheetname "")
		)
		(fill
			(thermal_gap 0.5)
			(thermal_bridge_width 0.5)
			(island_removal_mode 0)
		)
		(polygon
			(pts
				(xy 151.294084 -12.446762) (xy 152.741884 -12.446762) (xy 152.894284 -12.294362) (xy 152.894284 -11.176762)
				(xy 152.741884 -11.024362) (xy 151.344884 -11.024362) (xy 151.167084 -11.202162) (xy 151.167084 -12.319762)
			)
		)
	)
	(zone
		(layer "F.Cu")
		(hatch none 0.5)
		(connect_pads
			(clearance 0)
		)
		(min_thickness 0.25)
		(keepout
			(tracks allowed)
			(vias allowed)
			(pads allowed)
			(copperpour allowed)
			(footprints allowed)
		)
		(placement
			(enabled no)
			(sheetname "")
		)
		(fill
			(thermal_gap 0.5)
			(thermal_bridge_width 0.5)
			(island_removal_mode 0)
		)
		(polygon
			(pts
				(xy 179.7558 -128.1684) (xy 180.9496 -128.1684) (xy 181.102 -128.016) (xy 181.102 -125.2728) (xy 180.7972 -124.968)
				(xy 179.705 -126.0602) (xy 179.705 -128.1176)
			)
		)
	)
	(zone
		(layer "F.Cu")
		(hatch none 0.5)
		(connect_pads
			(clearance 0)
		)
		(min_thickness 0.25)
		(keepout
			(tracks not_allowed)
			(vias allowed)
			(pads allowed)
			(copperpour not_allowed)
			(footprints allowed)
		)
		(placement
			(enabled no)
			(sheetname "")
		)
		(fill
			(thermal_gap 0.5)
			(thermal_bridge_width 0.5)
			(island_removal_mode 0)
		)
		(polygon
			(pts
				(arc
					(start 78.503018 -83.310222)
					(mid 78.122145 -82.928968)
					(end 77.741018 -83.309968)
				)
				(arc
					(start 77.741018 -83.45551)
					(mid 77.806337 -83.42807)
					(end 77.869288 -83.395566)
				)
				(arc
					(start 77.869288 -83.395566)
					(mid 78.332708 -83.146566)
					(end 77.975206 -83.532472)
				)
				(arc
					(start 77.975206 -83.532472)
					(mid 77.861247 -83.591704)
					(end 77.741018 -83.636866)
				)
				(arc
					(start 77.741018 -83.87207)
					(mid 77.861241 -83.917246)
					(end 77.975206 -83.976464)
				)
				(arc
					(start 77.975206 -83.976464)
					(mid 78.332687 -84.362354)
					(end 77.869288 -84.11337)
				)
				(arc
					(start 77.869288 -84.11337)
					(mid 77.80633 -84.080879)
					(end 77.741018 -84.053426)
				)
				(arc
					(start 77.741018 -84.198968)
					(mid 78.122018 -84.579968)
					(end 78.503018 -84.198968)
				)
			)
		)
	)
	(zone
		(net "AGND_P3V3_M2")
		(layer "F.Cu")
		(hatch none 0.5)
		(connect_pads
			(clearance 0.5)
		)
		(min_thickness 0.25)
		(fill yes
			(thermal_gap 0.5)
			(thermal_bridge_width 0.5)
			(island_removal_mode 0)
		)
		(polygon
			(pts
				(xy 212.610954 -96.800924) (xy 212.433154 -96.978724) (xy 212.433154 -103.168958) (xy 212.585554 -103.321358)
				(xy 214.62492 -103.321358) (xy 215.023954 -102.922324) (xy 215.023954 -100.179124) (xy 214.693754 -99.848924)
				(xy 214.693754 -96.927924) (xy 214.566754 -96.800924)
			)
		)
		(polygon
			(pts
				(xy 214.56904 -102.793292) (xy 214.36584 -102.793292) (xy 214.36584 -102.996492) (xy 214.56904 -102.996492)
			)
		)
		(polygon
			(pts
				(xy 214.56904 -102.234492) (xy 214.36584 -102.234492) (xy 214.36584 -102.437692) (xy 214.56904 -102.437692)
			)
		)
		(polygon
			(pts
				(xy 214.56904 -101.777292) (xy 214.36584 -101.777292) (xy 214.36584 -101.980492) (xy 214.56904 -101.980492)
			)
		)
		(polygon
			(pts
				(xy 214.56904 -101.218492) (xy 214.36584 -101.218492) (xy 214.36584 -101.421692) (xy 214.56904 -101.421692)
			)
		)
		(polygon
			(pts
				(xy 214.56904 -100.761292) (xy 214.36584 -100.761292) (xy 214.36584 -100.964492) (xy 214.56904 -100.964492)
			)
		)
		(polygon
			(pts
				(xy 214.56904 -100.202492) (xy 214.36584 -100.202492) (xy 214.36584 -100.405692) (xy 214.56904 -100.405692)
			)
		)
		(polygon
			(pts
				(xy 213.392258 -97.26041) (xy 213.189058 -97.26041) (xy 213.189058 -97.46361) (xy 213.392258 -97.46361)
			)
		)
		(polygon
			(pts
				(xy 212.833458 -97.26041) (xy 212.630258 -97.26041) (xy 212.630258 -97.46361) (xy 212.833458 -97.46361)
			)
		)
	)
	(zone
		(net "GND")
		(layer "F.Cu")
		(hatch none 0.5)
		(connect_pads
			(clearance 0.5)
		)
		(min_thickness 0.25)
		(fill yes
			(thermal_gap 0.5)
			(thermal_bridge_width 0.5)
			(island_removal_mode 0)
		)
		(polygon
			(pts
				(xy 217.001344 -95.775526) (xy 216.848182 -95.928688) (xy 216.848182 -98.848926) (xy 217.076782 -99.077526)
				(xy 222.827342 -99.077526) (xy 222.928942 -98.975926) (xy 222.928942 -98.703892) (xy 222.954342 -98.678492)
				(xy 223.208342 -98.678492) (xy 224.044764 -97.84207) (xy 225.020378 -97.84207) (xy 225.263964 -97.598484)
				(xy 225.263964 -96.013778) (xy 225.033078 -95.782892) (xy 224.300542 -95.782892) (xy 224.294446 -95.788988)
				(xy 223.303846 -95.788988) (xy 223.290638 -95.775526)
			)
		)
	)
	(zone
		(layer "F.Cu")
		(hatch none 0.5)
		(connect_pads
			(clearance 0)
		)
		(min_thickness 0.25)
		(keepout
			(tracks allowed)
			(vias allowed)
			(pads allowed)
			(copperpour allowed)
			(footprints allowed)
		)
		(placement
			(enabled no)
			(sheetname "")
		)
		(fill
			(thermal_gap 0.5)
			(thermal_bridge_width 0.5)
			(island_removal_mode 0)
		)
		(polygon
			(pts
				(xy 90.481912 -148.194522) (xy 90.481912 -150.048722) (xy 89.135712 -150.048722) (xy 89.135712 -148.194522)
			)
		)
	)
	(zone
		(layer "F.Cu")
		(hatch none 0.5)
		(connect_pads
			(clearance 0)
		)
		(min_thickness 0.25)
		(keepout
			(tracks allowed)
			(vias allowed)
			(pads allowed)
			(copperpour allowed)
			(footprints not_allowed)
		)
		(placement
			(enabled no)
			(sheetname "")
		)
		(fill
			(thermal_gap 0.5)
			(thermal_bridge_width 0.5)
			(island_removal_mode 0)
		)
		(polygon
			(pts
				(arc
					(start 97.249996 -187.999878)
					(mid 92.499942 -192.749932)
					(end 87.749888 -187.999878)
				)
				(arc
					(start 87.749888 -187.999878)
					(mid 92.499942 -183.249824)
					(end 97.249996 -187.999878)
				)
			)
		)
	)
	(zone
		(layer "F.Cu")
		(hatch none 0.5)
		(connect_pads
			(clearance 0)
		)
		(min_thickness 0.25)
		(keepout
			(tracks not_allowed)
			(vias allowed)
			(pads allowed)
			(copperpour not_allowed)
			(footprints allowed)
		)
		(placement
			(enabled no)
			(sheetname "")
		)
		(fill
			(thermal_gap 0.5)
			(thermal_bridge_width 0.5)
			(island_removal_mode 0)
		)
		(polygon
			(pts
				(arc
					(start 85.364828 -84.892388)
					(mid 84.983955 -84.511134)
					(end 84.602828 -84.892134)
				)
				(arc
					(start 84.602828 -85.037676)
					(mid 84.668147 -85.010236)
					(end 84.731098 -84.977732)
				)
				(arc
					(start 84.731098 -84.977732)
					(mid 85.194518 -84.728732)
					(end 84.837016 -85.114638)
				)
				(arc
					(start 84.837016 -85.114638)
					(mid 84.723057 -85.17387)
					(end 84.602828 -85.219032)
				)
				(arc
					(start 84.602828 -85.454236)
					(mid 84.723051 -85.499412)
					(end 84.837016 -85.55863)
				)
				(arc
					(start 84.837016 -85.55863)
					(mid 85.194497 -85.94452)
					(end 84.731098 -85.695536)
				)
				(arc
					(start 84.731098 -85.695536)
					(mid 84.66814 -85.663045)
					(end 84.602828 -85.635592)
				)
				(arc
					(start 84.602828 -85.781134)
					(mid 84.983828 -86.162134)
					(end 85.364828 -85.781134)
				)
			)
		)
	)
	(zone
		(layer "F.Cu")
		(hatch none 0.5)
		(connect_pads
			(clearance 0)
		)
		(min_thickness 0.25)
		(keepout
			(tracks not_allowed)
			(vias allowed)
			(pads allowed)
			(copperpour not_allowed)
			(footprints allowed)
		)
		(placement
			(enabled no)
			(sheetname "")
		)
		(fill
			(thermal_gap 0.5)
			(thermal_bridge_width 0.5)
			(island_removal_mode 0)
		)
		(polygon
			(pts
				(arc
					(start 78.503018 -89.711022)
					(mid 78.122145 -89.329768)
					(end 77.741018 -89.710768)
				)
				(arc
					(start 77.741018 -89.85631)
					(mid 77.806337 -89.82887)
					(end 77.869288 -89.796366)
				)
				(arc
					(start 77.869288 -89.796366)
					(mid 78.332708 -89.547366)
					(end 77.975206 -89.933272)
				)
				(arc
					(start 77.975206 -89.933272)
					(mid 77.861247 -89.992504)
					(end 77.741018 -90.037666)
				)
				(arc
					(start 77.741018 -90.27287)
					(mid 77.861241 -90.318046)
					(end 77.975206 -90.377264)
				)
				(arc
					(start 77.975206 -90.377264)
					(mid 78.332687 -90.763154)
					(end 77.869288 -90.51417)
				)
				(arc
					(start 77.869288 -90.51417)
					(mid 77.80633 -90.481679)
					(end 77.741018 -90.454226)
				)
				(arc
					(start 77.741018 -90.599768)
					(mid 78.122018 -90.980768)
					(end 78.503018 -90.599768)
				)
			)
		)
	)
	(zone
		(net "GND")
		(layer "F.Cu")
		(hatch none 0.5)
		(connect_pads
			(clearance 0.5)
		)
		(min_thickness 0.25)
		(fill yes
			(thermal_gap 0.5)
			(thermal_bridge_width 0.5)
			(island_removal_mode 0)
		)
		(polygon
			(pts
				(xy 212.6742 -132.715) (xy 212.4964 -132.8928) (xy 212.4964 -135.8138) (xy 212.3694 -135.9408) (xy 212.3694 -136.4615)
				(xy 212.4964 -136.5885) (xy 215.0364 -136.5885) (xy 215.3412 -136.2837) (xy 215.3412 -132.715)
			)
		)
	)
	(zone
		(layer "F.Cu")
		(hatch none 0.5)
		(connect_pads
			(clearance 0)
		)
		(min_thickness 0.25)
		(keepout
			(tracks allowed)
			(vias allowed)
			(pads allowed)
			(copperpour allowed)
			(footprints allowed)
		)
		(placement
			(enabled no)
			(sheetname "")
		)
		(fill
			(thermal_gap 0.5)
			(thermal_bridge_width 0.5)
			(island_removal_mode 0)
		)
		(polygon
			(pts
				(xy 60.7822 -138.9888) (xy 62.6364 -138.9888) (xy 62.6364 -139.7762) (xy 60.7822 -139.7762)
			)
		)
	)
	(zone
		(net "P3V3_STBY")
		(layer "F.Cu")
		(hatch none 0.5)
		(connect_pads
			(clearance 0.5)
		)
		(min_thickness 0.25)
		(fill yes
			(thermal_gap 0.5)
			(thermal_bridge_width 0.5)
			(island_removal_mode 0)
		)
		(polygon
			(pts
				(xy 44.9834 -161.3916) (xy 44.8056 -161.5694) (xy 43.0784 -161.5694) (xy 43.0022 -161.6456) (xy 43.0022 -162.70224)
				(xy 43.27398 -162.97402) (xy 50.42408 -162.97402) (xy 50.6476 -162.7505) (xy 50.6476 -161.6456)
				(xy 50.3936 -161.3916)
			)
		)
		(polygon
			(pts
				(xy 44.7548 -162.0266) (xy 44.5516 -162.0266) (xy 44.5516 -162.2298) (xy 44.7548 -162.2298)
			)
		)
		(polygon
			(pts
				(xy 44.196 -162.0266) (xy 43.9928 -162.0266) (xy 43.9928 -162.2298) (xy 44.196 -162.2298)
			)
		)
		(polygon
			(pts
				(xy 43.7134 -162.0266) (xy 43.5102 -162.0266) (xy 43.5102 -162.2298) (xy 43.7134 -162.2298)
			)
		)
		(polygon
			(pts
				(xy 48.914304 -161.873692) (xy 48.711104 -161.873692) (xy 48.711104 -162.076892) (xy 48.914304 -162.076892)
			)
		)
		(polygon
			(pts
				(xy 48.355504 -161.873692) (xy 48.152304 -161.873692) (xy 48.152304 -162.076892) (xy 48.355504 -162.076892)
			)
		)
		(polygon
			(pts
				(xy 47.872904 -161.840672) (xy 47.669704 -161.840672) (xy 47.669704 -162.043872) (xy 47.872904 -162.043872)
			)
		)
		(polygon
			(pts
				(xy 47.314104 -161.840672) (xy 47.110904 -161.840672) (xy 47.110904 -162.043872) (xy 47.314104 -162.043872)
			)
		)
		(polygon
			(pts
				(xy 46.831504 -161.840672) (xy 46.628304 -161.840672) (xy 46.628304 -162.043872) (xy 46.831504 -162.043872)
			)
		)
		(polygon
			(pts
				(xy 46.272704 -161.840672) (xy 46.069504 -161.840672) (xy 46.069504 -162.043872) (xy 46.272704 -162.043872)
			)
		)
		(polygon
			(pts
				(xy 45.790104 -161.840672) (xy 45.586904 -161.840672) (xy 45.586904 -162.043872) (xy 45.790104 -162.043872)
			)
		)
		(polygon
			(pts
				(xy 45.231304 -161.840672) (xy 45.028104 -161.840672) (xy 45.028104 -162.043872) (xy 45.231304 -162.043872)
			)
		)
	)
	(zone
		(net "P5V_USB")
		(layer "F.Cu")
		(hatch none 0.5)
		(connect_pads
			(clearance 0.5)
		)
		(min_thickness 0.25)
		(fill yes
			(thermal_gap 0.5)
			(thermal_bridge_width 0.5)
			(island_removal_mode 0)
		)
		(polygon
			(pts
				(xy 83.902804 -29.473652) (xy 83.526122 -29.850334) (xy 83.526122 -31.314644) (xy 83.950048 -31.73857)
				(xy 87.8586 -31.73857) (xy 89.36863 -33.2486) (xy 90.8558 -33.2486) (xy 91.0844 -33.4772) (xy 91.0844 -35.5346)
				(xy 91.4654 -35.9156) (xy 94.5388 -35.9156) (xy 94.7166 -35.7378) (xy 94.7166 -32.512) (xy 94.361 -32.1564)
				(xy 91.0844 -32.1564) (xy 90.941652 -32.013652) (xy 90.941652 -30.209998) (xy 90.77452 -30.042866)
				(xy 88.680798 -30.042866) (xy 88.111584 -29.473652)
			)
		)
		(polygon
			(pts
				(xy 88.172036 -30.660848) (xy 87.968836 -30.660848) (xy 87.968836 -30.864048) (xy 88.172036 -30.864048)
			)
		)
		(polygon
			(pts
				(xy 87.308436 -30.660848) (xy 87.105236 -30.660848) (xy 87.105236 -30.864048) (xy 87.308436 -30.864048)
			)
		)
		(polygon
			(pts
				(xy 85.5091 -30.6451) (xy 85.3059 -30.6451) (xy 85.3059 -30.8483) (xy 85.5091 -30.8483)
			)
		)
		(polygon
			(pts
				(xy 84.1121 -30.6451) (xy 83.9089 -30.6451) (xy 83.9089 -30.8483) (xy 84.1121 -30.8483)
			)
		)
		(polygon
			(pts
				(xy 88.172036 -30.279848) (xy 87.968836 -30.279848) (xy 87.968836 -30.483048) (xy 88.172036 -30.483048)
			)
		)
		(polygon
			(pts
				(xy 87.308436 -30.279848) (xy 87.105236 -30.279848) (xy 87.105236 -30.483048) (xy 87.308436 -30.483048)
			)
		)
		(polygon
			(pts
				(xy 86.902036 -30.279848) (xy 86.698836 -30.279848) (xy 86.698836 -30.483048) (xy 86.902036 -30.483048)
			)
		)
		(polygon
			(pts
				(xy 86.038436 -30.279848) (xy 85.835236 -30.279848) (xy 85.835236 -30.483048) (xy 86.038436 -30.483048)
			)
		)
	)
	(zone
		(layer "F.Cu")
		(hatch none 0.5)
		(connect_pads
			(clearance 0)
		)
		(min_thickness 0.25)
		(keepout
			(tracks allowed)
			(vias allowed)
			(pads allowed)
			(copperpour allowed)
			(footprints allowed)
		)
		(placement
			(enabled no)
			(sheetname "")
		)
		(fill
			(thermal_gap 0.5)
			(thermal_bridge_width 0.5)
			(island_removal_mode 0)
		)
		(polygon
			(pts
				(xy 63.2968 -142.4686) (xy 65.151 -142.4686) (xy 65.151 -143.256) (xy 63.2968 -143.256)
			)
		)
	)
	(zone
		(layer "F.Cu")
		(hatch none 0.5)
		(connect_pads
			(clearance 0)
		)
		(min_thickness 0.25)
		(keepout
			(tracks allowed)
			(vias allowed)
			(pads allowed)
			(copperpour allowed)
			(footprints not_allowed)
		)
		(placement
			(enabled no)
			(sheetname "")
		)
		(fill
			(thermal_gap 0.5)
			(thermal_bridge_width 0.5)
			(island_removal_mode 0)
		)
		(polygon
			(pts
				(arc
					(start 150.750016 -153.999946)
					(mid 155.50007 -149.249892)
					(end 160.250124 -153.999946)
				)
				(arc
					(start 160.250124 -153.999946)
					(mid 155.50007 -158.75)
					(end 150.750016 -153.999946)
				)
			)
		)
	)
	(zone
		(layer "F.Cu")
		(hatch none 0.5)
		(connect_pads
			(clearance 0)
		)
		(min_thickness 0.25)
		(keepout
			(tracks not_allowed)
			(vias allowed)
			(pads allowed)
			(copperpour not_allowed)
			(footprints allowed)
		)
		(placement
			(enabled no)
			(sheetname "")
		)
		(fill
			(thermal_gap 0.5)
			(thermal_bridge_width 0.5)
			(island_removal_mode 0)
		)
		(polygon
			(pts
				(arc
					(start 77.054456 -80.862424)
					(mid 76.981581 -80.825003)
					(end 76.902818 -80.80248)
				)
				(arc
					(start 76.902818 -80.998568)
					(mid 77.283818 -81.379568)
					(end 77.664818 -80.998568)
				)
				(arc
					(start 77.664818 -80.109822)
					(mid 77.283945 -79.728568)
					(end 76.902818 -80.109568)
				)
				(arc
					(start 76.902818 -80.30591)
					(mid 76.98159 -80.283403)
					(end 77.054456 -80.245966)
				)
				(arc
					(start 77.054456 -80.245966)
					(mid 77.454178 -79.904241)
					(end 77.190854 -80.359504)
				)
				(arc
					(start 77.190854 -80.359504)
					(mid 77.054918 -80.43896)
					(end 76.902818 -80.479646)
				)
				(arc
					(start 76.902818 -80.628744)
					(mid 77.054745 -80.66939)
					(end 77.1906 -80.748632)
				)
				(arc
					(start 77.1906 -80.748632)
					(mid 77.454858 -81.20327)
					(end 77.054456 -80.862424)
				)
			)
		)
	)
	(zone
		(net "P3V3_STBY")
		(layer "F.Cu")
		(hatch none 0.5)
		(connect_pads
			(clearance 0.5)
		)
		(min_thickness 0.25)
		(fill yes
			(thermal_gap 0.5)
			(thermal_bridge_width 0.5)
			(island_removal_mode 0)
		)
		(polygon
			(pts
				(xy 39.1922 -129.8702) (xy 39.11473 -129.94767) (xy 39.11473 -130.50647) (xy 39.92626 -131.318)
				(xy 41.3258 -131.318) (xy 41.3512 -131.2926) (xy 41.3512 -130.0988) (xy 41.1226 -129.8702)
			)
		)
		(polygon
			(pts
				(xy 40.945308 -130.670046) (xy 40.742108 -130.670046) (xy 40.742108 -130.873246) (xy 40.945308 -130.873246)
			)
		)
		(polygon
			(pts
				(xy 40.486584 -130.662426) (xy 40.283384 -130.662426) (xy 40.283384 -130.865626) (xy 40.486584 -130.865626)
			)
		)
		(polygon
			(pts
				(xy 39.927784 -130.662426) (xy 39.724584 -130.662426) (xy 39.724584 -130.865626) (xy 39.927784 -130.865626)
			)
		)
	)
	(zone
		(net "TPS74801_P1V15_STBY_FB")
		(layer "F.Cu")
		(hatch none 0.5)
		(connect_pads
			(clearance 0.5)
		)
		(min_thickness 0.25)
		(fill yes
			(thermal_gap 0.5)
			(thermal_bridge_width 0.5)
			(island_removal_mode 0)
		)
		(polygon
			(pts
				(xy 75.8571 -154.8765) (xy 75.4634 -155.2702) (xy 75.4634 -158.347156) (xy 76.3016 -159.185356)
				(xy 76.3016 -160.2359) (xy 76.327 -160.2613) (xy 76.602844 -160.2613) (xy 76.653644 -160.2105) (xy 76.653644 -158.448756)
				(xy 77.2668 -157.8356) (xy 77.2668 -157.372812) (xy 76.971144 -157.077156) (xy 76.971144 -154.94)
				(xy 76.907644 -154.8765)
			)
		)
		(polygon
			(pts
				(xy 76.797662 -157.7975) (xy 76.594462 -157.7975) (xy 76.594462 -158.0007) (xy 76.797662 -158.0007)
			)
		)
		(polygon
			(pts
				(xy 76.797662 -157.2387) (xy 76.594462 -157.2387) (xy 76.594462 -157.4419) (xy 76.797662 -157.4419)
			)
		)
		(polygon
			(pts
				(xy 76.5302 -156.739336) (xy 76.327 -156.739336) (xy 76.327 -156.942536) (xy 76.5302 -156.942536)
			)
		)
		(polygon
			(pts
				(xy 76.5302 -156.180536) (xy 76.327 -156.180536) (xy 76.327 -156.383736) (xy 76.5302 -156.383736)
			)
		)
		(polygon
			(pts
				(xy 76.52258 -155.7401) (xy 76.31938 -155.7401) (xy 76.31938 -155.9433) (xy 76.52258 -155.9433)
			)
		)
		(polygon
			(pts
				(xy 76.52258 -155.1305) (xy 76.31938 -155.1305) (xy 76.31938 -155.3337) (xy 76.52258 -155.3337)
			)
		)
	)
	(zone
		(layer "F.Cu")
		(hatch none 0.5)
		(connect_pads
			(clearance 0)
		)
		(min_thickness 0.25)
		(keepout
			(tracks allowed)
			(vias allowed)
			(pads allowed)
			(copperpour allowed)
			(footprints not_allowed)
		)
		(placement
			(enabled no)
			(sheetname "")
		)
		(fill
			(thermal_gap 0.5)
			(thermal_bridge_width 0.5)
			(island_removal_mode 0)
		)
		(polygon
			(pts
				(arc
					(start 37.69995 -169.999914)
					(mid 41.450006 -166.249858)
					(end 45.200062 -169.999914)
				)
				(arc
					(start 45.200062 -169.999914)
					(mid 41.450006 -173.74997)
					(end 37.69995 -169.999914)
				)
			)
		)
	)
	(zone
		(layer "F.Cu")
		(hatch none 0.5)
		(connect_pads
			(clearance 0)
		)
		(min_thickness 0.25)
		(keepout
			(tracks allowed)
			(vias allowed)
			(pads allowed)
			(copperpour allowed)
			(footprints not_allowed)
		)
		(placement
			(enabled no)
			(sheetname "")
		)
		(fill
			(thermal_gap 0.5)
			(thermal_bridge_width 0.5)
			(island_removal_mode 0)
		)
		(polygon
			(pts
				(arc
					(start 227.24999 -7.999984)
					(mid 222.499936 -12.750038)
					(end 217.749882 -7.999984)
				)
				(arc
					(start 217.749882 -7.999984)
					(mid 222.499936 -3.24993)
					(end 227.24999 -7.999984)
				)
			)
		)
	)
	(zone
		(layer "F.Cu")
		(hatch none 0.5)
		(connect_pads
			(clearance 0)
		)
		(min_thickness 0.25)
		(keepout
			(tracks not_allowed)
			(vias allowed)
			(pads allowed)
			(copperpour not_allowed)
			(footprints allowed)
		)
		(placement
			(enabled no)
			(sheetname "")
		)
		(fill
			(thermal_gap 0.5)
			(thermal_bridge_width 0.5)
			(island_removal_mode 0)
		)
		(polygon
			(pts
				(arc
					(start 13.24991 -24.99995)
					(mid 17.999964 -20.249896)
					(end 22.750018 -24.99995)
				)
				(arc
					(start 22.750018 -24.99995)
					(mid 17.999964 -29.750004)
					(end 13.24991 -24.99995)
				)
			)
		)
	)
	(zone
		(net "GND")
		(layer "F.Cu")
		(hatch none 0.5)
		(connect_pads
			(clearance 0.5)
		)
		(min_thickness 0.25)
		(fill yes
			(thermal_gap 0.5)
			(thermal_bridge_width 0.5)
			(island_removal_mode 0)
		)
		(polygon
			(pts
				(xy 193.2432 -131.7244) (xy 192.9638 -132.0038) (xy 192.9638 -134.758176) (xy 192.296542 -135.425434)
				(xy 192.296542 -136.185148) (xy 192.576704 -136.46531) (xy 193.89344 -136.46531) (xy 194.44335 -135.9154)
				(xy 194.7926 -135.9154) (xy 194.8688 -135.8392) (xy 194.8688 -131.8006) (xy 194.7926 -131.7244)
			)
		)
	)
	(zone
		(layer "F.Cu")
		(hatch none 0.5)
		(connect_pads
			(clearance 0)
		)
		(min_thickness 0.25)
		(keepout
			(tracks allowed)
			(vias allowed)
			(pads allowed)
			(copperpour allowed)
			(footprints not_allowed)
		)
		(placement
			(enabled no)
			(sheetname "")
		)
		(fill
			(thermal_gap 0.5)
			(thermal_bridge_width 0.5)
			(island_removal_mode 0)
		)
		(polygon
			(pts
				(arc
					(start 198.3994 -21.249894)
					(mid 204.399388 -27.249882)
					(end 210.399376 -21.249894)
				)
				(xy 216.400126 -21.249894) (xy 216.400126 -56.74995) (xy 215.35009 -56.74995) (xy 215.35009 -66.74993)
				(xy 216.400126 -66.74993) (xy 216.400126 -128.249934) (xy 167.39997 -128.249934) (xy 167.39997 -21.249894)
				(arc
					(start 173.39945 -21.249894)
					(mid 179.399438 -27.249882)
					(end 185.399426 -21.249894)
				)
			)
		)
	)
	(zone
		(net "GND")
		(layer "F.Cu")
		(hatch none 0.5)
		(connect_pads
			(clearance 0.5)
		)
		(min_thickness 0.25)
		(fill yes
			(thermal_gap 0.5)
			(thermal_bridge_width 0.5)
			(island_removal_mode 0)
		)
		(polygon
			(pts
				(xy 30.0736 -162.8648) (xy 30.0228 -162.9156) (xy 30.0228 -164.4904) (xy 30.1371 -164.6047) (xy 30.3911 -164.6047)
				(xy 30.4038 -164.6174) (xy 32.7152 -164.6174) (xy 32.8422 -164.4904) (xy 32.8422 -163.068) (xy 32.639 -162.8648)
			)
		)
		(polygon
			(pts
				(xy 32.004 -163.7284) (xy 31.8008 -163.7284) (xy 31.8008 -163.9316) (xy 32.004 -163.9316)
			)
		)
		(polygon
			(pts
				(xy 31.6738 -163.3982) (xy 31.4706 -163.3982) (xy 31.4706 -163.6014) (xy 31.6738 -163.6014)
			)
		)
		(polygon
			(pts
				(xy 31.0642 -163.3982) (xy 30.861 -163.3982) (xy 30.861 -163.6014) (xy 31.0642 -163.6014)
			)
		)
		(polygon
			(pts
				(xy 30.734 -163.3982) (xy 30.5308 -163.3982) (xy 30.5308 -163.6014) (xy 30.734 -163.6014)
			)
		)
	)
	(zone
		(layer "F.Cu")
		(hatch none 0.5)
		(connect_pads
			(clearance 0)
		)
		(min_thickness 0.25)
		(keepout
			(tracks not_allowed)
			(vias allowed)
			(pads allowed)
			(copperpour not_allowed)
			(footprints allowed)
		)
		(placement
			(enabled no)
			(sheetname "")
		)
		(fill
			(thermal_gap 0.5)
			(thermal_bridge_width 0.5)
			(island_removal_mode 0)
		)
		(polygon
			(pts
				(arc
					(start 150.750016 -153.999946)
					(mid 155.50007 -149.249892)
					(end 160.250124 -153.999946)
				)
				(arc
					(start 160.250124 -153.999946)
					(mid 155.50007 -158.75)
					(end 150.750016 -153.999946)
				)
			)
		)
	)
	(zone
		(layer "F.Cu")
		(hatch none 0.5)
		(connect_pads
			(clearance 0)
		)
		(min_thickness 0.25)
		(keepout
			(tracks not_allowed)
			(vias allowed)
			(pads allowed)
			(copperpour not_allowed)
			(footprints allowed)
		)
		(placement
			(enabled no)
			(sheetname "")
		)
		(fill
			(thermal_gap 0.5)
			(thermal_bridge_width 0.5)
			(island_removal_mode 0)
		)
		(polygon
			(pts
				(xy 11.8999 -109.799882) (xy 11.8999 -103.799894)
				(arc
					(start 18.317464 -103.799894)
					(mid 20.016891 -101.275181)
					(end 22.899878 -100.300028)
				)
				(arc
					(start 22.899878 -100.300028)
					(mid 27.649932 -105.050082)
					(end 22.899878 -109.799882)
				)
			)
		)
	)
	(zone
		(net "P3V3_M2")
		(layer "F.Cu")
		(hatch none 0.5)
		(connect_pads
			(clearance 0.5)
		)
		(min_thickness 0.25)
		(fill yes
			(thermal_gap 0.5)
			(thermal_bridge_width 0.5)
			(island_removal_mode 0)
		)
		(polygon
			(pts
				(xy 195.536058 -123.571508) (xy 195.1482 -123.959366) (xy 195.1482 -128.0922) (xy 195.1736 -128.1176)
				(xy 196.0372 -128.1176) (xy 196.0626 -128.0922) (xy 196.0626 -126.365) (xy 196.2404 -126.1872) (xy 197.612 -126.1872)
				(xy 197.739 -126.3142) (xy 197.739 -128.0414) (xy 197.7898 -128.0922) (xy 199.5678 -128.0922) (xy 199.5678 -126.4666)
				(xy 199.5932 -126.4412) (xy 199.5932 -123.933458) (xy 199.23125 -123.571508)
			)
		)
	)
	(zone
		(layer "F.Cu")
		(hatch none 0.5)
		(connect_pads
			(clearance 0)
		)
		(min_thickness 0.25)
		(keepout
			(tracks allowed)
			(vias allowed)
			(pads allowed)
			(copperpour allowed)
			(footprints not_allowed)
		)
		(placement
			(enabled no)
			(sheetname "")
		)
		(fill
			(thermal_gap 0.5)
			(thermal_bridge_width 0.5)
			(island_removal_mode 0)
		)
		(polygon
			(pts
				(xy 6.700012 -113.050066) (xy 85.700108 -113.050066) (xy 85.700108 -109.799882)
				(arc
					(start 78.550008 -109.799882)
					(mid 73.800208 -105.050082)
					(end 78.550008 -100.300028)
				)
				(xy 85.700108 -100.300028) (xy 85.700108 -44.800012)
				(arc
					(start 78.49997 -44.800012)
					(mid 73.749916 -40.049958)
					(end 78.49997 -35.299904)
				)
				(xy 85.700108 -35.299904) (xy 85.700108 -31.049976) (xy 82.300064 -31.049976) (xy 82.300064 0)
				(arc
					(start 74.030078 0)
					(mid 73.322973 -0.292893)
					(end 73.03008 -0.999998)
				)
				(arc
					(start 73.03008 -109.050074)
					(mid 72.737187 -109.757179)
					(end 72.030082 -110.050072)
				)
				(arc
					(start 31.530036 -110.050072)
					(mid 30.822931 -109.757179)
					(end 30.530038 -109.050074)
				)
				(xy 30.530038 -48.600106) (xy 6.700012 -48.600106) (xy 6.700012 -55.79999)
				(arc
					(start 22.800056 -55.79999)
					(mid 27.55011 -60.550044)
					(end 22.800056 -65.300098)
				)
				(xy 6.700012 -65.300098) (xy 6.700012 -103.799894)
				(arc
					(start 18.317464 -103.799894)
					(mid 20.016891 -101.275181)
					(end 22.899878 -100.300028)
				)
				(arc
					(start 22.899878 -100.300028)
					(mid 27.649932 -105.050082)
					(end 22.899878 -109.799882)
				)
				(xy 6.700012 -109.799882)
			)
		)
	)
	(zone
		(layer "F.Cu")
		(hatch none 0.5)
		(connect_pads
			(clearance 0)
		)
		(min_thickness 0.25)
		(keepout
			(tracks allowed)
			(vias allowed)
			(pads allowed)
			(copperpour allowed)
			(footprints allowed)
		)
		(placement
			(enabled no)
			(sheetname "")
		)
		(fill
			(thermal_gap 0.5)
			(thermal_bridge_width 0.5)
			(island_removal_mode 0)
		)
		(polygon
			(pts
				(xy 195.2244 -128.1684) (xy 196.469 -128.1684) (xy 196.5706 -128.0668) (xy 196.5706 -126.5428) (xy 196.4436 -126.4158)
				(xy 195.2752 -126.4158) (xy 195.1228 -126.5682) (xy 195.1228 -128.0668)
			)
		)
	)
	(zone
		(layer "F.Cu")
		(hatch none 0.5)
		(connect_pads
			(clearance 0)
		)
		(min_thickness 0.25)
		(keepout
			(tracks not_allowed)
			(vias allowed)
			(pads allowed)
			(copperpour not_allowed)
			(footprints allowed)
		)
		(placement
			(enabled no)
			(sheetname "")
		)
		(fill
			(thermal_gap 0.5)
			(thermal_bridge_width 0.5)
			(island_removal_mode 0)
		)
		(polygon
			(pts
				(arc
					(start 83.739228 -75.305412)
					(mid 83.358355 -74.924158)
					(end 82.977228 -75.305158)
				)
				(arc
					(start 82.977228 -75.4507)
					(mid 83.042547 -75.42326)
					(end 83.105498 -75.390756)
				)
				(arc
					(start 83.105498 -75.390756)
					(mid 83.568918 -75.141756)
					(end 83.211416 -75.527662)
				)
				(arc
					(start 83.211416 -75.527662)
					(mid 83.097457 -75.586894)
					(end 82.977228 -75.632056)
				)
				(arc
					(start 82.977228 -75.86726)
					(mid 83.097451 -75.912436)
					(end 83.211416 -75.971654)
				)
				(arc
					(start 83.211416 -75.971654)
					(mid 83.568897 -76.357544)
					(end 83.105498 -76.10856)
				)
				(arc
					(start 83.105498 -76.10856)
					(mid 83.04254 -76.076069)
					(end 82.977228 -76.048616)
				)
				(arc
					(start 82.977228 -76.194158)
					(mid 83.358228 -76.575158)
					(end 83.739228 -76.194158)
				)
			)
		)
	)
	(zone
		(layer "F.Cu")
		(hatch none 0.5)
		(connect_pads
			(clearance 0)
		)
		(min_thickness 0.25)
		(keepout
			(tracks allowed)
			(vias allowed)
			(pads allowed)
			(copperpour allowed)
			(footprints not_allowed)
		)
		(placement
			(enabled no)
			(sheetname "")
		)
		(fill
			(thermal_gap 0.5)
			(thermal_bridge_width 0.5)
			(island_removal_mode 0)
		)
		(polygon
			(pts
				(arc
					(start 160.250124 -153.999946)
					(mid 155.50007 -158.75)
					(end 150.750016 -153.999946)
				)
				(arc
					(start 150.750016 -153.999946)
					(mid 155.50007 -149.249892)
					(end 160.250124 -153.999946)
				)
			)
		)
	)
	(zone
		(layer "F.Cu")
		(hatch none 0.5)
		(connect_pads
			(clearance 0)
		)
		(min_thickness 0.25)
		(keepout
			(tracks not_allowed)
			(vias allowed)
			(pads allowed)
			(copperpour not_allowed)
			(footprints allowed)
		)
		(placement
			(enabled no)
			(sheetname "")
		)
		(fill
			(thermal_gap 0.5)
			(thermal_bridge_width 0.5)
			(island_removal_mode 0)
		)
		(polygon
			(pts
				(arc
					(start 78.550008 -100.300028)
					(mid 73.799954 -105.050082)
					(end 78.550008 -109.799882)
				)
				(xy 92.700094 -109.799882) (xy 92.700094 -100.300028)
			)
		)
	)
	(zone
		(layer "F.Cu")
		(hatch none 0.5)
		(connect_pads
			(clearance 0)
		)
		(min_thickness 0.25)
		(keepout
			(tracks allowed)
			(vias allowed)
			(pads allowed)
			(copperpour allowed)
			(footprints allowed)
		)
		(placement
			(enabled no)
			(sheetname "")
		)
		(fill
			(thermal_gap 0.5)
			(thermal_bridge_width 0.5)
			(island_removal_mode 0)
		)
		(polygon
			(pts
				(xy 68.2498 -139.192) (xy 70.104 -139.192) (xy 70.104 -139.9794) (xy 68.2498 -139.9794)
			)
		)
	)
	(zone
		(layer "F.Cu")
		(hatch none 0.5)
		(connect_pads
			(clearance 0)
		)
		(min_thickness 0.25)
		(keepout
			(tracks not_allowed)
			(vias allowed)
			(pads allowed)
			(copperpour not_allowed)
			(footprints allowed)
		)
		(placement
			(enabled no)
			(sheetname "")
		)
		(fill
			(thermal_gap 0.5)
			(thermal_bridge_width 0.5)
			(island_removal_mode 0)
		)
		(polygon
			(pts
				(arc
					(start 83.739228 -81.69275)
					(mid 83.358355 -81.311496)
					(end 82.977228 -81.692496)
				)
				(arc
					(start 82.977228 -81.838038)
					(mid 83.042547 -81.810598)
					(end 83.105498 -81.778094)
				)
				(arc
					(start 83.105498 -81.778094)
					(mid 83.568918 -81.529094)
					(end 83.211416 -81.915)
				)
				(arc
					(start 83.211416 -81.915)
					(mid 83.097457 -81.974232)
					(end 82.977228 -82.019394)
				)
				(arc
					(start 82.977228 -82.254598)
					(mid 83.097451 -82.299774)
					(end 83.211416 -82.358992)
				)
				(arc
					(start 83.211416 -82.358992)
					(mid 83.568897 -82.744882)
					(end 83.105498 -82.495898)
				)
				(arc
					(start 83.105498 -82.495898)
					(mid 83.04254 -82.463407)
					(end 82.977228 -82.435954)
				)
				(arc
					(start 82.977228 -82.581496)
					(mid 83.358228 -82.962496)
					(end 83.739228 -82.581496)
				)
			)
		)
	)
	(zone
		(layer "F.Cu")
		(hatch none 0.5)
		(connect_pads
			(clearance 0)
		)
		(min_thickness 0.25)
		(keepout
			(tracks allowed)
			(vias allowed)
			(pads allowed)
			(copperpour allowed)
			(footprints allowed)
		)
		(placement
			(enabled no)
			(sheetname "")
		)
		(fill
			(thermal_gap 0.5)
			(thermal_bridge_width 0.5)
			(island_removal_mode 0)
		)
		(polygon
			(pts
				(xy 93.98 -151.3332) (xy 93.98 -153.1874) (xy 92.6338 -153.1874) (xy 92.6338 -151.3332)
			)
		)
	)
	(zone
		(layer "F.Cu")
		(hatch none 0.5)
		(connect_pads
			(clearance 0)
		)
		(min_thickness 0.25)
		(keepout
			(tracks allowed)
			(vias allowed)
			(pads allowed)
			(copperpour allowed)
			(footprints not_allowed)
		)
		(placement
			(enabled no)
			(sheetname "")
		)
		(fill
			(thermal_gap 0.5)
			(thermal_bridge_width 0.5)
			(island_removal_mode 0)
		)
		(polygon
			(pts
				(arc
					(start 87.749888 -187.999878)
					(mid 92.499942 -183.249824)
					(end 97.249996 -187.999878)
				)
				(arc
					(start 97.249996 -187.999878)
					(mid 92.499942 -192.749932)
					(end 87.749888 -187.999878)
				)
			)
		)
	)
	(zone
		(net "GND")
		(layer "F.Cu")
		(hatch none 0.5)
		(connect_pads
			(clearance 0.5)
		)
		(min_thickness 0.25)
		(fill yes
			(thermal_gap 0.5)
			(thermal_bridge_width 0.5)
			(island_removal_mode 0)
		)
		(polygon
			(pts
				(xy 127.64008 -4.28117) (xy 127.387096 -4.534154) (xy 127.387096 -5.921502) (xy 127.781812 -6.316218)
				(xy 129.599436 -6.316218) (xy 129.766314 -6.14934) (xy 129.766314 -4.417822) (xy 129.629662 -4.28117)
			)
		)
		(polygon
			(pts
				(xy 128.96977 -5.156708) (xy 128.76657 -5.156708) (xy 128.76657 -5.359908) (xy 128.96977 -5.359908)
			)
		)
		(polygon
			(pts
				(xy 128.646174 -5.155946) (xy 128.442974 -5.155946) (xy 128.442974 -5.359146) (xy 128.646174 -5.359146)
			)
		)
		(polygon
			(pts
				(xy 127.782574 -5.155946) (xy 127.579374 -5.155946) (xy 127.579374 -5.359146) (xy 127.782574 -5.359146)
			)
		)
	)
	(zone
		(layer "F.Cu")
		(hatch none 0.5)
		(connect_pads
			(clearance 0)
		)
		(min_thickness 0.25)
		(keepout
			(tracks allowed)
			(vias allowed)
			(pads allowed)
			(copperpour allowed)
			(footprints not_allowed)
		)
		(placement
			(enabled no)
			(sheetname "")
		)
		(fill
			(thermal_gap 0.5)
			(thermal_bridge_width 0.5)
			(island_removal_mode 0)
		)
		(polygon
			(pts
				(arc
					(start 217.749882 -7.999984)
					(mid 222.499936 -3.24993)
					(end 227.24999 -7.999984)
				)
				(arc
					(start 227.24999 -7.999984)
					(mid 222.499936 -12.750038)
					(end 217.749882 -7.999984)
				)
			)
		)
	)
	(zone
		(layer "F.Cu")
		(hatch none 0.5)
		(connect_pads
			(clearance 0)
		)
		(min_thickness 0.25)
		(keepout
			(tracks allowed)
			(vias allowed)
			(pads allowed)
			(copperpour allowed)
			(footprints not_allowed)
		)
		(placement
			(enabled no)
			(sheetname "")
		)
		(fill
			(thermal_gap 0.5)
			(thermal_bridge_width 0.5)
			(island_removal_mode 0)
		)
		(polygon
			(pts
				(xy 73.429876 -129.519934) (xy 73.429876 -113.199926) (xy 24.5999 -113.199926) (xy 24.5999 -129.519934)
			)
		)
	)
	(zone
		(net "P3V3_STBY")
		(layer "F.Cu")
		(hatch none 0.5)
		(connect_pads
			(clearance 0.5)
		)
		(min_thickness 0.25)
		(fill yes
			(thermal_gap 0.5)
			(thermal_bridge_width 0.5)
			(island_removal_mode 0)
		)
		(polygon
			(pts
				(xy 95.2246 -146.05) (xy 95.2246 -146.3802) (xy 95.25 -146.4056) (xy 95.8088 -146.4056) (xy 95.9358 -146.5326)
				(xy 95.9358 -147.4216) (xy 95.9231 -147.4343) (xy 95.9231 -147.7391) (xy 95.988632 -147.804632)
				(xy 98.630232 -147.804632) (xy 98.8441 -148.0185) (xy 99.3521 -148.0185) (xy 99.5426 -148.209) (xy 99.5426 -150.9776)
				(xy 99.6442 -151.0792) (xy 100.8634 -151.0792) (xy 101.219 -151.4348) (xy 101.219 -152.019) (xy 100.9142 -152.3238)
				(xy 99.7712 -152.3238) (xy 99.5426 -152.5524) (xy 99.5426 -154.051) (xy 99.695 -154.2034) (xy 100.5332 -154.2034)
				(xy 100.8888 -154.559) (xy 100.8888 -155.7274) (xy 99.949 -156.6672) (xy 99.1362 -156.6672) (xy 99.0854 -156.718)
				(xy 99.0854 -157.1752) (xy 99.2759 -157.3657) (xy 100.0633 -157.3657) (xy 100.33 -157.6324) (xy 100.33 -158.5214)
				(xy 99.441 -159.4104) (xy 99.441 -162.2806) (xy 99.6188 -162.4584) (xy 101.2952 -162.4584) (xy 101.70287 -162.05073)
				(xy 101.70287 -150.95347) (xy 100.12045 -149.37105) (xy 100.12045 -147.63115) (xy 99.7966 -147.3073)
				(xy 98.8949 -147.3073) (xy 98.5012 -146.9136) (xy 98.5012 -146.2532) (xy 98.4758 -146.2278) (xy 96.9264 -146.2278)
				(xy 96.8756 -146.177) (xy 96.8756 -146.1516) (xy 96.774 -146.05)
			)
		)
		(polygon
			(pts
				(xy 100.1014 -161.6456) (xy 99.8982 -161.6456) (xy 99.8982 -161.8488) (xy 100.1014 -161.8488)
			)
		)
		(polygon
			(pts
				(xy 100.110544 -159.83712) (xy 99.907344 -159.83712) (xy 99.907344 -160.04032) (xy 100.110544 -160.04032)
			)
		)
		(polygon
			(pts
				(xy 100.110544 -159.27832) (xy 99.907344 -159.27832) (xy 99.907344 -159.48152) (xy 100.110544 -159.48152)
			)
		)
		(polygon
			(pts
				(xy 100.203 -153.3906) (xy 99.9998 -153.3906) (xy 99.9998 -153.5938) (xy 100.203 -153.5938)
			)
		)
		(polygon
			(pts
				(xy 100.203 -152.908) (xy 99.9998 -152.908) (xy 99.9998 -153.1112) (xy 100.203 -153.1112)
			)
		)
		(polygon
			(pts
				(xy 100.1776 -150.2918) (xy 99.9744 -150.2918) (xy 99.9744 -150.495) (xy 100.1776 -150.495)
			)
		)
		(polygon
			(pts
				(xy 100.1776 -149.8092) (xy 99.9744 -149.8092) (xy 99.9744 -150.0124) (xy 100.1776 -150.0124)
			)
		)
		(polygon
			(pts
				(xy 97.663 -147.0406) (xy 97.4598 -147.0406) (xy 97.4598 -147.2438) (xy 97.663 -147.2438)
			)
		)
		(polygon
			(pts
				(xy 97.1042 -147.0406) (xy 96.901 -147.0406) (xy 96.901 -147.2438) (xy 97.1042 -147.2438)
			)
		)
		(polygon
			(pts
				(xy 96.5962 -147.0406) (xy 96.393 -147.0406) (xy 96.393 -147.2438) (xy 96.5962 -147.2438)
			)
		)
		(polygon
			(pts
				(xy 98.199194 -146.769074) (xy 97.995994 -146.769074) (xy 97.995994 -146.972274) (xy 98.199194 -146.972274)
			)
		)
	)
	(zone
		(layer "F.Cu")
		(hatch none 0.5)
		(connect_pads
			(clearance 0)
		)
		(min_thickness 0.25)
		(keepout
			(tracks allowed)
			(vias allowed)
			(pads allowed)
			(copperpour allowed)
			(footprints allowed)
		)
		(placement
			(enabled no)
			(sheetname "")
		)
		(fill
			(thermal_gap 0.5)
			(thermal_bridge_width 0.5)
			(island_removal_mode 0)
		)
		(polygon
			(pts
				(xy 153.149554 -9.124696) (xy 153.149554 -10.20191) (xy 153.327354 -10.37971) (xy 154.72029 -10.37971)
				(xy 154.813 -10.287) (xy 154.813 -9.66089) (xy 154.161744 -9.009634) (xy 153.264616 -9.009634)
			)
		)
	)
	(zone
		(layer "F.Cu")
		(hatch none 0.5)
		(connect_pads
			(clearance 0)
		)
		(min_thickness 0.25)
		(keepout
			(tracks allowed)
			(vias allowed)
			(pads allowed)
			(copperpour allowed)
			(footprints not_allowed)
		)
		(placement
			(enabled no)
			(sheetname "")
		)
		(fill
			(thermal_gap 0.5)
			(thermal_bridge_width 0.5)
			(island_removal_mode 0)
		)
		(polygon
			(pts
				(arc
					(start 217.749882 -153.999946)
					(mid 222.499936 -149.249892)
					(end 227.24999 -153.999946)
				)
				(arc
					(start 227.24999 -153.999946)
					(mid 222.499936 -158.75)
					(end 217.749882 -153.999946)
				)
			)
		)
	)
	(zone
		(layer "F.Cu")
		(hatch none 0.5)
		(connect_pads
			(clearance 0)
		)
		(min_thickness 0.25)
		(keepout
			(tracks allowed)
			(vias allowed)
			(pads allowed)
			(copperpour allowed)
			(footprints allowed)
		)
		(placement
			(enabled no)
			(sheetname "")
		)
		(fill
			(thermal_gap 0.5)
			(thermal_bridge_width 0.5)
			(island_removal_mode 0)
		)
		(polygon
			(pts
				(xy 90.2716 -154.94) (xy 90.2716 -156.2862) (xy 90.2716 -157.5816) (xy 90.0684 -157.7848) (xy 88.392 -157.7848)
				(xy 88.3793 -157.7721) (xy 87.6681 -157.7721) (xy 87.4014 -157.5054) (xy 87.4014 -155.1432) (xy 87.8586 -154.686)
				(xy 90.0176 -154.686)
			)
		)
	)
	(zone
		(net "P3V3_STBY")
		(layer "F.Cu")
		(hatch none 0.5)
		(connect_pads
			(clearance 0.5)
		)
		(min_thickness 0.25)
		(fill yes
			(thermal_gap 0.5)
			(thermal_bridge_width 0.5)
			(island_removal_mode 0)
		)
		(polygon
			(pts
				(xy 61.1124 -181.61) (xy 60.7187 -182.0037) (xy 60.7187 -188.595) (xy 60.96635 -188.84265) (xy 63.63335 -188.84265)
				(xy 63.9826 -188.4934) (xy 63.9826 -182.2704) (xy 63.3222 -181.61)
			)
		)
	)
	(zone
		(net "AGND_CURRENT_MON")
		(layer "F.Cu")
		(hatch none 0.5)
		(connect_pads
			(clearance 0.5)
		)
		(min_thickness 0.25)
		(fill yes
			(thermal_gap 0.5)
			(thermal_bridge_width 0.5)
			(island_removal_mode 0)
		)
		(polygon
			(pts
				(xy 110.96244 -4.953) (xy 109.22 -6.69544) (xy 109.22 -14.275816) (xy 109.538008 -14.593824) (xy 110.92688 -14.593824)
				(xy 110.9726 -14.548104) (xy 110.9726 -14.1986) (xy 110.5662 -13.7922) (xy 110.5662 -8.9662) (xy 110.617 -8.9154)
				(xy 111.8108 -8.9154) (xy 112.0902 -9.1948) (xy 112.0902 -9.8806) (xy 112.1918 -9.9822) (xy 112.649 -9.9822)
				(xy 112.6998 -9.9314) (xy 112.6998 -5.2832) (xy 112.3696 -4.953)
			)
		)
		(polygon
			(pts
				(xy 109.714284 -13.4874) (xy 109.511084 -13.4874) (xy 109.511084 -13.6906) (xy 109.714284 -13.6906)
			)
		)
		(polygon
			(pts
				(xy 109.714284 -12.6238) (xy 109.511084 -12.6238) (xy 109.511084 -12.827) (xy 109.714284 -12.827)
			)
		)
		(polygon
			(pts
				(xy 109.71657 -12.304776) (xy 109.51337 -12.304776) (xy 109.51337 -12.507976) (xy 109.71657 -12.507976)
			)
		)
		(polygon
			(pts
				(xy 109.71657 -11.441176) (xy 109.51337 -11.441176) (xy 109.51337 -11.644376) (xy 109.71657 -11.644376)
			)
		)
		(polygon
			(pts
				(xy 109.717078 -11.122152) (xy 109.513878 -11.122152) (xy 109.513878 -11.325352) (xy 109.717078 -11.325352)
			)
		)
		(polygon
			(pts
				(xy 109.717078 -10.258552) (xy 109.513878 -10.258552) (xy 109.513878 -10.461752) (xy 109.717078 -10.461752)
			)
		)
		(polygon
			(pts
				(xy 110.10519 -9.844278) (xy 109.90199 -9.844278) (xy 109.90199 -10.047478) (xy 110.10519 -10.047478)
			)
		)
		(polygon
			(pts
				(xy 110.10519 -9.285478) (xy 109.90199 -9.285478) (xy 109.90199 -9.488678) (xy 110.10519 -9.488678)
			)
		)
		(polygon
			(pts
				(xy 112.20069 -8.320278) (xy 111.99749 -8.320278) (xy 111.99749 -8.523478) (xy 112.20069 -8.523478)
			)
		)
		(polygon
			(pts
				(xy 112.26419 -7.913878) (xy 112.06099 -7.913878) (xy 112.06099 -8.117078) (xy 112.26419 -8.117078)
			)
		)
		(polygon
			(pts
				(xy 112.26419 -7.355078) (xy 112.06099 -7.355078) (xy 112.06099 -7.558278) (xy 112.26419 -7.558278)
			)
		)
		(polygon
			(pts
				(xy 112.26419 -6.821678) (xy 112.06099 -6.821678) (xy 112.06099 -7.024878) (xy 112.26419 -7.024878)
			)
		)
		(polygon
			(pts
				(xy 112.26419 -6.262878) (xy 112.06099 -6.262878) (xy 112.06099 -6.466078) (xy 112.26419 -6.466078)
			)
		)
		(polygon
			(pts
				(xy 112.23879 -5.754878) (xy 112.03559 -5.754878) (xy 112.03559 -5.958078) (xy 112.23879 -5.958078)
			)
		)
		(polygon
			(pts
				(xy 112.23879 -5.196078) (xy 112.03559 -5.196078) (xy 112.03559 -5.399278) (xy 112.23879 -5.399278)
			)
		)
	)
	(zone
		(layer "F.Cu")
		(hatch none 0.5)
		(connect_pads
			(clearance 0)
		)
		(min_thickness 0.25)
		(keepout
			(tracks not_allowed)
			(vias allowed)
			(pads allowed)
			(copperpour not_allowed)
			(footprints allowed)
		)
		(placement
			(enabled no)
			(sheetname "")
		)
		(fill
			(thermal_gap 0.5)
			(thermal_bridge_width 0.5)
			(island_removal_mode 0)
		)
		(polygon
			(pts
				(arc
					(start 87.749888 -187.999878)
					(mid 92.499942 -183.249824)
					(end 97.249996 -187.999878)
				)
				(arc
					(start 97.249996 -187.999878)
					(mid 92.499942 -192.749932)
					(end 87.749888 -187.999878)
				)
			)
		)
	)
	(zone
		(layer "F.Cu")
		(hatch none 0.5)
		(connect_pads
			(clearance 0)
		)
		(min_thickness 0.25)
		(keepout
			(tracks not_allowed)
			(vias allowed)
			(pads allowed)
			(copperpour not_allowed)
			(footprints allowed)
		)
		(placement
			(enabled no)
			(sheetname "")
		)
		(fill
			(thermal_gap 0.5)
			(thermal_bridge_width 0.5)
			(island_removal_mode 0)
		)
		(polygon
			(pts
				(arc
					(start 83.739228 -94.492826)
					(mid 83.358355 -94.111572)
					(end 82.977228 -94.492572)
				)
				(arc
					(start 82.977228 -94.638114)
					(mid 83.042547 -94.610674)
					(end 83.105498 -94.57817)
				)
				(arc
					(start 83.105498 -94.57817)
					(mid 83.568918 -94.32917)
					(end 83.211416 -94.715076)
				)
				(arc
					(start 83.211416 -94.715076)
					(mid 83.097457 -94.774308)
					(end 82.977228 -94.81947)
				)
				(arc
					(start 82.977228 -95.054674)
					(mid 83.097451 -95.09985)
					(end 83.211416 -95.159068)
				)
				(arc
					(start 83.211416 -95.159068)
					(mid 83.568897 -95.544958)
					(end 83.105498 -95.295974)
				)
				(arc
					(start 83.105498 -95.295974)
					(mid 83.04254 -95.263483)
					(end 82.977228 -95.23603)
				)
				(arc
					(start 82.977228 -95.381572)
					(mid 83.358228 -95.762572)
					(end 83.739228 -95.381572)
				)
			)
		)
	)
	(zone
		(layer "F.Cu")
		(hatch none 0.5)
		(connect_pads
			(clearance 0)
		)
		(min_thickness 0.25)
		(keepout
			(tracks allowed)
			(vias allowed)
			(pads allowed)
			(copperpour allowed)
			(footprints not_allowed)
		)
		(placement
			(enabled no)
			(sheetname "")
		)
		(fill
			(thermal_gap 0.5)
			(thermal_bridge_width 0.5)
			(island_removal_mode 0)
		)
		(polygon
			(pts
				(xy 213.19998 -155.999942) (xy 213.19998 -145.999962) (xy 203.2 -145.999962) (xy 203.2 -155.999942)
			)
		)
	)
	(zone
		(layer "F.Cu")
		(hatch none 0.5)
		(connect_pads
			(clearance 0)
		)
		(min_thickness 0.25)
		(keepout
			(tracks not_allowed)
			(vias allowed)
			(pads allowed)
			(copperpour not_allowed)
			(footprints allowed)
		)
		(placement
			(enabled no)
			(sheetname "")
		)
		(fill
			(thermal_gap 0.5)
			(thermal_bridge_width 0.5)
			(island_removal_mode 0)
		)
		(polygon
			(pts
				(arc
					(start 107.750102 -9.99998)
					(mid 103.000048 -14.750034)
					(end 98.249994 -9.99998)
				)
				(arc
					(start 98.249994 -9.99998)
					(mid 103.000048 -5.249926)
					(end 107.750102 -9.99998)
				)
			)
		)
	)
	(zone
		(layer "F.Cu")
		(hatch none 0.5)
		(connect_pads
			(clearance 0)
		)
		(min_thickness 0.25)
		(keepout
			(tracks allowed)
			(vias allowed)
			(pads allowed)
			(copperpour allowed)
			(footprints not_allowed)
		)
		(placement
			(enabled no)
			(sheetname "")
		)
		(fill
			(thermal_gap 0.5)
			(thermal_bridge_width 0.5)
			(island_removal_mode 0)
		)
		(polygon
			(pts
				(arc
					(start 107.750102 -9.99998)
					(mid 103.000048 -14.750034)
					(end 98.249994 -9.99998)
				)
				(arc
					(start 98.249994 -9.99998)
					(mid 103.000048 -5.249926)
					(end 107.750102 -9.99998)
				)
			)
		)
	)
	(zone
		(layer "F.Cu")
		(hatch none 0.5)
		(connect_pads
			(clearance 0)
		)
		(min_thickness 0.25)
		(keepout
			(tracks allowed)
			(vias allowed)
			(pads allowed)
			(copperpour allowed)
			(footprints allowed)
		)
		(placement
			(enabled no)
			(sheetname "")
		)
		(fill
			(thermal_gap 0.5)
			(thermal_bridge_width 0.5)
			(island_removal_mode 0)
		)
		(polygon
			(pts
				(xy 75.426824 -96.814132) (xy 75.426824 -66.514726) (xy 82.888074 -66.514726) (xy 82.888074 -96.814132)
			)
		)
	)
	(zone
		(layer "F.Cu")
		(hatch none 0.5)
		(connect_pads
			(clearance 0)
		)
		(min_thickness 0.25)
		(keepout
			(tracks allowed)
			(vias allowed)
			(pads allowed)
			(copperpour allowed)
			(footprints allowed)
		)
		(placement
			(enabled no)
			(sheetname "")
		)
		(fill
			(thermal_gap 0.5)
			(thermal_bridge_width 0.5)
			(island_removal_mode 0)
		)
		(polygon
			(pts
				(xy 219.412566 -101.602286) (xy 219.412566 -99.316286) (xy 219.260166 -99.163886) (xy 218.142566 -99.163886)
				(xy 217.990166 -99.316286) (xy 217.990166 -101.399086) (xy 218.345766 -101.754686) (xy 219.260166 -101.754686)
			)
		)
	)
	(zone
		(layer "F.Cu")
		(hatch none 0.5)
		(connect_pads
			(clearance 0)
		)
		(min_thickness 0.25)
		(keepout
			(tracks allowed)
			(vias allowed)
			(pads allowed)
			(copperpour allowed)
			(footprints not_allowed)
		)
		(placement
			(enabled no)
			(sheetname "")
		)
		(fill
			(thermal_gap 0.5)
			(thermal_bridge_width 0.5)
			(island_removal_mode 0)
		)
		(polygon
			(pts
				(arc
					(start 227.24999 -153.999946)
					(mid 222.499936 -158.75)
					(end 217.749882 -153.999946)
				)
				(arc
					(start 217.749882 -153.999946)
					(mid 222.499936 -149.249892)
					(end 227.24999 -153.999946)
				)
			)
		)
	)
	(zone
		(layer "F.Cu")
		(hatch none 0.5)
		(connect_pads
			(clearance 0)
		)
		(min_thickness 0.25)
		(keepout
			(tracks allowed)
			(vias allowed)
			(pads allowed)
			(copperpour allowed)
			(footprints not_allowed)
		)
		(placement
			(enabled no)
			(sheetname "")
		)
		(fill
			(thermal_gap 0.5)
			(thermal_bridge_width 0.5)
			(island_removal_mode 0)
		)
		(polygon
			(pts
				(arc
					(start 75.25004 -120.000014)
					(mid 80.000094 -115.24996)
					(end 84.749894 -120.000014)
				)
				(arc
					(start 84.749894 -120.000014)
					(mid 80.000094 -124.749814)
					(end 75.25004 -120.000014)
				)
			)
		)
	)
	(zone
		(layer "F.Cu")
		(hatch none 0.5)
		(connect_pads
			(clearance 0)
		)
		(min_thickness 0.25)
		(keepout
			(tracks allowed)
			(vias allowed)
			(pads allowed)
			(copperpour allowed)
			(footprints not_allowed)
		)
		(placement
			(enabled no)
			(sheetname "")
		)
		(fill
			(thermal_gap 0.5)
			(thermal_bridge_width 0.5)
			(island_removal_mode 0)
		)
		(polygon
			(pts
				(xy 225.35007 -56.74995) (xy 215.35009 -56.74995) (xy 215.35009 -66.74993) (xy 225.35007 -66.74993)
			)
		)
	)
	(zone
		(layer "F.Cu")
		(hatch none 0.5)
		(connect_pads
			(clearance 0)
		)
		(min_thickness 0.25)
		(keepout
			(tracks not_allowed)
			(vias allowed)
			(pads allowed)
			(copperpour not_allowed)
			(footprints allowed)
		)
		(placement
			(enabled no)
			(sheetname "")
		)
		(fill
			(thermal_gap 0.5)
			(thermal_bridge_width 0.5)
			(island_removal_mode 0)
		)
		(polygon
			(pts
				(arc
					(start 128.467866 -25.830276)
					(mid 128.086866 -26.211276)
					(end 128.467866 -26.592276)
				)
				(xy 128.76022 -26.592276) (xy 128.76022 -26.54681)
				(arc
					(start 128.76022 -26.542238)
					(mid 128.740709 -26.446354)
					(end 128.68529 -26.365708)
				)
				(arc
					(start 128.68529 -26.365708)
					(mid 128.210384 -26.141812)
					(end 128.73355 -26.187146)
				)
				(arc
					(start 128.73355 -26.187146)
					(mid 128.869614 -26.322845)
					(end 128.9304 -26.505154)
				)
				(xy 128.931924 -26.506678) (xy 128.931924 -26.531824) (xy 128.931924 -26.542238) (xy 128.931924 -26.54681)
				(xy 128.931924 -26.592276) (xy 129.071624 -26.592276) (xy 129.071624 -26.54681) (xy 129.07137 -26.542238)
				(xy 129.071624 -26.531824) (xy 129.071624 -26.506678)
				(arc
					(start 129.072894 -26.505154)
					(mid 129.133553 -26.322972)
					(end 129.26949 -26.1874)
				)
				(arc
					(start 129.26949 -26.1874)
					(mid 129.792559 -26.141031)
					(end 129.318004 -26.365962)
				)
				(arc
					(start 129.318004 -26.365962)
					(mid 129.262593 -26.44647)
					(end 129.243074 -26.542238)
				)
				(xy 129.24282 -26.54681) (xy 129.24282 -26.592276)
				(arc
					(start 129.53492 -26.592276)
					(mid 129.916174 -26.211403)
					(end 129.535174 -25.830276)
				)
			)
		)
	)
	(zone
		(net "P5V_VBUS_CONN")
		(layer "F.Cu")
		(hatch none 0.5)
		(connect_pads
			(clearance 0.5)
		)
		(min_thickness 0.25)
		(fill yes
			(thermal_gap 0.5)
			(thermal_bridge_width 0.5)
			(island_removal_mode 0)
		)
		(polygon
			(pts
				(xy 85.747606 -19.744944) (xy 83.448906 -22.043644) (xy 83.448906 -28.525978) (xy 83.891374 -28.968446)
				(xy 85.318854 -28.968446) (xy 85.53577 -28.75153) (xy 85.53577 -27.428444) (xy 85.53958 -27.42438)
				(xy 85.53958 -27.38882) (xy 86.0298 -26.8986) (xy 89.1286 -26.8986) (xy 89.316052 -26.711148) (xy 89.316052 -20.442174)
				(xy 88.618822 -19.744944)
			)
		)
		(polygon
			(pts
				(xy 84.1121 -27.5717) (xy 83.9089 -27.5717) (xy 83.9089 -27.7749) (xy 84.1121 -27.7749)
			)
		)
	)
	(zone
		(net "P12V_STBY")
		(layer "F.Cu")
		(hatch none 0.5)
		(connect_pads
			(clearance 0.5)
		)
		(min_thickness 0.25)
		(fill yes
			(thermal_gap 0.5)
			(thermal_bridge_width 0.5)
			(island_removal_mode 0)
		)
		(polygon
			(pts
				(xy 149.387052 -17.072864) (xy 149.039326 -17.42059) (xy 149.039326 -20.135342) (xy 149.340316 -20.436332)
				(xy 151.674068 -20.436332) (xy 151.754332 -20.356068) (xy 151.754332 -18.798032) (xy 152.583642 -17.968722)
				(xy 152.583642 -17.072864)
			)
		)
		(polygon
			(pts
				(xy 151.802338 -17.857978) (xy 151.599138 -17.857978) (xy 151.599138 -18.061178) (xy 151.802338 -18.061178)
			)
		)
	)
	(zone
		(layer "F.Cu")
		(hatch none 0.5)
		(connect_pads
			(clearance 0)
		)
		(min_thickness 0.25)
		(keepout
			(tracks not_allowed)
			(vias allowed)
			(pads allowed)
			(copperpour not_allowed)
			(footprints allowed)
		)
		(placement
			(enabled no)
			(sheetname "")
		)
		(fill
			(thermal_gap 0.5)
			(thermal_bridge_width 0.5)
			(island_removal_mode 0)
		)
		(polygon
			(pts
				(arc
					(start 78.503018 -76.909422)
					(mid 78.122145 -76.528168)
					(end 77.741018 -76.909168)
				)
				(arc
					(start 77.741018 -77.05471)
					(mid 77.806337 -77.02727)
					(end 77.869288 -76.994766)
				)
				(arc
					(start 77.869288 -76.994766)
					(mid 78.332708 -76.745766)
					(end 77.975206 -77.131672)
				)
				(arc
					(start 77.975206 -77.131672)
					(mid 77.861247 -77.190904)
					(end 77.741018 -77.236066)
				)
				(arc
					(start 77.741018 -77.47127)
					(mid 77.861241 -77.516446)
					(end 77.975206 -77.575664)
				)
				(arc
					(start 77.975206 -77.575664)
					(mid 78.332687 -77.961554)
					(end 77.869288 -77.71257)
				)
				(arc
					(start 77.869288 -77.71257)
					(mid 77.80633 -77.680079)
					(end 77.741018 -77.652626)
				)
				(arc
					(start 77.741018 -77.798168)
					(mid 78.122018 -78.179168)
					(end 78.503018 -77.798168)
				)
			)
		)
	)
	(zone
		(layer "F.Cu")
		(hatch none 0.5)
		(connect_pads
			(clearance 0)
		)
		(min_thickness 0.25)
		(keepout
			(tracks allowed)
			(vias allowed)
			(pads allowed)
			(copperpour allowed)
			(footprints allowed)
		)
		(placement
			(enabled no)
			(sheetname "")
		)
		(fill
			(thermal_gap 0.5)
			(thermal_bridge_width 0.5)
			(island_removal_mode 0)
		)
		(polygon
			(pts
				(xy 44.665138 -180.20665) (xy 45.020738 -179.85105) (xy 45.020738 -178.93665) (xy 44.868338 -178.78425)
				(xy 44.868338 -178.70805) (xy 44.792138 -178.63185) (xy 41.566338 -178.63185) (xy 41.337738 -178.86045)
				(xy 41.337738 -179.85105) (xy 42.023538 -180.53685) (xy 44.334938 -180.53685)
			)
		)
	)
	(zone
		(net "P2V5_STBY")
		(layer "F.Cu")
		(hatch none 0.5)
		(connect_pads
			(clearance 0.5)
		)
		(min_thickness 0.25)
		(fill yes
			(thermal_gap 0.5)
			(thermal_bridge_width 0.5)
			(island_removal_mode 0)
		)
		(polygon
			(pts
				(xy 14.744192 -147.295362) (xy 14.523212 -147.516342) (xy 13.803376 -148.249894) (xy 13.803376 -152.106376)
				(xy 19.620738 -157.923738) (xy 20.901406 -157.923738) (xy 23.819866 -160.842198) (xy 26.691844 -160.842198)
				(xy 27.608022 -161.758376) (xy 27.608022 -166.748206) (xy 29.18968 -168.329864) (xy 31.505144 -168.329864)
				(xy 31.700978 -168.13403) (xy 31.700978 -166.275258) (xy 31.456376 -166.030656) (xy 30.576012 -166.030656)
				(xy 29.434536 -164.88918) (xy 29.434536 -159.768794) (xy 29.000196 -159.334454) (xy 25.995376 -159.334454)
				(xy 25.481534 -158.820612) (xy 25.481534 -157.231842) (xy 25.083516 -156.833824) (xy 23.789132 -156.833824)
				(xy 15.637256 -148.683726) (xy 15.637256 -147.622514) (xy 15.310104 -147.295362)
			)
		)
	)
	(zone
		(net "P3V3_STBY_OUT")
		(layer "F.Cu")
		(hatch none 0.5)
		(connect_pads
			(clearance 0.5)
		)
		(min_thickness 0.25)
		(fill yes
			(thermal_gap 0.5)
			(thermal_bridge_width 0.5)
			(island_removal_mode 0)
		)
		(polygon
			(pts
				(xy 58.5724 -180.6956) (xy 58.3692 -180.8988) (xy 58.3692 -181.5084) (xy 58.1914 -181.6862) (xy 52.685696 -181.6862)
				(xy 51.796696 -182.5752) (xy 44.0436 -182.5752) (xy 43.894248 -182.724552) (xy 43.894248 -188.468)
				(xy 44.326048 -188.8998) (xy 59.4868 -188.8998) (xy 59.7916 -188.595) (xy 59.7916 -180.975) (xy 59.5122 -180.6956)
			)
		)
		(polygon
			(pts
				(xy 57.658 -182.2196) (xy 57.4548 -182.2196) (xy 57.4548 -182.4228) (xy 57.658 -182.4228)
			)
		)
		(polygon
			(pts
				(xy 57.0484 -182.2196) (xy 56.8452 -182.2196) (xy 56.8452 -182.4228) (xy 57.0484 -182.4228)
			)
		)
	)
	(zone
		(net "AGND_P3V3_STBY")
		(layer "F.Cu")
		(hatch none 0.5)
		(connect_pads
			(clearance 0.5)
		)
		(min_thickness 0.25)
		(fill yes
			(thermal_gap 0.5)
			(thermal_bridge_width 0.5)
			(island_removal_mode 0)
		)
		(polygon
			(pts
				(xy 28.409646 -173.79061) (xy 28.282646 -173.91761) (xy 28.282646 -176.20361) (xy 28.528518 -176.449482)
				(xy 30.1498 -176.449482) (xy 30.2514 -176.347882) (xy 30.2514 -175.9204) (xy 30.4292 -175.7426)
				(xy 31.5214 -175.7426) (xy 32.545274 -176.766474) (xy 33.338008 -176.766474) (xy 33.655 -176.449482)
				(xy 35.021774 -176.449482) (xy 35.267646 -176.20361) (xy 35.267646 -173.91761) (xy 35.140646 -173.79061)
			)
		)
		(polygon
			(pts
				(xy 29.628846 -175.805338) (xy 29.425646 -175.805338) (xy 29.425646 -176.008538) (xy 29.628846 -176.008538)
			)
		)
		(polygon
			(pts
				(xy 29.171646 -175.805338) (xy 28.968446 -175.805338) (xy 28.968446 -176.008538) (xy 29.171646 -176.008538)
			)
		)
		(polygon
			(pts
				(xy 28.612846 -175.805338) (xy 28.409646 -175.805338) (xy 28.409646 -176.008538) (xy 28.612846 -176.008538)
			)
		)
		(polygon
			(pts
				(xy 31.229046 -175.094138) (xy 31.025846 -175.094138) (xy 31.025846 -175.297338) (xy 31.229046 -175.297338)
			)
		)
		(polygon
			(pts
				(xy 30.670246 -175.094138) (xy 30.467046 -175.094138) (xy 30.467046 -175.297338) (xy 30.670246 -175.297338)
			)
		)
		(polygon
			(pts
				(xy 34.785046 -174.85741) (xy 34.581846 -174.85741) (xy 34.581846 -175.06061) (xy 34.785046 -175.06061)
			)
		)
		(polygon
			(pts
				(xy 34.785046 -174.29861) (xy 34.581846 -174.29861) (xy 34.581846 -174.50181) (xy 34.785046 -174.50181)
			)
		)
	)
	(zone
		(net "GND")
		(layer "F.Cu")
		(hatch none 0.5)
		(connect_pads
			(clearance 0.5)
		)
		(min_thickness 0.25)
		(fill yes
			(thermal_gap 0.5)
			(thermal_bridge_width 0.5)
			(island_removal_mode 0)
		)
		(polygon
			(pts
				(xy 73.43648 -178.73091) (xy 73.43648 -179.37988) (xy 73.27138 -179.54498) (xy 70.80758 -179.54498)
				(xy 70.66788 -179.68468) (xy 70.66788 -180.95468) (xy 70.87108 -181.15788) (xy 73.46188 -181.15788)
				(xy 73.48728 -181.18328) (xy 73.48728 -181.99608) (xy 76.71308 -181.99608) (xy 76.71308 -181.23408)
				(xy 76.76388 -181.18328) (xy 82.83448 -181.18328) (xy 83.08848 -180.92928) (xy 83.08848 -179.10048)
				(xy 82.87258 -178.88458) (xy 82.8548 -178.88458) (xy 82.78622 -178.816) (xy 79.0194 -178.816) (xy 78.9432 -178.8922)
				(xy 78.9432 -179.05476) (xy 78.46568 -179.53228) (xy 76.73848 -179.53228) (xy 76.73848 -178.77028)
				(xy 76.69911 -178.73091)
			)
		)
		(polygon
			(pts
				(xy 79.579216 -180.47208) (xy 79.376016 -180.47208) (xy 79.376016 -180.67528) (xy 79.579216 -180.67528)
			)
		)
		(polygon
			(pts
				(xy 78.969616 -180.47208) (xy 78.766416 -180.47208) (xy 78.766416 -180.67528) (xy 78.969616 -180.67528)
			)
		)
	)
	(zone
		(net "P3V3_STBY")
		(layer "F.Cu")
		(hatch none 0.5)
		(connect_pads
			(clearance 0.5)
		)
		(min_thickness 0.25)
		(fill yes
			(thermal_gap 0.5)
			(thermal_bridge_width 0.5)
			(island_removal_mode 0)
		)
		(polygon
			(pts
				(xy 81.965546 -52.8066) (xy 81.261712 -53.510434) (xy 78.88351 -53.510434) (xy 78.876398 -53.517546)
				(xy 78.876398 -53.945028) (xy 78.92288 -53.99151) (xy 81.349342 -53.99151) (xy 84.152232 -56.7944)
				(xy 90.8304 -56.7944) (xy 90.902028 -56.722772) (xy 90.902028 -53.284628) (xy 90.424 -52.8066)
			)
		)
	)
	(zone
		(layer "F.Cu")
		(hatch none 0.5)
		(connect_pads
			(clearance 0)
		)
		(min_thickness 0.25)
		(keepout
			(tracks not_allowed)
			(vias allowed)
			(pads allowed)
			(copperpour not_allowed)
			(footprints allowed)
		)
		(placement
			(enabled no)
			(sheetname "")
		)
		(fill
			(thermal_gap 0.5)
			(thermal_bridge_width 0.5)
			(island_removal_mode 0)
		)
		(polygon
			(pts
				(arc
					(start 134.585202 -42.800016)
					(mid 134.100062 -42.314876)
					(end 133.614922 -42.800016)
				)
				(arc
					(start 133.614922 -44.19981)
					(mid 134.099935 -44.685204)
					(end 134.585202 -44.200064)
				)
				(xy 134.585202 -43.74134) (xy 134.57936 -43.74134) (xy 134.566152 -43.741594) (xy 134.56158 -43.74134)
				(xy 134.267956 -43.74134)
				(arc
					(start 134.263384 -43.741594)
					(mid 134.209784 -43.76313)
					(end 134.185914 -43.815762)
				)
				(arc
					(start 134.185914 -43.815762)
					(mid 134.100062 -44.593839)
					(end 134.01421 -43.815762)
				)
				(xy 134.014464 -43.81119) (xy 134.014464 -43.783504)
				(arc
					(start 134.017258 -43.78071)
					(mid 134.087246 -43.642926)
					(end 134.22503 -43.572938)
				)
				(xy 134.227824 -43.570144) (xy 134.25551 -43.570144) (xy 134.263384 -43.56989) (xy 134.267956 -43.570144)
				(xy 134.56158 -43.570144) (xy 134.566152 -43.56989) (xy 134.585202 -43.569636) (xy 134.585202 -43.430444)
				(xy 134.575804 -43.430444) (xy 134.566152 -43.430444) (xy 134.56158 -43.430444) (xy 134.26821 -43.430444)
				(xy 134.263638 -43.430444) (xy 134.255764 -43.430444) (xy 134.228078 -43.430444)
				(arc
					(start 134.225284 -43.427396)
					(mid 134.087323 -43.357331)
					(end 134.017258 -43.21937)
				)
				(xy 134.014464 -43.216576) (xy 134.014464 -43.18889)
				(arc
					(start 134.01421 -43.184318)
					(mid 134.100062 -42.406241)
					(end 134.185914 -43.184318)
				)
				(arc
					(start 134.185914 -43.184318)
					(mid 134.209809 -43.23718)
					(end 134.263638 -43.25874)
				)
				(xy 134.26821 -43.25874) (xy 134.56158 -43.25874) (xy 134.566152 -43.25874) (xy 134.585202 -43.257724)
			)
		)
	)
	(zone
		(net "GND")
		(layer "F.Cu")
		(hatch none 0.5)
		(connect_pads
			(clearance 0.5)
		)
		(min_thickness 0.25)
		(fill yes
			(thermal_gap 0.5)
			(thermal_bridge_width 0.5)
			(island_removal_mode 0)
		)
		(polygon
			(pts
				(xy 154.217624 -5.340096) (xy 154.164538 -5.393182) (xy 154.164538 -9.022842) (xy 154.142186 -9.045194)
				(xy 154.142186 -10.179304) (xy 154.235912 -10.27303) (xy 155.073604 -10.27303) (xy 157.100016 -8.246618)
				(xy 157.100016 -7.180326) (xy 157.030166 -7.110476) (xy 155.812236 -7.110476) (xy 155.791408 -7.089648)
				(xy 155.791408 -5.41147) (xy 155.720034 -5.340096)
			)
		)
		(polygon
			(pts
				(xy 155.231338 -8.028178) (xy 155.028138 -8.028178) (xy 155.028138 -8.231378) (xy 155.231338 -8.231378)
			)
		)
		(polygon
			(pts
				(xy 155.231338 -7.164578) (xy 155.028138 -7.164578) (xy 155.028138 -7.367778) (xy 155.231338 -7.367778)
			)
		)
	)
	(zone
		(net "P3V3_M2")
		(layer "F.Cu")
		(hatch none 0.5)
		(connect_pads
			(clearance 0.5)
		)
		(min_thickness 0.25)
		(fill yes
			(thermal_gap 0.5)
			(thermal_bridge_width 0.5)
			(island_removal_mode 0)
		)
		(polygon
			(pts
				(xy 211.754974 -124.847858) (xy 211.530946 -125.071886) (xy 211.530946 -125.526546) (xy 212.1916 -126.1872)
				(xy 212.1916 -128.0414) (xy 212.217 -128.0414) (xy 212.3186 -128.143) (xy 213.6902 -128.143) (xy 213.7664 -128.0668)
				(xy 213.7664 -125.071886) (xy 213.542372 -124.847858)
			)
		)
	)
	(zone
		(net "GND")
		(layer "F.Cu")
		(hatch none 0.5)
		(connect_pads
			(clearance 0.5)
		)
		(min_thickness 0.25)
		(fill yes
			(thermal_gap 0.5)
			(thermal_bridge_width 0.5)
			(island_removal_mode 0)
		)
		(polygon
			(pts
				(xy 222.229426 -14.66088) (xy 215.954356 -20.93595) (xy 215.954356 -30.02915) (xy 216.690448 -30.765242)
				(xy 220.941646 -30.765242) (xy 221.45371 -30.253178) (xy 221.45371 -20.323302) (xy 223.697546 -18.079466)
				(xy 229.075234 -18.079466) (xy 229.122986 -18.031714) (xy 229.122986 -15.20317) (xy 228.580696 -14.66088)
			)
		)
	)
	(zone
		(net "GND")
		(layer "F.Cu")
		(hatch none 0.5)
		(connect_pads
			(clearance 0.5)
		)
		(min_thickness 0.25)
		(fill yes
			(thermal_gap 0.5)
			(thermal_bridge_width 0.5)
			(island_removal_mode 0)
		)
		(polygon
			(pts
				(xy 15.064486 -167.500554) (xy 15.0368 -167.52824) (xy 15.0368 -168.148) (xy 14.8717 -168.3131)
				(xy 12.4079 -168.3131) (xy 12.2682 -168.4528) (xy 12.2682 -169.7228) (xy 12.4714 -169.926) (xy 15.0622 -169.926)
				(xy 15.0876 -169.9514) (xy 15.0876 -170.7642) (xy 18.3134 -170.7642) (xy 18.3134 -170.0022) (xy 18.3642 -169.9514)
				(xy 24.4348 -169.9514) (xy 24.6888 -169.6974) (xy 24.6888 -167.8686) (xy 24.4729 -167.6527) (xy 20.7137 -167.6527)
				(xy 20.066 -168.3004) (xy 18.3388 -168.3004) (xy 18.3388 -167.521636) (xy 18.317718 -167.500554)
			)
		)
		(polygon
			(pts
				(xy 21.179536 -169.2402) (xy 20.976336 -169.2402) (xy 20.976336 -169.4434) (xy 21.179536 -169.4434)
			)
		)
		(polygon
			(pts
				(xy 20.569936 -169.2402) (xy 20.366736 -169.2402) (xy 20.366736 -169.4434) (xy 20.569936 -169.4434)
			)
		)
	)
	(zone
		(layer "F.Cu")
		(hatch none 0.5)
		(connect_pads
			(clearance 0)
		)
		(min_thickness 0.25)
		(keepout
			(tracks allowed)
			(vias allowed)
			(pads allowed)
			(copperpour allowed)
			(footprints not_allowed)
		)
		(placement
			(enabled no)
			(sheetname "")
		)
		(fill
			(thermal_gap 0.5)
			(thermal_bridge_width 0.5)
			(island_removal_mode 0)
		)
		(polygon
			(pts
				(arc
					(start 84.749894 -120.000014)
					(mid 80.000094 -124.749814)
					(end 75.25004 -120.000014)
				)
				(arc
					(start 75.25004 -120.000014)
					(mid 80.000094 -115.24996)
					(end 84.749894 -120.000014)
				)
			)
		)
	)
	(zone
		(net "P5V_STBY")
		(layer "F.Cu")
		(hatch none 0.5)
		(connect_pads
			(clearance 0.5)
		)
		(min_thickness 0.25)
		(fill yes
			(thermal_gap 0.5)
			(thermal_bridge_width 0.5)
			(island_removal_mode 0)
		)
		(polygon
			(pts
				(xy 78.938374 -49.509426) (xy 78.232 -50.2158) (xy 77.36713 -50.2158) (xy 77.2414 -50.34153) (xy 77.2414 -50.80762)
				(xy 77.35951 -50.92573) (xy 78.15453 -50.92573) (xy 78.8162 -51.5874) (xy 81.9404 -51.5874) (xy 82.0928 -51.435)
				(xy 82.0928 -49.7078) (xy 81.894426 -49.509426)
			)
		)
	)
	(zone
		(net "P3V3")
		(layer "F.Cu")
		(hatch none 0.5)
		(connect_pads
			(clearance 0.5)
		)
		(min_thickness 0.25)
		(fill yes
			(thermal_gap 0.5)
			(thermal_bridge_width 0.5)
			(island_removal_mode 0)
		)
		(polygon
			(pts
				(xy 87.0204 -47.1678) (xy 86.36 -47.8282) (xy 85.1408 -47.8282) (xy 84.7598 -48.2092) (xy 84.7598 -51.3588)
				(xy 85.0646 -51.6636) (xy 89.6366 -51.6636) (xy 89.7128 -51.5874) (xy 89.7128 -50.0126) (xy 89.6366 -49.9364)
				(xy 88.7984 -49.9364) (xy 88.6206 -49.7586) (xy 88.6206 -47.6758) (xy 88.1126 -47.1678)
			)
		)
		(polygon
			(pts
				(xy 88.158828 -49.346612) (xy 87.955628 -49.346612) (xy 87.955628 -49.549812) (xy 88.158828 -49.549812)
			)
		)
		(polygon
			(pts
				(xy 88.158828 -48.787812) (xy 87.955628 -48.787812) (xy 87.955628 -48.991012) (xy 88.158828 -48.991012)
			)
		)
		(polygon
			(pts
				(xy 88.108028 -48.406812) (xy 87.904828 -48.406812) (xy 87.904828 -48.610012) (xy 88.108028 -48.610012)
			)
		)
		(polygon
			(pts
				(xy 88.108028 -47.797212) (xy 87.904828 -47.797212) (xy 87.904828 -48.000412) (xy 88.108028 -48.000412)
			)
		)
	)
	(zone
		(net "GND")
		(layer "F.Cu")
		(hatch none 0.5)
		(connect_pads
			(clearance 0.5)
		)
		(min_thickness 0.25)
		(fill yes
			(thermal_gap 0.5)
			(thermal_bridge_width 0.5)
			(island_removal_mode 0)
		)
		(polygon
			(pts
				(xy 187.9346 -132.5118) (xy 187.579 -132.8674) (xy 187.579 -135.89) (xy 187.3504 -136.1186) (xy 187.3504 -136.4234)
				(xy 187.4774 -136.5504) (xy 190.5508 -136.5504) (xy 190.7794 -136.3218) (xy 190.7794 -132.7912)
				(xy 190.5 -132.5118)
			)
		)
	)
	(zone
		(layer "F.Cu")
		(hatch none 0.5)
		(connect_pads
			(clearance 0)
		)
		(min_thickness 0.25)
		(keepout
			(tracks allowed)
			(vias allowed)
			(pads allowed)
			(copperpour allowed)
			(footprints allowed)
		)
		(placement
			(enabled no)
			(sheetname "")
		)
		(fill
			(thermal_gap 0.5)
			(thermal_bridge_width 0.5)
			(island_removal_mode 0)
		)
		(polygon
			(pts
				(xy 35.7632 -173.5836) (xy 35.7632 -175.8696) (xy 35.9156 -176.022) (xy 37.0332 -176.022) (xy 37.1856 -175.8696)
				(xy 37.1856 -173.7868) (xy 36.83 -173.4312) (xy 35.9156 -173.4312)
			)
		)
	)
	(zone
		(layer "F.Cu")
		(hatch none 0.5)
		(connect_pads
			(clearance 0)
		)
		(min_thickness 0.25)
		(keepout
			(tracks allowed)
			(vias allowed)
			(pads allowed)
			(copperpour allowed)
			(footprints allowed)
		)
		(placement
			(enabled no)
			(sheetname "")
		)
		(fill
			(thermal_gap 0.5)
			(thermal_bridge_width 0.5)
			(island_removal_mode 0)
		)
		(polygon
			(pts
				(xy 155.053284 -12.472162) (xy 156.221684 -12.472162) (xy 156.374084 -12.319762) (xy 156.374084 -11.519662)
				(xy 156.196284 -11.341862) (xy 154.964384 -11.341862) (xy 154.900884 -11.405362) (xy 154.900884 -12.319762)
			)
		)
	)
	(zone
		(layer "F.Cu")
		(hatch none 0.5)
		(connect_pads
			(clearance 0)
		)
		(min_thickness 0.25)
		(keepout
			(tracks not_allowed)
			(vias allowed)
			(pads allowed)
			(copperpour not_allowed)
			(footprints allowed)
		)
		(placement
			(enabled no)
			(sheetname "")
		)
		(fill
			(thermal_gap 0.5)
			(thermal_bridge_width 0.5)
			(island_removal_mode 0)
		)
		(polygon
			(pts
				(arc
					(start 37.69995 -169.999914)
					(mid 41.450006 -166.249858)
					(end 45.200062 -169.999914)
				)
				(arc
					(start 45.200062 -169.999914)
					(mid 41.450006 -173.74997)
					(end 37.69995 -169.999914)
				)
			)
		)
	)
	(zone
		(net "GND")
		(layer "F.Cu")
		(hatch none 0.5)
		(connect_pads
			(clearance 0.5)
		)
		(min_thickness 0.25)
		(fill yes
			(thermal_gap 0.5)
			(thermal_bridge_width 0.5)
			(island_removal_mode 0)
		)
		(polygon
			(pts
				(xy 23.511256 -170.282616) (xy 23.328376 -170.465496) (xy 23.328376 -174.317914) (xy 23.54707 -174.536608)
				(xy 25.598628 -174.536608) (xy 25.81148 -174.323756) (xy 25.81148 -170.414442) (xy 25.679654 -170.282616)
			)
		)
	)
	(zone
		(layer "F.Cu")
		(hatch none 0.5)
		(connect_pads
			(clearance 0)
		)
		(min_thickness 0.25)
		(keepout
			(tracks allowed)
			(vias allowed)
			(pads allowed)
			(copperpour allowed)
			(footprints allowed)
		)
		(placement
			(enabled no)
			(sheetname "")
		)
		(fill
			(thermal_gap 0.5)
			(thermal_bridge_width 0.5)
			(island_removal_mode 0)
		)
		(polygon
			(pts
				(xy 36.6014 -181.229) (xy 36.6014 -179.4256) (xy 36.576 -179.4002) (xy 36.576 -178.6636) (xy 37.9222 -177.3174)
				(xy 38.608 -177.3174) (xy 38.8874 -177.5968) (xy 38.8874 -178.7652) (xy 38.4302 -179.2224) (xy 38.4302 -179.5272)
				(xy 38.4302 -181.229)
			)
		)
	)
	(zone
		(net "P5V_STBY")
		(layer "F.Cu")
		(hatch none 0.5)
		(connect_pads
			(clearance 0.5)
		)
		(min_thickness 0.25)
		(fill yes
			(thermal_gap 0.5)
			(thermal_bridge_width 0.5)
			(island_removal_mode 0)
		)
		(polygon
			(pts
				(xy 223.628712 -18.723356) (xy 221.946978 -20.40509) (xy 221.946978 -34.636202) (xy 222.340932 -35.030156)
				(xy 229.541324 -35.030156) (xy 230.061008 -34.510472) (xy 230.061008 -18.807176) (xy 229.977188 -18.723356)
			)
		)
	)
	(zone
		(layer "F.Cu")
		(hatch none 0.5)
		(connect_pads
			(clearance 0)
		)
		(min_thickness 0.25)
		(keepout
			(tracks allowed)
			(vias allowed)
			(pads allowed)
			(copperpour allowed)
			(footprints allowed)
		)
		(placement
			(enabled no)
			(sheetname "")
		)
		(fill
			(thermal_gap 0.5)
			(thermal_bridge_width 0.5)
			(island_removal_mode 0)
		)
		(polygon
			(pts
				(xy 24.63673 -150.308564) (xy 24.63673 -132.833364) (xy 15.08633 -132.833364) (xy 15.08633 -150.308564)
			)
		)
	)
	(zone
		(layer "F.Cu")
		(hatch none 0.5)
		(connect_pads
			(clearance 0)
		)
		(min_thickness 0.25)
		(keepout
			(tracks allowed)
			(vias allowed)
			(pads allowed)
			(copperpour allowed)
			(footprints allowed)
		)
		(placement
			(enabled no)
			(sheetname "")
		)
		(fill
			(thermal_gap 0.5)
			(thermal_bridge_width 0.5)
			(island_removal_mode 0)
		)
		(polygon
			(pts
				(xy 93.98 -177.6222) (xy 93.98 -179.9082) (xy 94.1324 -180.0606) (xy 94.1578 -180.0606) (xy 94.3356 -180.2384)
				(xy 95.6818 -180.2384) (xy 95.8723 -180.0479) (xy 96.012 -179.9082) (xy 96.012 -178.435) (xy 95.4024 -177.8254)
				(xy 95.0468 -177.4698) (xy 94.1324 -177.4698)
			)
		)
	)
	(zone
		(layer "F.Cu")
		(hatch none 0.5)
		(connect_pads
			(clearance 0)
		)
		(min_thickness 0.25)
		(keepout
			(tracks allowed)
			(vias allowed)
			(pads allowed)
			(copperpour allowed)
			(footprints allowed)
		)
		(placement
			(enabled no)
			(sheetname "")
		)
		(fill
			(thermal_gap 0.5)
			(thermal_bridge_width 0.5)
			(island_removal_mode 0)
		)
		(polygon
			(pts
				(xy 120.719342 -6.619494) (xy 122.573542 -6.619494) (xy 122.573542 -10.8712) (xy 120.719342 -10.8712)
			)
		)
	)
	(zone
		(layer "F.Cu")
		(hatch none 0.5)
		(connect_pads
			(clearance 0)
		)
		(min_thickness 0.25)
		(keepout
			(tracks allowed)
			(vias allowed)
			(pads allowed)
			(copperpour allowed)
			(footprints allowed)
		)
		(placement
			(enabled no)
			(sheetname "")
		)
		(fill
			(thermal_gap 0.5)
			(thermal_bridge_width 0.5)
			(island_removal_mode 0)
		)
		(polygon
			(pts
				(xy 197.7898 -128.2446) (xy 199.9234 -128.2446) (xy 200.0758 -128.0922) (xy 200.0758 -126.4666)
				(xy 199.8218 -126.2126) (xy 198.0692 -126.2126) (xy 197.3834 -126.2126) (xy 197.2056 -126.3904)
				(xy 197.2056 -128.1684) (xy 197.2818 -128.2446)
			)
		)
	)
	(zone
		(net "GND")
		(layer "F.Cu")
		(hatch none 0.5)
		(connect_pads
			(clearance 0.5)
		)
		(min_thickness 0.25)
		(fill yes
			(thermal_gap 0.5)
			(thermal_bridge_width 0.5)
			(island_removal_mode 0)
		)
		(polygon
			(pts
				(xy 153.230326 -10.586974) (xy 153.087832 -10.729468) (xy 153.087832 -12.169394) (xy 153.175716 -12.257278)
				(xy 154.69489 -12.257278) (xy 154.754834 -12.197334) (xy 154.754834 -10.680954) (xy 154.660854 -10.586974)
			)
		)
	)
	(zone
		(net "P12V_IOM")
		(layer "F.Cu")
		(hatch none 0.5)
		(connect_pads
			(clearance 0.5)
		)
		(min_thickness 0.25)
		(fill yes
			(thermal_gap 0.5)
			(thermal_bridge_width 0.5)
			(island_removal_mode 0)
		)
		(polygon
			(pts
				(xy 137.175748 -13.176758) (xy 137.139426 -13.21308) (xy 137.139426 -15.150338) (xy 136.694164 -15.5956)
				(xy 130.77571 -15.5956) (xy 130.644138 -15.464028) (xy 129.484374 -15.46606) (xy 127.34798 -17.602454)
				(xy 124.945902 -17.602454) (xy 124.388372 -18.159984) (xy 124.388372 -20.594828) (xy 124.634244 -20.840446)
				(xy 129.777744 -20.840446) (xy 130.404362 -20.213828) (xy 130.404362 -18.762218) (xy 130.92176 -18.24482)
				(xy 139.480798 -18.24482) (xy 139.783312 -17.942306) (xy 139.783312 -13.307314) (xy 139.652756 -13.176758)
			)
		)
		(polygon
			(pts
				(xy 137.466832 -17.917414) (xy 137.263632 -17.917414) (xy 137.263632 -18.120614) (xy 137.466832 -18.120614)
			)
		)
		(polygon
			(pts
				(xy 136.603232 -17.917414) (xy 136.400032 -17.917414) (xy 136.400032 -18.120614) (xy 136.603232 -18.120614)
			)
		)
		(polygon
			(pts
				(xy 137.466832 -17.053814) (xy 137.263632 -17.053814) (xy 137.263632 -17.257014) (xy 137.466832 -17.257014)
			)
		)
		(polygon
			(pts
				(xy 136.603232 -17.053814) (xy 136.400032 -17.053814) (xy 136.400032 -17.257014) (xy 136.603232 -17.257014)
			)
		)
		(polygon
			(pts
				(xy 139.2936 -15.748) (xy 139.0904 -15.748) (xy 139.0904 -15.9512) (xy 139.2936 -15.9512)
			)
		)
		(polygon
			(pts
				(xy 139.2936 -15.1384) (xy 139.0904 -15.1384) (xy 139.0904 -15.3416) (xy 139.2936 -15.3416)
			)
		)
	)
	(zone
		(layer "F.Cu")
		(hatch none 0.5)
		(connect_pads
			(clearance 0)
		)
		(min_thickness 0.25)
		(keepout
			(tracks allowed)
			(vias allowed)
			(pads allowed)
			(copperpour allowed)
			(footprints not_allowed)
		)
		(placement
			(enabled no)
			(sheetname "")
		)
		(fill
			(thermal_gap 0.5)
			(thermal_bridge_width 0.5)
			(island_removal_mode 0)
		)
		(polygon
			(pts
				(xy 198.399908 -40.25011)
				(arc
					(start 198.399908 -51.250088)
					(mid 204.399896 -57.250076)
					(end 210.399884 -51.250088)
				)
				(xy 210.399884 -40.25011)
			)
		)
	)
	(zone
		(net "GND")
		(layer "F.Cu")
		(hatch none 0.5)
		(connect_pads
			(clearance 0.5)
		)
		(min_thickness 0.25)
		(fill yes
			(thermal_gap 0.5)
			(thermal_bridge_width 0.5)
			(island_removal_mode 0)
		)
		(polygon
			(pts
				(xy 228.34346 -49.981866) (xy 228.32949 -49.995836) (xy 226.877626 -49.995836) (xy 226.598988 -50.274728)
				(xy 226.574096 -50.29962) (xy 226.574096 -52.104036) (xy 226.243896 -52.434236) (xy 226.243896 -56.101234)
				(xy 226.5299 -56.387492) (xy 230.153972 -56.387492) (xy 230.403908 -56.137556) (xy 230.403908 -55.814214)
				(xy 230.402384 -55.81269) (xy 230.402384 -50.842672) (xy 229.541578 -49.981866)
			)
		)
	)
	(zone
		(net "P1V2_STBY")
		(layer "F.Cu")
		(hatch none 0.5)
		(connect_pads
			(clearance 0.5)
		)
		(min_thickness 0.25)
		(fill yes
			(thermal_gap 0.5)
			(thermal_bridge_width 0.5)
			(island_removal_mode 0)
		)
		(polygon
			(pts
				(xy 19.0754 -158.369) (xy 18.8976 -158.5468) (xy 18.8976 -160.309814) (xy 19.369786 -160.782) (xy 20.7264 -160.782)
				(xy 21.1328 -160.3756) (xy 21.1328 -158.6484) (xy 20.8534 -158.369)
			)
		)
	)
	(zone
		(layer "F.Cu")
		(hatch none 0.5)
		(connect_pads
			(clearance 0)
		)
		(min_thickness 0.25)
		(keepout
			(tracks allowed)
			(vias allowed)
			(pads allowed)
			(copperpour allowed)
			(footprints not_allowed)
		)
		(placement
			(enabled no)
			(sheetname "")
		)
		(fill
			(thermal_gap 0.5)
			(thermal_bridge_width 0.5)
			(island_removal_mode 0)
		)
		(polygon
			(pts
				(arc
					(start 144.549876 -78.000098)
					(mid 149.29993 -73.250044)
					(end 154.049984 -78.000098)
				)
				(arc
					(start 154.049984 -78.000098)
					(mid 149.29993 -82.750152)
					(end 144.549876 -78.000098)
				)
			)
		)
	)
	(zone
		(net "GND")
		(layer "F.Cu")
		(hatch none 0.5)
		(connect_pads
			(clearance 0.5)
		)
		(min_thickness 0.25)
		(fill yes
			(thermal_gap 0.5)
			(thermal_bridge_width 0.5)
			(island_removal_mode 0)
		)
		(polygon
			(pts
				(xy 55.372 -162.8394) (xy 55.3466 -162.8648) (xy 55.3466 -163.322) (xy 55.0926 -163.576) (xy 52.6288 -163.576)
				(xy 52.5272 -163.6776) (xy 52.5272 -165.1254) (xy 53.3146 -165.9128) (xy 55.7784 -165.9128) (xy 56.0324 -165.6588)
				(xy 56.0324 -162.8902) (xy 55.9816 -162.8394)
			)
		)
		(polygon
			(pts
				(xy 54.920642 -165.251384) (xy 54.717442 -165.251384) (xy 54.717442 -165.454584) (xy 54.920642 -165.454584)
			)
		)
		(polygon
			(pts
				(xy 54.361842 -165.251384) (xy 54.158642 -165.251384) (xy 54.158642 -165.454584) (xy 54.361842 -165.454584)
			)
		)
		(polygon
			(pts
				(xy 55.327042 -165.213284) (xy 55.123842 -165.213284) (xy 55.123842 -165.416484) (xy 55.327042 -165.416484)
			)
		)
	)
	(zone
		(net "V1PLLAV11")
		(layer "F.Cu")
		(hatch none 0.5)
		(connect_pads
			(clearance 0.5)
		)
		(min_thickness 0.25)
		(fill yes
			(thermal_gap 0.5)
			(thermal_bridge_width 0.5)
			(island_removal_mode 0)
		)
		(polygon
			(pts
				(xy 34.6202 -161.2392) (xy 34.544 -161.3154) (xy 32.131 -161.3154) (xy 32.126936 -161.319464) (xy 30.14599 -161.319464)
				(xy 29.972 -161.493454) (xy 29.972 -162.5092) (xy 30.0482 -162.5854) (xy 35.2044 -162.5854) (xy 35.4076 -162.3822)
				(xy 35.4076 -161.2392)
			)
		)
		(polygon
			(pts
				(xy 31.6738 -161.8742) (xy 31.4706 -161.8742) (xy 31.4706 -162.0774) (xy 31.6738 -162.0774)
			)
		)
		(polygon
			(pts
				(xy 31.0642 -161.8742) (xy 30.861 -161.8742) (xy 30.861 -162.0774) (xy 31.0642 -162.0774)
			)
		)
		(polygon
			(pts
				(xy 30.734 -161.8742) (xy 30.5308 -161.8742) (xy 30.5308 -162.0774) (xy 30.734 -162.0774)
			)
		)
		(polygon
			(pts
				(xy 32.8676 -161.4424) (xy 32.6644 -161.4424) (xy 32.6644 -161.6456) (xy 32.8676 -161.6456)
			)
		)
		(polygon
			(pts
				(xy 32.004 -161.4424) (xy 31.8008 -161.4424) (xy 31.8008 -161.6456) (xy 32.004 -161.6456)
			)
		)
	)
	(zone
		(layer "F.Cu")
		(hatch none 0.5)
		(connect_pads
			(clearance 0)
		)
		(min_thickness 0.25)
		(keepout
			(tracks allowed)
			(vias allowed)
			(pads allowed)
			(copperpour allowed)
			(footprints allowed)
		)
		(placement
			(enabled no)
			(sheetname "")
		)
		(fill
			(thermal_gap 0.5)
			(thermal_bridge_width 0.5)
			(island_removal_mode 0)
		)
		(polygon
			(pts
				(xy 92.4052 -129.5908) (xy 92.4052 -130.3782) (xy 90.551 -130.3782) (xy 90.2462 -130.3782) (xy 89.9414 -130.0734)
				(xy 89.9414 -128.397) (xy 92.2528 -128.397) (xy 92.4052 -128.5494) (xy 92.4052 -128.9558)
			)
		)
	)
	(zone
		(layer "F.Cu")
		(hatch none 0.5)
		(connect_pads
			(clearance 0)
		)
		(min_thickness 0.25)
		(keepout
			(tracks allowed)
			(vias allowed)
			(pads allowed)
			(copperpour allowed)
			(footprints not_allowed)
		)
		(placement
			(enabled no)
			(sheetname "")
		)
		(fill
			(thermal_gap 0.5)
			(thermal_bridge_width 0.5)
			(island_removal_mode 0)
		)
		(polygon
			(pts
				(xy 185.399934 -40.25011) (xy 173.399958 -40.25011)
				(arc
					(start 173.399958 -51.250088)
					(mid 179.399946 -57.250076)
					(end 185.399934 -51.250088)
				)
			)
		)
	)
	(zone
		(layer "F.Cu")
		(hatch none 0.5)
		(connect_pads
			(clearance 0)
		)
		(min_thickness 0.25)
		(keepout
			(tracks allowed)
			(vias allowed)
			(pads allowed)
			(copperpour allowed)
			(footprints not_allowed)
		)
		(placement
			(enabled no)
			(sheetname "")
		)
		(fill
			(thermal_gap 0.5)
			(thermal_bridge_width 0.5)
			(island_removal_mode 0)
		)
		(polygon
			(pts
				(xy 213.19998 -145.999962) (xy 203.2 -145.999962) (xy 203.2 -155.999942) (xy 213.19998 -155.999942)
			)
		)
	)
	(zone
		(layers "F.Cu" "B.Cu")
		(hatch none 0.5)
		(connect_pads
			(clearance 0)
		)
		(min_thickness 0.25)
		(keepout
			(tracks allowed)
			(vias allowed)
			(pads allowed)
			(copperpour allowed)
			(footprints allowed)
		)
		(placement
			(enabled no)
			(sheetname "")
		)
		(fill yes
			(thermal_gap 0.5)
			(thermal_bridge_width 0.5)
			(island_removal_mode 0)
		)
		(polygon
			(pts
				(xy 216.759536 -39.83101) (xy 218.272106 -39.83101) (xy 218.34094 -39.762176) (xy 218.34094 -39.41318)
				(xy 218.259914 -39.332154) (xy 216.747598 -39.332154) (xy 216.654126 -39.425626) (xy 216.654126 -39.7256)
			)
		)
	)
	(zone
		(layers "F.Cu" "B.Cu" "In1.Cu" "In2.Cu" "In3.Cu" "In4.Cu" "In5.Cu" "In6.Cu")
		(hatch none 0.5)
		(connect_pads
			(clearance 0)
		)
		(min_thickness 0.25)
		(keepout
			(tracks not_allowed)
			(vias allowed)
			(pads allowed)
			(copperpour not_allowed)
			(footprints allowed)
		)
		(placement
			(enabled no)
			(sheetname "")
		)
		(fill yes
			(thermal_gap 0.5)
			(thermal_bridge_width 0.5)
			(island_removal_mode 0)
		)
		(polygon
			(pts
				(arc
					(start 144.549876 -78.000098)
					(mid 149.29993 -73.250044)
					(end 154.049984 -78.000098)
				)
				(arc
					(start 154.049984 -78.000098)
					(mid 149.29993 -82.750152)
					(end 144.549876 -78.000098)
				)
			)
		)
	)
	(zone
		(layers "F.Cu" "B.Cu" "In1.Cu" "In2.Cu" "In3.Cu" "In4.Cu" "In5.Cu" "In6.Cu")
		(name "Route Keepin")
		(hatch none 0.5)
		(connect_pads
			(clearance 0)
		)
		(min_thickness 0.25)
		(keepout
			(tracks allowed)
			(vias allowed)
			(pads allowed)
			(copperpour allowed)
			(footprints allowed)
		)
		(placement
			(enabled no)
			(sheetname "")
		)
		(fill
			(thermal_gap 0.5)
			(thermal_bridge_width 0.5)
			(island_removal_mode 0)
		)
		(polygon
			(pts
				(arc
					(start 5.40512 -193.106548)
					(mid 5.492861 -193.202556)
					(end 5.617972 -193.23812)
				)
				(arc
					(start 98.081846 -193.23812)
					(mid 98.207115 -193.202642)
					(end 98.294952 -193.106548)
				)
				(arc
					(start 102.912926 -183.870346)
					(mid 102.931684 -183.818596)
					(end 102.938072 -183.76392)
				)
				(arc
					(start 102.938072 -47.999904)
					(mid 103.798188 -46.803514)
					(end 105.206038 -47.237904)
				)
				(arc
					(start 142.793974 -47.237904)
					(mid 144.201748 -46.80374)
					(end 145.06194 -47.999904)
				)
				(arc
					(start 145.06194 -149.763734)
					(mid 145.068307 -149.818415)
					(end 145.087086 -149.87016)
				)
				(arc
					(start 149.70506 -159.106362)
					(mid 149.792801 -159.20237)
					(end 149.917912 -159.237934)
				)
				(arc
					(start 214.00008 -159.237934)
					(mid 215.246001 -159.754011)
					(end 215.762078 -160.999932)
				)
				(arc
					(start 215.762078 -193.000122)
					(mid 215.831786 -193.168412)
					(end 216.000076 -193.23812)
				)
				(arc
					(start 229.382066 -193.23812)
					(mid 229.507189 -193.202575)
					(end 229.594918 -193.106548)
				)
				(arc
					(start 234.212892 -183.870346)
					(mid 234.23165 -183.818596)
					(end 234.238038 -183.76392)
				)
				(arc
					(start 234.238038 -0.999998)
					(mid 234.16833 -0.831708)
					(end 234.00004 -0.762)
				)
				(arc
					(start 74.030078 -0.762)
					(mid 73.861788 -0.831708)
					(end 73.79208 -0.999998)
				)
				(arc
					(start 73.79208 -109.050074)
					(mid 73.276003 -110.295995)
					(end 72.030082 -110.812072)
				)
				(arc
					(start 31.530036 -110.812072)
					(mid 30.284115 -110.295995)
					(end 29.768038 -109.050074)
				)
				(arc
					(start 29.768038 -0.999998)
					(mid 29.69833 -0.831708)
					(end 29.53004 -0.762)
				)
				(arc
					(start 0.999998 -0.762)
					(mid 0.831708 -0.831708)
					(end 0.762 -0.999998)
				)
				(arc
					(start 0.762 -183.76392)
					(mid 0.768367 -183.818601)
					(end 0.787146 -183.870346)
				)
			)
		)
	)
	(zone
		(layers "F.Cu" "B.Cu" "In1.Cu" "In2.Cu" "In3.Cu" "In4.Cu" "In5.Cu" "In6.Cu")
		(name "Package Keepin")
		(hatch none 0.5)
		(connect_pads
			(clearance 0)
		)
		(min_thickness 0.25)
		(keepout
			(tracks allowed)
			(vias allowed)
			(pads allowed)
			(copperpour allowed)
			(footprints allowed)
		)
		(placement
			(enabled no)
			(sheetname "")
		)
		(fill
			(thermal_gap 0.5)
			(thermal_bridge_width 0.5)
			(island_removal_mode 0)
		)
		(polygon
			(pts
				(xy 8.092694 -188.99632) (xy 95.607378 -188.99632) (xy 98.696272 -182.818532)
				(arc
					(start 98.696272 -47.99965)
					(mid 101.227215 -43.367996)
					(end 106.49204 -42.996104)
				)
				(arc
					(start 141.507972 -42.996104)
					(mid 146.772667 -43.368198)
					(end 149.30374 -47.99965)
				)
				(xy 149.30374 -148.8186) (xy 152.39238 -154.996134)
				(arc
					(start 214.00008 -154.996134)
					(mid 218.245406 -156.754606)
					(end 220.003878 -160.999932)
				)
				(xy 220.003878 -188.99632) (xy 226.907344 -188.99632) (xy 229.996238 -182.818532) (xy 229.996238 -5.0038)
				(xy 78.03388 -5.0038)
				(arc
					(start 78.03388 -109.050074)
					(mid 76.275408 -113.2954)
					(end 72.030082 -115.053872)
				)
				(arc
					(start 31.530036 -115.053872)
					(mid 27.28471 -113.2954)
					(end 25.526238 -109.050074)
				)
				(xy 25.526238 -5.0038) (xy 5.0038 -5.0038) (xy 5.0038 -182.818532)
			)
		)
	)
	(zone
		(layers "F.Cu" "B.Cu" "In2.Cu")
		(hatch none 0.5)
		(connect_pads
			(clearance 0)
		)
		(min_thickness 0.25)
		(keepout
			(tracks not_allowed)
			(vias allowed)
			(pads allowed)
			(copperpour not_allowed)
			(footprints allowed)
		)
		(placement
			(enabled no)
			(sheetname "")
		)
		(fill yes
			(thermal_gap 0.5)
			(thermal_bridge_width 0.5)
			(island_removal_mode 0)
		)
		(polygon
			(pts
				(arc
					(start 116.584984 -35.600132)
					(mid 116.099844 -35.114992)
					(end 115.614704 -35.600132)
				)
				(arc
					(start 115.614704 -36.999926)
					(mid 116.098447 -37.485318)
					(end 116.584984 -37.00272)
				)
				(arc
					(start 116.493544 -37.00272)
					(mid 116.099844 -37.393888)
					(end 115.706144 -37.00272)
				)
				(arc
					(start 115.706144 -37.00018)
					(mid 116.099844 -36.60648)
					(end 116.493544 -37.00018)
				)
				(xy 116.584984 -37.00018) (xy 116.584984 -35.602672)
				(arc
					(start 116.493544 -35.602672)
					(mid 116.099844 -35.99384)
					(end 115.706144 -35.602672)
				)
				(arc
					(start 115.706144 -35.600132)
					(mid 116.099844 -35.206432)
					(end 116.493544 -35.600132)
				)
			)
		)
	)
	(zone
		(layers "F.Cu" "B.Cu" "In2.Cu")
		(hatch none 0.5)
		(connect_pads
			(clearance 0)
		)
		(min_thickness 0.25)
		(keepout
			(tracks not_allowed)
			(vias allowed)
			(pads allowed)
			(copperpour not_allowed)
			(footprints allowed)
		)
		(placement
			(enabled no)
			(sheetname "")
		)
		(fill yes
			(thermal_gap 0.5)
			(thermal_bridge_width 0.5)
			(island_removal_mode 0)
		)
		(polygon
			(pts
				(arc
					(start 111.185198 -36.800028)
					(mid 110.700058 -36.314888)
					(end 110.214918 -36.800028)
				)
				(arc
					(start 110.214918 -38.199822)
					(mid 110.698661 -38.685214)
					(end 111.185198 -38.202616)
				)
				(arc
					(start 111.093758 -38.202616)
					(mid 110.700058 -38.593784)
					(end 110.306358 -38.202616)
				)
				(arc
					(start 110.306358 -38.200076)
					(mid 110.700058 -37.806376)
					(end 111.093758 -38.200076)
				)
				(xy 111.185198 -38.200076) (xy 111.185198 -36.802568)
				(arc
					(start 111.093758 -36.802568)
					(mid 110.700058 -37.193736)
					(end 110.306358 -36.802568)
				)
				(arc
					(start 110.306358 -36.800028)
					(mid 110.700058 -36.406328)
					(end 111.093758 -36.800028)
				)
			)
		)
	)
	(zone
		(layers "F.Cu" "B.Cu" "In2.Cu")
		(hatch none 0.5)
		(connect_pads
			(clearance 0)
		)
		(min_thickness 0.25)
		(keepout
			(tracks not_allowed)
			(vias allowed)
			(pads allowed)
			(copperpour not_allowed)
			(footprints allowed)
		)
		(placement
			(enabled no)
			(sheetname "")
		)
		(fill yes
			(thermal_gap 0.5)
			(thermal_bridge_width 0.5)
			(island_removal_mode 0)
		)
		(polygon
			(pts
				(arc
					(start 118.385082 -36.800028)
					(mid 117.899942 -36.314888)
					(end 117.414802 -36.800028)
				)
				(arc
					(start 117.414802 -38.199822)
					(mid 117.898545 -38.685214)
					(end 118.385082 -38.202616)
				)
				(arc
					(start 118.293642 -38.202616)
					(mid 117.899942 -38.593784)
					(end 117.506242 -38.202616)
				)
				(arc
					(start 117.506242 -38.200076)
					(mid 117.899942 -37.806376)
					(end 118.293642 -38.200076)
				)
				(xy 118.385082 -38.200076) (xy 118.385082 -36.802568)
				(arc
					(start 118.293642 -36.802568)
					(mid 117.899942 -37.193736)
					(end 117.506242 -36.802568)
				)
				(arc
					(start 117.506242 -36.800028)
					(mid 117.899942 -36.406328)
					(end 118.293642 -36.800028)
				)
			)
		)
	)
	(zone
		(layers "F.Cu" "B.Cu" "In2.Cu")
		(hatch none 0.5)
		(connect_pads
			(clearance 0)
		)
		(min_thickness 0.25)
		(keepout
			(tracks not_allowed)
			(vias allowed)
			(pads allowed)
			(copperpour not_allowed)
			(footprints allowed)
		)
		(placement
			(enabled no)
			(sheetname "")
		)
		(fill yes
			(thermal_gap 0.5)
			(thermal_bridge_width 0.5)
			(island_removal_mode 0)
		)
		(polygon
			(pts
				(arc
					(start 120.18518 -35.600132)
					(mid 119.70004 -35.114992)
					(end 119.2149 -35.600132)
				)
				(arc
					(start 119.2149 -36.999926)
					(mid 119.698643 -37.485318)
					(end 120.18518 -37.00272)
				)
				(arc
					(start 120.09374 -37.00272)
					(mid 119.70004 -37.393888)
					(end 119.30634 -37.00272)
				)
				(arc
					(start 119.30634 -37.00018)
					(mid 119.70004 -36.60648)
					(end 120.09374 -37.00018)
				)
				(xy 120.18518 -37.00018) (xy 120.18518 -35.602672)
				(arc
					(start 120.09374 -35.602672)
					(mid 119.70004 -35.99384)
					(end 119.30634 -35.602672)
				)
				(arc
					(start 119.30634 -35.600132)
					(mid 119.70004 -35.206432)
					(end 120.09374 -35.600132)
				)
			)
		)
	)
	(zone
		(layers "F.Cu" "B.Cu" "In2.Cu")
		(hatch none 0.5)
		(connect_pads
			(clearance 0)
		)
		(min_thickness 0.25)
		(keepout
			(tracks not_allowed)
			(vias allowed)
			(pads allowed)
			(copperpour not_allowed)
			(footprints allowed)
		)
		(placement
			(enabled no)
			(sheetname "")
		)
		(fill yes
			(thermal_gap 0.5)
			(thermal_bridge_width 0.5)
			(island_removal_mode 0)
		)
		(polygon
			(pts
				(arc
					(start 141.785086 -42.800016)
					(mid 141.299946 -42.314876)
					(end 140.814806 -42.800016)
				)
				(arc
					(start 140.814806 -44.19981)
					(mid 141.298549 -44.685202)
					(end 141.785086 -44.202604)
				)
				(arc
					(start 141.693646 -44.202604)
					(mid 141.299946 -44.593772)
					(end 140.906246 -44.202604)
				)
				(arc
					(start 140.906246 -44.200064)
					(mid 141.299946 -43.806364)
					(end 141.693646 -44.200064)
				)
				(xy 141.785086 -44.200064) (xy 141.785086 -42.802556)
				(arc
					(start 141.693646 -42.802556)
					(mid 141.299946 -43.193724)
					(end 140.906246 -42.802556)
				)
				(arc
					(start 140.906246 -42.800016)
					(mid 141.299946 -42.406316)
					(end 141.693646 -42.800016)
				)
			)
		)
	)
	(zone
		(layers "F.Cu" "B.Cu" "In2.Cu")
		(hatch none 0.5)
		(connect_pads
			(clearance 0)
		)
		(min_thickness 0.25)
		(keepout
			(tracks not_allowed)
			(vias allowed)
			(pads allowed)
			(copperpour not_allowed)
			(footprints allowed)
		)
		(placement
			(enabled no)
			(sheetname "")
		)
		(fill yes
			(thermal_gap 0.5)
			(thermal_bridge_width 0.5)
			(island_removal_mode 0)
		)
		(polygon
			(pts
				(arc
					(start 130.985006 -35.600132)
					(mid 130.499866 -35.114992)
					(end 130.014726 -35.600132)
				)
				(arc
					(start 130.014726 -36.999926)
					(mid 130.498469 -37.485318)
					(end 130.985006 -37.00272)
				)
				(arc
					(start 130.893566 -37.00272)
					(mid 130.499866 -37.393888)
					(end 130.106166 -37.00272)
				)
				(arc
					(start 130.106166 -37.00018)
					(mid 130.499866 -36.60648)
					(end 130.893566 -37.00018)
				)
				(xy 130.985006 -37.00018) (xy 130.985006 -35.602672)
				(arc
					(start 130.893566 -35.602672)
					(mid 130.499866 -35.99384)
					(end 130.106166 -35.602672)
				)
				(arc
					(start 130.106166 -35.600132)
					(mid 130.499866 -35.206432)
					(end 130.893566 -35.600132)
				)
			)
		)
	)
	(zone
		(layers "F.Cu" "B.Cu" "In2.Cu")
		(hatch none 0.5)
		(connect_pads
			(clearance 0)
		)
		(min_thickness 0.25)
		(keepout
			(tracks not_allowed)
			(vias allowed)
			(pads allowed)
			(copperpour not_allowed)
			(footprints allowed)
		)
		(placement
			(enabled no)
			(sheetname "")
		)
		(fill yes
			(thermal_gap 0.5)
			(thermal_bridge_width 0.5)
			(island_removal_mode 0)
		)
		(polygon
			(pts
				(arc
					(start 141.785086 -35.600132)
					(mid 141.299946 -35.114992)
					(end 140.814806 -35.600132)
				)
				(arc
					(start 140.814806 -36.999926)
					(mid 141.298549 -37.485318)
					(end 141.785086 -37.00272)
				)
				(arc
					(start 141.693646 -37.00272)
					(mid 141.299946 -37.393888)
					(end 140.906246 -37.00272)
				)
				(arc
					(start 140.906246 -37.00018)
					(mid 141.299946 -36.60648)
					(end 141.693646 -37.00018)
				)
				(xy 141.785086 -37.00018) (xy 141.785086 -35.602672)
				(arc
					(start 141.693646 -35.602672)
					(mid 141.299946 -35.99384)
					(end 140.906246 -35.602672)
				)
				(arc
					(start 140.906246 -35.600132)
					(mid 141.299946 -35.206432)
					(end 141.693646 -35.600132)
				)
			)
		)
	)
	(zone
		(layers "F.Cu" "B.Cu" "In2.Cu")
		(hatch none 0.5)
		(connect_pads
			(clearance 0)
		)
		(min_thickness 0.25)
		(keepout
			(tracks not_allowed)
			(vias allowed)
			(pads allowed)
			(copperpour not_allowed)
			(footprints allowed)
		)
		(placement
			(enabled no)
			(sheetname "")
		)
		(fill yes
			(thermal_gap 0.5)
			(thermal_bridge_width 0.5)
			(island_removal_mode 0)
		)
		(polygon
			(pts
				(arc
					(start 138.185144 -35.600132)
					(mid 137.700004 -35.114992)
					(end 137.214864 -35.600132)
				)
				(arc
					(start 137.214864 -36.999926)
					(mid 137.698607 -37.485318)
					(end 138.185144 -37.00272)
				)
				(arc
					(start 138.093704 -37.00272)
					(mid 137.700004 -37.393888)
					(end 137.306304 -37.00272)
				)
				(arc
					(start 137.306304 -37.00018)
					(mid 137.700004 -36.60648)
					(end 138.093704 -37.00018)
				)
				(xy 138.185144 -37.00018) (xy 138.185144 -35.602672)
				(arc
					(start 138.093704 -35.602672)
					(mid 137.700004 -35.99384)
					(end 137.306304 -35.602672)
				)
				(arc
					(start 137.306304 -35.600132)
					(mid 137.700004 -35.206432)
					(end 138.093704 -35.600132)
				)
			)
		)
	)
	(zone
		(layers "F.Cu" "B.Cu" "In2.Cu")
		(hatch none 0.5)
		(connect_pads
			(clearance 0)
		)
		(min_thickness 0.25)
		(keepout
			(tracks not_allowed)
			(vias allowed)
			(pads allowed)
			(copperpour not_allowed)
			(footprints allowed)
		)
		(placement
			(enabled no)
			(sheetname "")
		)
		(fill yes
			(thermal_gap 0.5)
			(thermal_bridge_width 0.5)
			(island_removal_mode 0)
		)
		(polygon
			(pts
				(arc
					(start 114.78514 -36.800028)
					(mid 114.3 -36.314888)
					(end 113.81486 -36.800028)
				)
				(arc
					(start 113.81486 -38.199822)
					(mid 114.298603 -38.685214)
					(end 114.78514 -38.202616)
				)
				(arc
					(start 114.6937 -38.202616)
					(mid 114.3 -38.593784)
					(end 113.9063 -38.202616)
				)
				(arc
					(start 113.9063 -38.200076)
					(mid 114.3 -37.806376)
					(end 114.6937 -38.200076)
				)
				(xy 114.78514 -38.200076) (xy 114.78514 -36.802568)
				(arc
					(start 114.6937 -36.802568)
					(mid 114.3 -37.193736)
					(end 113.9063 -36.802568)
				)
				(arc
					(start 113.9063 -36.800028)
					(mid 114.3 -36.406328)
					(end 114.6937 -36.800028)
				)
			)
		)
	)
	(zone
		(layers "F.Cu" "B.Cu" "In2.Cu")
		(hatch none 0.5)
		(connect_pads
			(clearance 0)
		)
		(min_thickness 0.25)
		(keepout
			(tracks not_allowed)
			(vias allowed)
			(pads allowed)
			(copperpour not_allowed)
			(footprints allowed)
		)
		(placement
			(enabled no)
			(sheetname "")
		)
		(fill yes
			(thermal_gap 0.5)
			(thermal_bridge_width 0.5)
			(island_removal_mode 0)
		)
		(polygon
			(pts
				(arc
					(start 109.3851 -35.600132)
					(mid 108.89996 -35.114992)
					(end 108.41482 -35.600132)
				)
				(arc
					(start 108.41482 -36.999926)
					(mid 108.898563 -37.485318)
					(end 109.3851 -37.00272)
				)
				(arc
					(start 109.29366 -37.00272)
					(mid 108.89996 -37.393888)
					(end 108.50626 -37.00272)
				)
				(arc
					(start 108.50626 -37.00018)
					(mid 108.89996 -36.60648)
					(end 109.29366 -37.00018)
				)
				(xy 109.3851 -37.00018) (xy 109.3851 -35.602672)
				(arc
					(start 109.29366 -35.602672)
					(mid 108.89996 -35.99384)
					(end 108.50626 -35.602672)
				)
				(arc
					(start 108.50626 -35.600132)
					(mid 108.89996 -35.206432)
					(end 109.29366 -35.600132)
				)
			)
		)
	)
	(zone
		(layers "F.Cu" "B.Cu" "In2.Cu")
		(hatch none 0.5)
		(connect_pads
			(clearance 0)
		)
		(min_thickness 0.25)
		(keepout
			(tracks not_allowed)
			(vias allowed)
			(pads allowed)
			(copperpour not_allowed)
			(footprints allowed)
		)
		(placement
			(enabled no)
			(sheetname "")
		)
		(fill yes
			(thermal_gap 0.5)
			(thermal_bridge_width 0.5)
			(island_removal_mode 0)
		)
		(polygon
			(pts
				(arc
					(start 112.985042 -35.600132)
					(mid 112.499902 -35.114992)
					(end 112.014762 -35.600132)
				)
				(arc
					(start 112.014762 -36.999926)
					(mid 112.498505 -37.485318)
					(end 112.985042 -37.00272)
				)
				(arc
					(start 112.893602 -37.00272)
					(mid 112.499902 -37.393888)
					(end 112.106202 -37.00272)
				)
				(arc
					(start 112.106202 -37.00018)
					(mid 112.499902 -36.60648)
					(end 112.893602 -37.00018)
				)
				(xy 112.985042 -37.00018) (xy 112.985042 -35.602672)
				(arc
					(start 112.893602 -35.602672)
					(mid 112.499902 -35.99384)
					(end 112.106202 -35.602672)
				)
				(arc
					(start 112.106202 -35.600132)
					(mid 112.499902 -35.206432)
					(end 112.893602 -35.600132)
				)
			)
		)
	)
	(zone
		(layers "F.Cu" "B.Cu" "In2.Cu")
		(hatch none 0.5)
		(connect_pads
			(clearance 0)
		)
		(min_thickness 0.25)
		(keepout
			(tracks not_allowed)
			(vias allowed)
			(pads allowed)
			(copperpour not_allowed)
			(footprints allowed)
		)
		(placement
			(enabled no)
			(sheetname "")
		)
		(fill yes
			(thermal_gap 0.5)
			(thermal_bridge_width 0.5)
			(island_removal_mode 0)
		)
		(polygon
			(pts
				(arc
					(start 129.185162 -36.800028)
					(mid 128.700022 -36.314888)
					(end 128.214882 -36.800028)
				)
				(arc
					(start 128.214882 -38.199822)
					(mid 128.698625 -38.685214)
					(end 129.185162 -38.202616)
				)
				(arc
					(start 129.093722 -38.202616)
					(mid 128.700022 -38.593784)
					(end 128.306322 -38.202616)
				)
				(arc
					(start 128.306322 -38.200076)
					(mid 128.700022 -37.806376)
					(end 129.093722 -38.200076)
				)
				(xy 129.185162 -38.200076) (xy 129.185162 -36.802568)
				(arc
					(start 129.093722 -36.802568)
					(mid 128.700022 -37.193736)
					(end 128.306322 -36.802568)
				)
				(arc
					(start 128.306322 -36.800028)
					(mid 128.700022 -36.406328)
					(end 129.093722 -36.800028)
				)
			)
		)
	)
	(zone
		(layers "F.Cu" "B.Cu" "In2.Cu")
		(hatch none 0.5)
		(connect_pads
			(clearance 0)
		)
		(min_thickness 0.25)
		(keepout
			(tracks not_allowed)
			(vias allowed)
			(pads allowed)
			(copperpour not_allowed)
			(footprints allowed)
		)
		(placement
			(enabled no)
			(sheetname "")
		)
		(fill yes
			(thermal_gap 0.5)
			(thermal_bridge_width 0.5)
			(island_removal_mode 0)
		)
		(polygon
			(pts
				(arc
					(start 132.785104 -36.800028)
					(mid 132.299964 -36.314888)
					(end 131.814824 -36.800028)
				)
				(arc
					(start 131.814824 -38.199822)
					(mid 132.298567 -38.685214)
					(end 132.785104 -38.202616)
				)
				(arc
					(start 132.693664 -38.202616)
					(mid 132.299964 -38.593784)
					(end 131.906264 -38.202616)
				)
				(arc
					(start 131.906264 -38.200076)
					(mid 132.299964 -37.806376)
					(end 132.693664 -38.200076)
				)
				(xy 132.785104 -38.200076) (xy 132.785104 -36.802568)
				(arc
					(start 132.693664 -36.802568)
					(mid 132.299964 -37.193736)
					(end 131.906264 -36.802568)
				)
				(arc
					(start 131.906264 -36.800028)
					(mid 132.299964 -36.406328)
					(end 132.693664 -36.800028)
				)
			)
		)
	)
	(zone
		(layers "F.Cu" "B.Cu" "In2.Cu")
		(hatch none 0.5)
		(connect_pads
			(clearance 0)
		)
		(min_thickness 0.25)
		(keepout
			(tracks not_allowed)
			(vias allowed)
			(pads allowed)
			(copperpour not_allowed)
			(footprints allowed)
		)
		(placement
			(enabled no)
			(sheetname "")
		)
		(fill yes
			(thermal_gap 0.5)
			(thermal_bridge_width 0.5)
			(island_removal_mode 0)
		)
		(polygon
			(pts
				(arc
					(start 107.585002 -36.800028)
					(mid 107.099862 -36.314888)
					(end 106.614722 -36.800028)
				)
				(arc
					(start 106.614722 -38.199822)
					(mid 107.098465 -38.685214)
					(end 107.585002 -38.202616)
				)
				(arc
					(start 107.493562 -38.202616)
					(mid 107.099862 -38.593784)
					(end 106.706162 -38.202616)
				)
				(arc
					(start 106.706162 -38.200076)
					(mid 107.099862 -37.806376)
					(end 107.493562 -38.200076)
				)
				(xy 107.585002 -38.200076) (xy 107.585002 -36.802568)
				(arc
					(start 107.493562 -36.802568)
					(mid 107.099862 -37.193736)
					(end 106.706162 -36.802568)
				)
				(arc
					(start 106.706162 -36.800028)
					(mid 107.099862 -36.406328)
					(end 107.493562 -36.800028)
				)
			)
		)
	)
	(zone
		(layers "F.Cu" "B.Cu" "In2.Cu")
		(hatch none 0.5)
		(connect_pads
			(clearance 0)
		)
		(min_thickness 0.25)
		(keepout
			(tracks not_allowed)
			(vias allowed)
			(pads allowed)
			(copperpour not_allowed)
			(footprints allowed)
		)
		(placement
			(enabled no)
			(sheetname "")
		)
		(fill yes
			(thermal_gap 0.5)
			(thermal_bridge_width 0.5)
			(island_removal_mode 0)
		)
		(polygon
			(pts
				(arc
					(start 139.984988 -36.800028)
					(mid 139.499848 -36.314888)
					(end 139.014708 -36.800028)
				)
				(arc
					(start 139.014708 -38.199822)
					(mid 139.498451 -38.685214)
					(end 139.984988 -38.202616)
				)
				(arc
					(start 139.893548 -38.202616)
					(mid 139.499848 -38.593784)
					(end 139.106148 -38.202616)
				)
				(arc
					(start 139.106148 -38.200076)
					(mid 139.499848 -37.806376)
					(end 139.893548 -38.200076)
				)
				(xy 139.984988 -38.200076) (xy 139.984988 -36.802568)
				(arc
					(start 139.893548 -36.802568)
					(mid 139.499848 -37.193736)
					(end 139.106148 -36.802568)
				)
				(arc
					(start 139.106148 -36.800028)
					(mid 139.499848 -36.406328)
					(end 139.893548 -36.800028)
				)
			)
		)
	)
	(zone
		(layers "F.Cu" "B.Cu" "In2.Cu")
		(hatch none 0.5)
		(connect_pads
			(clearance 0)
		)
		(min_thickness 0.25)
		(keepout
			(tracks not_allowed)
			(vias allowed)
			(pads allowed)
			(copperpour not_allowed)
			(footprints allowed)
		)
		(placement
			(enabled no)
			(sheetname "")
		)
		(fill yes
			(thermal_gap 0.5)
			(thermal_bridge_width 0.5)
			(island_removal_mode 0)
		)
		(polygon
			(pts
				(arc
					(start 134.585202 -35.600132)
					(mid 134.100062 -35.114992)
					(end 133.614922 -35.600132)
				)
				(arc
					(start 133.614922 -36.999926)
					(mid 134.098665 -37.485318)
					(end 134.585202 -37.00272)
				)
				(arc
					(start 134.493762 -37.00272)
					(mid 134.100062 -37.393888)
					(end 133.706362 -37.00272)
				)
				(arc
					(start 133.706362 -37.00018)
					(mid 134.100062 -36.60648)
					(end 134.493762 -37.00018)
				)
				(xy 134.585202 -37.00018) (xy 134.585202 -35.602672)
				(arc
					(start 134.493762 -35.602672)
					(mid 134.100062 -35.99384)
					(end 133.706362 -35.602672)
				)
				(arc
					(start 133.706362 -35.600132)
					(mid 134.100062 -35.206432)
					(end 134.493762 -35.600132)
				)
			)
		)
	)
	(zone
		(layers "F.Cu" "B.Cu" "In2.Cu")
		(hatch none 0.5)
		(connect_pads
			(clearance 0)
		)
		(min_thickness 0.25)
		(keepout
			(tracks not_allowed)
			(vias allowed)
			(pads allowed)
			(copperpour not_allowed)
			(footprints allowed)
		)
		(placement
			(enabled no)
			(sheetname "")
		)
		(fill yes
			(thermal_gap 0.5)
			(thermal_bridge_width 0.5)
			(island_removal_mode 0)
		)
		(polygon
			(pts
				(arc
					(start 136.385046 -36.800028)
					(mid 135.899906 -36.314888)
					(end 135.414766 -36.800028)
				)
				(arc
					(start 135.414766 -38.199822)
					(mid 135.898509 -38.685214)
					(end 136.385046 -38.202616)
				)
				(arc
					(start 136.293606 -38.202616)
					(mid 135.899906 -38.593784)
					(end 135.506206 -38.202616)
				)
				(arc
					(start 135.506206 -38.200076)
					(mid 135.899906 -37.806376)
					(end 136.293606 -38.200076)
				)
				(xy 136.385046 -38.200076) (xy 136.385046 -36.802568)
				(arc
					(start 136.293606 -36.802568)
					(mid 135.899906 -37.193736)
					(end 135.506206 -36.802568)
				)
				(arc
					(start 135.506206 -36.800028)
					(mid 135.899906 -36.406328)
					(end 136.293606 -36.800028)
				)
			)
		)
	)
	(zone
		(net "GND")
		(layers "F.Cu" "B.Cu" "In2.Cu")
		(hatch none 0.5)
		(connect_pads
			(clearance 0.5)
		)
		(min_thickness 0.25)
		(fill yes
			(thermal_gap 0.5)
			(thermal_bridge_width 0.5)
			(island_removal_mode 0)
		)
		(polygon
			(pts
				(xy 100.906072 -178.38039) (xy 100.906072 -182.8546) (xy 102.937056 -182.8546) (xy 102.937056 -178.38039)
			)
		)
	)
	(zone
		(layers "F.Cu" "In2.Cu" "In5.Cu")
		(hatch none 0.5)
		(connect_pads
			(clearance 0)
		)
		(min_thickness 0.25)
		(keepout
			(tracks not_allowed)
			(vias allowed)
			(pads allowed)
			(copperpour not_allowed)
			(footprints allowed)
		)
		(placement
			(enabled no)
			(sheetname "")
		)
		(fill yes
			(thermal_gap 0.5)
			(thermal_bridge_width 0.5)
			(island_removal_mode 0)
		)
		(polygon
			(pts
				(arc
					(start 116.584984 -32.00019)
					(mid 116.099844 -31.51505)
					(end 115.614704 -32.00019)
				)
				(arc
					(start 115.614704 -33.39973)
					(mid 116.098447 -33.885122)
					(end 116.584984 -33.402524)
				)
				(arc
					(start 116.493544 -33.402524)
					(mid 116.099844 -33.793692)
					(end 115.706144 -33.402524)
				)
				(arc
					(start 115.706144 -33.399984)
					(mid 116.099844 -33.006284)
					(end 116.493544 -33.399984)
				)
				(xy 116.584984 -33.399984) (xy 116.584984 -32.00273)
				(arc
					(start 116.493544 -32.00273)
					(mid 116.099844 -32.393898)
					(end 115.706144 -32.00273)
				)
				(arc
					(start 115.706144 -32.00019)
					(mid 116.099844 -31.60649)
					(end 116.493544 -32.00019)
				)
			)
		)
	)
	(zone
		(layers "F.Cu" "In2.Cu" "In5.Cu")
		(hatch none 0.5)
		(connect_pads
			(clearance 0)
		)
		(min_thickness 0.25)
		(keepout
			(tracks not_allowed)
			(vias allowed)
			(pads allowed)
			(copperpour not_allowed)
			(footprints allowed)
		)
		(placement
			(enabled no)
			(sheetname "")
		)
		(fill yes
			(thermal_gap 0.5)
			(thermal_bridge_width 0.5)
			(island_removal_mode 0)
		)
		(polygon
			(pts
				(arc
					(start 134.585202 -32.00019)
					(mid 134.100062 -31.51505)
					(end 133.614922 -32.00019)
				)
				(arc
					(start 133.614922 -33.39973)
					(mid 134.098665 -33.885122)
					(end 134.585202 -33.402524)
				)
				(arc
					(start 134.493762 -33.402524)
					(mid 134.100062 -33.793692)
					(end 133.706362 -33.402524)
				)
				(arc
					(start 133.706362 -33.399984)
					(mid 134.100062 -33.006284)
					(end 134.493762 -33.399984)
				)
				(xy 134.585202 -33.399984) (xy 134.585202 -32.00273)
				(arc
					(start 134.493762 -32.00273)
					(mid 134.100062 -32.393898)
					(end 133.706362 -32.00273)
				)
				(arc
					(start 133.706362 -32.00019)
					(mid 134.100062 -31.60649)
					(end 134.493762 -32.00019)
				)
			)
		)
	)
	(zone
		(layers "F.Cu" "In2.Cu" "In5.Cu")
		(hatch none 0.5)
		(connect_pads
			(clearance 0)
		)
		(min_thickness 0.25)
		(keepout
			(tracks not_allowed)
			(vias allowed)
			(pads allowed)
			(copperpour not_allowed)
			(footprints allowed)
		)
		(placement
			(enabled no)
			(sheetname "")
		)
		(fill yes
			(thermal_gap 0.5)
			(thermal_bridge_width 0.5)
			(island_removal_mode 0)
		)
		(polygon
			(pts
				(arc
					(start 111.185198 -33.200086)
					(mid 110.700058 -32.714946)
					(end 110.214918 -33.200086)
				)
				(arc
					(start 110.214918 -34.600134)
					(mid 110.698788 -35.085272)
					(end 111.185198 -34.602674)
				)
				(arc
					(start 111.093758 -34.602674)
					(mid 110.700058 -34.993842)
					(end 110.306358 -34.602674)
				)
				(arc
					(start 110.306358 -34.600134)
					(mid 110.700058 -34.206434)
					(end 111.093758 -34.600134)
				)
				(xy 111.185198 -34.600134) (xy 111.185198 -33.202626)
				(arc
					(start 111.093758 -33.202626)
					(mid 110.700058 -33.593794)
					(end 110.306358 -33.202626)
				)
				(arc
					(start 110.306358 -33.200086)
					(mid 110.700058 -32.806386)
					(end 111.093758 -33.200086)
				)
			)
		)
	)
	(zone
		(layers "F.Cu" "In2.Cu" "In5.Cu")
		(hatch none 0.5)
		(connect_pads
			(clearance 0)
		)
		(min_thickness 0.25)
		(keepout
			(tracks not_allowed)
			(vias allowed)
			(pads allowed)
			(copperpour not_allowed)
			(footprints allowed)
		)
		(placement
			(enabled no)
			(sheetname "")
		)
		(fill yes
			(thermal_gap 0.5)
			(thermal_bridge_width 0.5)
			(island_removal_mode 0)
		)
		(polygon
			(pts
				(arc
					(start 118.385082 -33.200086)
					(mid 117.899942 -32.714946)
					(end 117.414802 -33.200086)
				)
				(arc
					(start 117.414802 -34.600134)
					(mid 117.898672 -35.085272)
					(end 118.385082 -34.602674)
				)
				(arc
					(start 118.293642 -34.602674)
					(mid 117.899942 -34.993842)
					(end 117.506242 -34.602674)
				)
				(arc
					(start 117.506242 -34.600134)
					(mid 117.899942 -34.206434)
					(end 118.293642 -34.600134)
				)
				(xy 118.385082 -34.600134) (xy 118.385082 -33.202626)
				(arc
					(start 118.293642 -33.202626)
					(mid 117.899942 -33.593794)
					(end 117.506242 -33.202626)
				)
				(arc
					(start 117.506242 -33.200086)
					(mid 117.899942 -32.806386)
					(end 118.293642 -33.200086)
				)
			)
		)
	)
	(zone
		(layers "F.Cu" "In2.Cu" "In5.Cu")
		(hatch none 0.5)
		(connect_pads
			(clearance 0)
		)
		(min_thickness 0.25)
		(keepout
			(tracks not_allowed)
			(vias allowed)
			(pads allowed)
			(copperpour not_allowed)
			(footprints allowed)
		)
		(placement
			(enabled no)
			(sheetname "")
		)
		(fill yes
			(thermal_gap 0.5)
			(thermal_bridge_width 0.5)
			(island_removal_mode 0)
		)
		(polygon
			(pts
				(arc
					(start 136.385046 -33.200086)
					(mid 135.899906 -32.714946)
					(end 135.414766 -33.200086)
				)
				(arc
					(start 135.414766 -34.600134)
					(mid 135.898636 -35.085272)
					(end 136.385046 -34.602674)
				)
				(arc
					(start 136.293606 -34.602674)
					(mid 135.899906 -34.993842)
					(end 135.506206 -34.602674)
				)
				(arc
					(start 135.506206 -34.600134)
					(mid 135.899906 -34.206434)
					(end 136.293606 -34.600134)
				)
				(xy 136.385046 -34.600134) (xy 136.385046 -33.202626)
				(arc
					(start 136.293606 -33.202626)
					(mid 135.899906 -33.593794)
					(end 135.506206 -33.202626)
				)
				(arc
					(start 135.506206 -33.200086)
					(mid 135.899906 -32.806386)
					(end 136.293606 -33.200086)
				)
			)
		)
	)
	(zone
		(layers "F.Cu" "In2.Cu" "In5.Cu")
		(hatch none 0.5)
		(connect_pads
			(clearance 0)
		)
		(min_thickness 0.25)
		(keepout
			(tracks not_allowed)
			(vias allowed)
			(pads allowed)
			(copperpour not_allowed)
			(footprints allowed)
		)
		(placement
			(enabled no)
			(sheetname "")
		)
		(fill yes
			(thermal_gap 0.5)
			(thermal_bridge_width 0.5)
			(island_removal_mode 0)
		)
		(polygon
			(pts
				(arc
					(start 129.185162 -33.200086)
					(mid 128.700022 -32.714946)
					(end 128.214882 -33.200086)
				)
				(arc
					(start 128.214882 -34.600134)
					(mid 128.698752 -35.085272)
					(end 129.185162 -34.602674)
				)
				(arc
					(start 129.093722 -34.602674)
					(mid 128.700022 -34.993842)
					(end 128.306322 -34.602674)
				)
				(arc
					(start 128.306322 -34.600134)
					(mid 128.700022 -34.206434)
					(end 129.093722 -34.600134)
				)
				(xy 129.185162 -34.600134) (xy 129.185162 -33.202626)
				(arc
					(start 129.093722 -33.202626)
					(mid 128.700022 -33.593794)
					(end 128.306322 -33.202626)
				)
				(arc
					(start 128.306322 -33.200086)
					(mid 128.700022 -32.806386)
					(end 129.093722 -33.200086)
				)
			)
		)
	)
	(zone
		(net "GND")
		(layers "F.Cu" "In2.Cu" "In5.Cu")
		(hatch none 0.5)
		(connect_pads
			(clearance 0.5)
		)
		(min_thickness 0.25)
		(fill yes
			(thermal_gap 0.5)
			(thermal_bridge_width 0.5)
			(island_removal_mode 0)
		)
		(polygon
			(pts
				(arc
					(start 0.999998 -0.763016)
					(mid 0.832426 -0.832426)
					(end 0.763016 -0.999998)
				)
				(arc
					(start 0.763016 -183.76392)
					(mid 0.769411 -183.818347)
					(end 0.788162 -183.869838)
				)
				(arc
					(start 5.406136 -193.10604)
					(mid 5.493436 -193.201687)
					(end 5.617972 -193.237104)
				)
				(arc
					(start 98.0821 -193.237104)
					(mid 98.206591 -193.201614)
					(end 98.293936 -193.10604)
				)
				(arc
					(start 102.91191 -183.869838)
					(mid 102.930633 -183.818341)
					(end 102.937056 -183.76392)
				)
				(xy 102.937056 -183.403748) (xy 100.874322 -183.403748) (xy 96.97339 -191.20612) (xy 6.726682 -191.20612)
				(xy 2.82575 -183.403748) (xy 2.767584 -183.403748) (xy 2.7305 -183.366664) (xy 2.7305 -183.313832)
				(xy 2.767584 -183.276748) (xy 2.794 -183.276748) (xy 2.794 -2.794) (xy 27.736038 -2.794) (xy 27.736038 -108.871258)
				(xy 29.767022 -108.871258)
				(arc
					(start 29.767022 -0.999998)
					(mid 29.697612 -0.832426)
					(end 29.53004 -0.763016)
				)
			)
		)
	)
	(zone
		(layers "F.Cu" "In2.Cu" "In5.Cu")
		(hatch none 0.5)
		(connect_pads
			(clearance 0)
		)
		(min_thickness 0.25)
		(keepout
			(tracks not_allowed)
			(vias allowed)
			(pads allowed)
			(copperpour not_allowed)
			(footprints allowed)
		)
		(placement
			(enabled no)
			(sheetname "")
		)
		(fill yes
			(thermal_gap 0.5)
			(thermal_bridge_width 0.5)
			(island_removal_mode 0)
		)
		(polygon
			(pts
				(arc
					(start 107.585002 -33.200086)
					(mid 107.099862 -32.714946)
					(end 106.614722 -33.200086)
				)
				(arc
					(start 106.614722 -34.600134)
					(mid 107.098592 -35.085272)
					(end 107.585002 -34.602674)
				)
				(arc
					(start 107.493562 -34.602674)
					(mid 107.099862 -34.993842)
					(end 106.706162 -34.602674)
				)
				(arc
					(start 106.706162 -34.600134)
					(mid 107.099862 -34.206434)
					(end 107.493562 -34.600134)
				)
				(xy 107.585002 -34.600134) (xy 107.585002 -33.202626)
				(arc
					(start 107.493562 -33.202626)
					(mid 107.099862 -33.593794)
					(end 106.706162 -33.202626)
				)
				(arc
					(start 106.706162 -33.200086)
					(mid 107.099862 -32.806386)
					(end 107.493562 -33.200086)
				)
			)
		)
	)
	(zone
		(layers "F.Cu" "In2.Cu" "In5.Cu")
		(hatch none 0.5)
		(connect_pads
			(clearance 0)
		)
		(min_thickness 0.25)
		(keepout
			(tracks not_allowed)
			(vias allowed)
			(pads allowed)
			(copperpour not_allowed)
			(footprints allowed)
		)
		(placement
			(enabled no)
			(sheetname "")
		)
		(fill yes
			(thermal_gap 0.5)
			(thermal_bridge_width 0.5)
			(island_removal_mode 0)
		)
		(polygon
			(pts
				(arc
					(start 109.3851 -32.00019)
					(mid 108.89996 -31.51505)
					(end 108.41482 -32.00019)
				)
				(arc
					(start 108.41482 -33.39973)
					(mid 108.898563 -33.885122)
					(end 109.3851 -33.402524)
				)
				(arc
					(start 109.29366 -33.402524)
					(mid 108.89996 -33.793692)
					(end 108.50626 -33.402524)
				)
				(arc
					(start 108.50626 -33.399984)
					(mid 108.89996 -33.006284)
					(end 109.29366 -33.399984)
				)
				(xy 109.3851 -33.399984) (xy 109.3851 -32.00273)
				(arc
					(start 109.29366 -32.00273)
					(mid 108.89996 -32.393898)
					(end 108.50626 -32.00273)
				)
				(arc
					(start 108.50626 -32.00019)
					(mid 108.89996 -31.60649)
					(end 109.29366 -32.00019)
				)
			)
		)
	)
	(zone
		(layers "F.Cu" "In2.Cu" "In5.Cu")
		(hatch none 0.5)
		(connect_pads
			(clearance 0)
		)
		(min_thickness 0.25)
		(keepout
			(tracks not_allowed)
			(vias allowed)
			(pads allowed)
			(copperpour not_allowed)
			(footprints allowed)
		)
		(placement
			(enabled no)
			(sheetname "")
		)
		(fill yes
			(thermal_gap 0.5)
			(thermal_bridge_width 0.5)
			(island_removal_mode 0)
		)
		(polygon
			(pts
				(arc
					(start 130.985006 -32.00019)
					(mid 130.499866 -31.51505)
					(end 130.014726 -32.00019)
				)
				(arc
					(start 130.014726 -33.39973)
					(mid 130.498469 -33.885122)
					(end 130.985006 -33.402524)
				)
				(arc
					(start 130.893566 -33.402524)
					(mid 130.499866 -33.793692)
					(end 130.106166 -33.402524)
				)
				(arc
					(start 130.106166 -33.399984)
					(mid 130.499866 -33.006284)
					(end 130.893566 -33.399984)
				)
				(xy 130.985006 -33.399984) (xy 130.985006 -32.00273)
				(arc
					(start 130.893566 -32.00273)
					(mid 130.499866 -32.393898)
					(end 130.106166 -32.00273)
				)
				(arc
					(start 130.106166 -32.00019)
					(mid 130.499866 -31.60649)
					(end 130.893566 -32.00019)
				)
			)
		)
	)
	(zone
		(layers "F.Cu" "In2.Cu" "In5.Cu")
		(hatch none 0.5)
		(connect_pads
			(clearance 0)
		)
		(min_thickness 0.25)
		(keepout
			(tracks not_allowed)
			(vias allowed)
			(pads allowed)
			(copperpour not_allowed)
			(footprints allowed)
		)
		(placement
			(enabled no)
			(sheetname "")
		)
		(fill yes
			(thermal_gap 0.5)
			(thermal_bridge_width 0.5)
			(island_removal_mode 0)
		)
		(polygon
			(pts
				(arc
					(start 138.185144 -32.00019)
					(mid 137.700004 -31.51505)
					(end 137.214864 -32.00019)
				)
				(arc
					(start 137.214864 -33.39973)
					(mid 137.698607 -33.885122)
					(end 138.185144 -33.402524)
				)
				(arc
					(start 138.093704 -33.402524)
					(mid 137.700004 -33.793692)
					(end 137.306304 -33.402524)
				)
				(arc
					(start 137.306304 -33.399984)
					(mid 137.700004 -33.006284)
					(end 138.093704 -33.399984)
				)
				(xy 138.185144 -33.399984) (xy 138.185144 -32.00273)
				(arc
					(start 138.093704 -32.00273)
					(mid 137.700004 -32.393898)
					(end 137.306304 -32.00273)
				)
				(arc
					(start 137.306304 -32.00019)
					(mid 137.700004 -31.60649)
					(end 138.093704 -32.00019)
				)
			)
		)
	)
	(zone
		(net "GND")
		(layers "F.Cu" "In2.Cu" "In5.Cu")
		(hatch none 0.5)
		(connect_pads
			(clearance 0.5)
		)
		(min_thickness 0.25)
		(fill yes
			(thermal_gap 0.5)
			(thermal_bridge_width 0.5)
			(island_removal_mode 0)
		)
		(polygon
			(pts
				(arc
					(start 74.030078 -0.763016)
					(mid 73.862506 -0.832426)
					(end 73.793096 -0.999998)
				)
				(xy 73.793096 -36.016946) (xy 75.82408 -36.016946) (xy 75.82408 -2.794) (xy 232.206038 -2.794) (xy 232.206038 -183.340248)
				(xy 228.273356 -191.20612) (xy 217.794078 -191.20612)
				(arc
					(start 217.794078 -160.999932)
					(mid 216.682842 -158.31717)
					(end 214.00008 -157.205934)
				)
				(xy 151.026622 -157.205934) (xy 147.09394 -149.340062)
				(arc
					(start 147.09394 -47.999904)
					(mid 145.397362 -45.119087)
					(end 142.055342 -45.205904)
				)
				(xy 140.912088 -45.205904) (xy 140.912088 -47.236888)
				(arc
					(start 142.793466 -47.236888)
					(mid 144.202311 -46.802855)
					(end 145.062956 -47.999904)
				)
				(arc
					(start 145.062956 -149.763734)
					(mid 145.069351 -149.818161)
					(end 145.088102 -149.869652)
				)
				(arc
					(start 149.706076 -159.105854)
					(mid 149.793376 -159.201501)
					(end 149.917912 -159.236918)
				)
				(arc
					(start 214.00008 -159.236918)
					(mid 215.246719 -159.753293)
					(end 215.763094 -160.999932)
				)
				(arc
					(start 215.763094 -193.000122)
					(mid 215.832504 -193.167694)
					(end 216.000076 -193.237104)
				)
				(arc
					(start 229.382066 -193.237104)
					(mid 229.506557 -193.201614)
					(end 229.593902 -193.10604)
				)
				(arc
					(start 234.211876 -183.869838)
					(mid 234.230599 -183.818341)
					(end 234.237022 -183.76392)
				)
				(arc
					(start 234.237022 -0.999998)
					(mid 234.167612 -0.832426)
					(end 234.00004 -0.763016)
				)
			)
		)
	)
	(zone
		(layers "F.Cu" "In2.Cu" "In5.Cu")
		(hatch none 0.5)
		(connect_pads
			(clearance 0)
		)
		(min_thickness 0.25)
		(keepout
			(tracks not_allowed)
			(vias allowed)
			(pads allowed)
			(copperpour not_allowed)
			(footprints allowed)
		)
		(placement
			(enabled no)
			(sheetname "")
		)
		(fill yes
			(thermal_gap 0.5)
			(thermal_bridge_width 0.5)
			(island_removal_mode 0)
		)
		(polygon
			(pts
				(arc
					(start 132.785104 -33.200086)
					(mid 132.299964 -32.714946)
					(end 131.814824 -33.200086)
				)
				(arc
					(start 131.814824 -34.600134)
					(mid 132.298694 -35.085272)
					(end 132.785104 -34.602674)
				)
				(arc
					(start 132.693664 -34.602674)
					(mid 132.299964 -34.993842)
					(end 131.906264 -34.602674)
				)
				(arc
					(start 131.906264 -34.600134)
					(mid 132.299964 -34.206434)
					(end 132.693664 -34.600134)
				)
				(xy 132.785104 -34.600134) (xy 132.785104 -33.202626)
				(arc
					(start 132.693664 -33.202626)
					(mid 132.299964 -33.593794)
					(end 131.906264 -33.202626)
				)
				(arc
					(start 131.906264 -33.200086)
					(mid 132.299964 -32.806386)
					(end 132.693664 -33.200086)
				)
			)
		)
	)
	(zone
		(layers "F.Cu" "In2.Cu" "In5.Cu")
		(hatch none 0.5)
		(connect_pads
			(clearance 0)
		)
		(min_thickness 0.25)
		(keepout
			(tracks not_allowed)
			(vias allowed)
			(pads allowed)
			(copperpour not_allowed)
			(footprints allowed)
		)
		(placement
			(enabled no)
			(sheetname "")
		)
		(fill yes
			(thermal_gap 0.5)
			(thermal_bridge_width 0.5)
			(island_removal_mode 0)
		)
		(polygon
			(pts
				(arc
					(start 141.785086 -32.00019)
					(mid 141.299946 -31.51505)
					(end 140.814806 -32.00019)
				)
				(arc
					(start 140.814806 -33.39973)
					(mid 141.298549 -33.885122)
					(end 141.785086 -33.402524)
				)
				(arc
					(start 141.693646 -33.402524)
					(mid 141.299946 -33.793692)
					(end 140.906246 -33.402524)
				)
				(arc
					(start 140.906246 -33.399984)
					(mid 141.299946 -33.006284)
					(end 141.693646 -33.399984)
				)
				(xy 141.785086 -33.399984) (xy 141.785086 -32.00273)
				(arc
					(start 141.693646 -32.00273)
					(mid 141.299946 -32.393898)
					(end 140.906246 -32.00273)
				)
				(arc
					(start 140.906246 -32.00019)
					(mid 141.299946 -31.60649)
					(end 141.693646 -32.00019)
				)
			)
		)
	)
	(zone
		(layers "F.Cu" "In2.Cu" "In5.Cu")
		(hatch none 0.5)
		(connect_pads
			(clearance 0)
		)
		(min_thickness 0.25)
		(keepout
			(tracks not_allowed)
			(vias allowed)
			(pads allowed)
			(copperpour not_allowed)
			(footprints allowed)
		)
		(placement
			(enabled no)
			(sheetname "")
		)
		(fill yes
			(thermal_gap 0.5)
			(thermal_bridge_width 0.5)
			(island_removal_mode 0)
		)
		(polygon
			(pts
				(arc
					(start 120.18518 -32.00019)
					(mid 119.70004 -31.51505)
					(end 119.2149 -32.00019)
				)
				(arc
					(start 119.2149 -33.39973)
					(mid 119.698643 -33.885122)
					(end 120.18518 -33.402524)
				)
				(arc
					(start 120.09374 -33.402524)
					(mid 119.70004 -33.793692)
					(end 119.30634 -33.402524)
				)
				(arc
					(start 119.30634 -33.399984)
					(mid 119.70004 -33.006284)
					(end 120.09374 -33.399984)
				)
				(xy 120.18518 -33.399984) (xy 120.18518 -32.00273)
				(arc
					(start 120.09374 -32.00273)
					(mid 119.70004 -32.393898)
					(end 119.30634 -32.00273)
				)
				(arc
					(start 119.30634 -32.00019)
					(mid 119.70004 -31.60649)
					(end 120.09374 -32.00019)
				)
			)
		)
	)
	(zone
		(layers "F.Cu" "In2.Cu" "In5.Cu")
		(hatch none 0.5)
		(connect_pads
			(clearance 0)
		)
		(min_thickness 0.25)
		(keepout
			(tracks not_allowed)
			(vias allowed)
			(pads allowed)
			(copperpour not_allowed)
			(footprints allowed)
		)
		(placement
			(enabled no)
			(sheetname "")
		)
		(fill yes
			(thermal_gap 0.5)
			(thermal_bridge_width 0.5)
			(island_removal_mode 0)
		)
		(polygon
			(pts
				(arc
					(start 114.78514 -33.200086)
					(mid 114.3 -32.714946)
					(end 113.81486 -33.200086)
				)
				(arc
					(start 113.81486 -34.600134)
					(mid 114.29873 -35.085272)
					(end 114.78514 -34.602674)
				)
				(arc
					(start 114.6937 -34.602674)
					(mid 114.3 -34.993842)
					(end 113.9063 -34.602674)
				)
				(arc
					(start 113.9063 -34.600134)
					(mid 114.3 -34.206434)
					(end 114.6937 -34.600134)
				)
				(xy 114.78514 -34.600134) (xy 114.78514 -33.202626)
				(arc
					(start 114.6937 -33.202626)
					(mid 114.3 -33.593794)
					(end 113.9063 -33.202626)
				)
				(arc
					(start 113.9063 -33.200086)
					(mid 114.3 -32.806386)
					(end 114.6937 -33.200086)
				)
			)
		)
	)
	(zone
		(layers "F.Cu" "In2.Cu" "In5.Cu")
		(hatch none 0.5)
		(connect_pads
			(clearance 0)
		)
		(min_thickness 0.25)
		(keepout
			(tracks not_allowed)
			(vias allowed)
			(pads allowed)
			(copperpour not_allowed)
			(footprints allowed)
		)
		(placement
			(enabled no)
			(sheetname "")
		)
		(fill yes
			(thermal_gap 0.5)
			(thermal_bridge_width 0.5)
			(island_removal_mode 0)
		)
		(polygon
			(pts
				(arc
					(start 139.984988 -33.200086)
					(mid 139.499848 -32.714946)
					(end 139.014708 -33.200086)
				)
				(arc
					(start 139.014708 -34.600134)
					(mid 139.498578 -35.085272)
					(end 139.984988 -34.602674)
				)
				(arc
					(start 139.893548 -34.602674)
					(mid 139.499848 -34.993842)
					(end 139.106148 -34.602674)
				)
				(arc
					(start 139.106148 -34.600134)
					(mid 139.499848 -34.206434)
					(end 139.893548 -34.600134)
				)
				(xy 139.984988 -34.600134) (xy 139.984988 -33.202626)
				(arc
					(start 139.893548 -33.202626)
					(mid 139.499848 -33.593794)
					(end 139.106148 -33.202626)
				)
				(arc
					(start 139.106148 -33.200086)
					(mid 139.499848 -32.806386)
					(end 139.893548 -33.200086)
				)
			)
		)
	)
	(zone
		(layers "F.Cu" "In2.Cu" "In5.Cu")
		(hatch none 0.5)
		(connect_pads
			(clearance 0)
		)
		(min_thickness 0.25)
		(keepout
			(tracks not_allowed)
			(vias allowed)
			(pads allowed)
			(copperpour not_allowed)
			(footprints allowed)
		)
		(placement
			(enabled no)
			(sheetname "")
		)
		(fill yes
			(thermal_gap 0.5)
			(thermal_bridge_width 0.5)
			(island_removal_mode 0)
		)
		(polygon
			(pts
				(arc
					(start 112.985042 -32.00019)
					(mid 112.499902 -31.51505)
					(end 112.014762 -32.00019)
				)
				(arc
					(start 112.014762 -33.39973)
					(mid 112.498505 -33.885122)
					(end 112.985042 -33.402524)
				)
				(arc
					(start 112.893602 -33.402524)
					(mid 112.499902 -33.793692)
					(end 112.106202 -33.402524)
				)
				(arc
					(start 112.106202 -33.399984)
					(mid 112.499902 -33.006284)
					(end 112.893602 -33.399984)
				)
				(xy 112.985042 -33.399984) (xy 112.985042 -32.00273)
				(arc
					(start 112.893602 -32.00273)
					(mid 112.499902 -32.393898)
					(end 112.106202 -32.00273)
				)
				(arc
					(start 112.106202 -32.00019)
					(mid 112.499902 -31.60649)
					(end 112.893602 -32.00019)
				)
			)
		)
	)
	(zone
		(layers "F.Cu" "In2.Cu" "In5.Cu")
		(hatch none 0.5)
		(connect_pads
			(clearance 0)
		)
		(min_thickness 0.25)
		(keepout
			(tracks not_allowed)
			(vias allowed)
			(pads allowed)
			(copperpour not_allowed)
			(footprints allowed)
		)
		(placement
			(enabled no)
			(sheetname "")
		)
		(fill yes
			(thermal_gap 0.5)
			(thermal_bridge_width 0.5)
			(island_removal_mode 0)
		)
		(polygon
			(pts
				(arc
					(start 120.18518 -42.800016)
					(mid 119.70004 -42.314876)
					(end 119.2149 -42.800016)
				)
				(arc
					(start 119.2149 -44.19981)
					(mid 119.698643 -44.685202)
					(end 120.18518 -44.202604)
				)
				(arc
					(start 120.09374 -44.202604)
					(mid 119.70004 -44.593772)
					(end 119.30634 -44.202604)
				)
				(arc
					(start 119.30634 -44.200064)
					(mid 119.70004 -43.806364)
					(end 120.09374 -44.200064)
				)
				(xy 120.18518 -44.200064) (xy 120.18518 -42.802556)
				(arc
					(start 120.09374 -42.802556)
					(mid 119.70004 -43.193724)
					(end 119.30634 -42.802556)
				)
				(arc
					(start 119.30634 -42.800016)
					(mid 119.70004 -42.406316)
					(end 120.09374 -42.800016)
				)
			)
		)
	)
	(zone
		(layer "B.Cu")
		(hatch none 0.5)
		(connect_pads
			(clearance 0)
		)
		(min_thickness 0.25)
		(keepout
			(tracks not_allowed)
			(vias allowed)
			(pads allowed)
			(copperpour not_allowed)
			(footprints allowed)
		)
		(placement
			(enabled no)
			(sheetname "")
		)
		(fill
			(thermal_gap 0.5)
			(thermal_bridge_width 0.5)
			(island_removal_mode 0)
		)
		(polygon
			(pts
				(arc
					(start 77.664818 -86.510622)
					(mid 77.283945 -86.129368)
					(end 76.902818 -86.510368)
				)
				(arc
					(start 76.902818 -87.399368)
					(mid 77.283818 -87.780368)
					(end 77.664818 -87.399368)
				)
				(xy 77.664818 -87.188548) (xy 77.615796 -87.188548)
				(arc
					(start 77.523086 -87.281512)
					(mid 77.095219 -87.587967)
					(end 77.401674 -87.1601)
				)
				(xy 77.544676 -87.017352) (xy 77.664818 -87.017352) (xy 77.664818 -86.877652) (xy 77.52969 -86.877652)
				(xy 77.52969 -86.877398)
				(arc
					(start 77.401674 -86.749636)
					(mid 77.095219 -86.321769)
					(end 77.523086 -86.628224)
				)
				(xy 77.60081 -86.705948) (xy 77.664818 -86.705948)
			)
		)
	)
	(zone
		(layer "B.Cu")
		(hatch none 0.5)
		(connect_pads
			(clearance 0)
		)
		(min_thickness 0.25)
		(keepout
			(tracks allowed)
			(vias allowed)
			(pads allowed)
			(copperpour allowed)
			(footprints allowed)
		)
		(placement
			(enabled no)
			(sheetname "")
		)
		(fill
			(thermal_gap 0.5)
			(thermal_bridge_width 0.5)
			(island_removal_mode 0)
		)
		(polygon
			(pts
				(xy 44.6532 -126.3142) (xy 45.3136 -126.3142) (xy 45.3136 -128.3716) (xy 44.6532 -128.3716)
			)
		)
	)
	(zone
		(layer "B.Cu")
		(hatch none 0.5)
		(connect_pads
			(clearance 0)
		)
		(min_thickness 0.25)
		(keepout
			(tracks not_allowed)
			(vias allowed)
			(pads allowed)
			(copperpour not_allowed)
			(footprints allowed)
		)
		(placement
			(enabled no)
			(sheetname "")
		)
		(fill
			(thermal_gap 0.5)
			(thermal_bridge_width 0.5)
			(island_removal_mode 0)
		)
		(polygon
			(pts
				(arc
					(start 77.664818 -92.911422)
					(mid 77.283945 -92.530168)
					(end 76.902818 -92.911168)
				)
				(arc
					(start 76.902818 -93.800168)
					(mid 77.283818 -94.181168)
					(end 77.664818 -93.800168)
				)
				(xy 77.664818 -93.596968) (xy 77.608176 -93.596968)
				(arc
					(start 77.523086 -93.682312)
					(mid 77.095219 -93.988767)
					(end 77.401674 -93.5609)
				)
				(xy 77.537056 -93.425772) (xy 77.664818 -93.425772) (xy 77.664818 -93.286072) (xy 77.53731 -93.286072)
				(xy 77.53731 -93.285818)
				(arc
					(start 77.401674 -93.150436)
					(mid 77.095219 -92.722569)
					(end 77.523086 -93.029024)
				)
				(xy 77.60843 -93.114368) (xy 77.664818 -93.114368)
			)
		)
	)
	(zone
		(layer "B.Cu")
		(hatch none 0.5)
		(connect_pads
			(clearance 0)
		)
		(min_thickness 0.25)
		(keepout
			(tracks not_allowed)
			(vias allowed)
			(pads allowed)
			(copperpour not_allowed)
			(footprints allowed)
		)
		(placement
			(enabled no)
			(sheetname "")
		)
		(fill
			(thermal_gap 0.5)
			(thermal_bridge_width 0.5)
			(island_removal_mode 0)
		)
		(polygon
			(pts
				(arc
					(start 138.185144 -32.00019)
					(mid 137.700004 -31.51505)
					(end 137.214864 -32.00019)
				)
				(xy 137.214864 -32.45866) (xy 137.53211 -32.45866)
				(arc
					(start 137.536682 -32.45866)
					(mid 137.590282 -32.437124)
					(end 137.614152 -32.384492)
				)
				(arc
					(start 137.614152 -32.384492)
					(mid 137.700004 -31.606415)
					(end 137.785856 -32.384492)
				)
				(xy 137.785856 -32.389064) (xy 137.785856 -32.41675)
				(arc
					(start 137.782808 -32.419544)
					(mid 137.71282 -32.557328)
					(end 137.575036 -32.627316)
				)
				(xy 137.572242 -32.630364) (xy 137.544556 -32.630364) (xy 137.536682 -32.630364) (xy 137.53211 -32.630364)
				(xy 137.214864 -32.630364) (xy 137.214864 -32.770064) (xy 137.53211 -32.770064) (xy 137.536682 -32.76981)
				(xy 137.544556 -32.770064) (xy 137.572242 -32.770064)
				(arc
					(start 137.575036 -32.772858)
					(mid 137.71282 -32.842846)
					(end 137.782808 -32.98063)
				)
				(xy 137.785856 -32.983424) (xy 137.785856 -33.01111)
				(arc
					(start 137.785856 -33.015682)
					(mid 137.700004 -33.793759)
					(end 137.614152 -33.015682)
				)
				(arc
					(start 137.614152 -33.015682)
					(mid 137.590331 -32.962999)
					(end 137.536682 -32.941514)
				)
				(xy 137.53211 -32.94126) (xy 137.214864 -32.94126)
				(arc
					(start 137.214864 -33.39973)
					(mid 137.699877 -33.885124)
					(end 138.185144 -33.399984)
				)
			)
		)
	)
	(zone
		(layer "B.Cu")
		(hatch none 0.5)
		(connect_pads
			(clearance 0)
		)
		(min_thickness 0.25)
		(keepout
			(tracks not_allowed)
			(vias allowed)
			(pads allowed)
			(copperpour not_allowed)
			(footprints allowed)
		)
		(placement
			(enabled no)
			(sheetname "")
		)
		(fill
			(thermal_gap 0.5)
			(thermal_bridge_width 0.5)
			(island_removal_mode 0)
		)
		(polygon
			(pts
				(arc
					(start 109.3851 -32.00019)
					(mid 108.89996 -31.51505)
					(end 108.41482 -32.00019)
				)
				(xy 108.41482 -32.45866) (xy 108.732066 -32.45866)
				(arc
					(start 108.736638 -32.45866)
					(mid 108.790238 -32.437124)
					(end 108.814108 -32.384492)
				)
				(arc
					(start 108.814108 -32.384492)
					(mid 108.89996 -31.606415)
					(end 108.985812 -32.384492)
				)
				(xy 108.985812 -32.389064) (xy 108.985812 -32.41675)
				(arc
					(start 108.982764 -32.419544)
					(mid 108.912776 -32.557328)
					(end 108.774992 -32.627316)
				)
				(xy 108.772198 -32.630364) (xy 108.744512 -32.630364) (xy 108.736638 -32.630364) (xy 108.732066 -32.630364)
				(xy 108.41482 -32.630364) (xy 108.41482 -32.770064) (xy 108.732066 -32.770064) (xy 108.736638 -32.76981)
				(xy 108.744512 -32.770064) (xy 108.772198 -32.770064)
				(arc
					(start 108.774992 -32.772858)
					(mid 108.912776 -32.842846)
					(end 108.982764 -32.98063)
				)
				(xy 108.985812 -32.983424) (xy 108.985812 -33.01111)
				(arc
					(start 108.985812 -33.015682)
					(mid 108.89996 -33.793759)
					(end 108.814108 -33.015682)
				)
				(arc
					(start 108.814108 -33.015682)
					(mid 108.790287 -32.962999)
					(end 108.736638 -32.941514)
				)
				(xy 108.732066 -32.94126) (xy 108.41482 -32.94126)
				(arc
					(start 108.41482 -33.39973)
					(mid 108.899833 -33.885124)
					(end 109.3851 -33.399984)
				)
			)
		)
	)
	(zone
		(layer "B.Cu")
		(hatch none 0.5)
		(connect_pads
			(clearance 0)
		)
		(min_thickness 0.25)
		(keepout
			(tracks allowed)
			(vias allowed)
			(pads allowed)
			(copperpour allowed)
			(footprints not_allowed)
		)
		(placement
			(enabled no)
			(sheetname "")
		)
		(fill
			(thermal_gap 0.5)
			(thermal_bridge_width 0.5)
			(island_removal_mode 0)
		)
		(polygon
			(pts
				(arc
					(start 13.24991 -120.000014)
					(mid 17.999964 -124.750068)
					(end 22.750018 -120.000014)
				)
				(arc
					(start 22.750018 -120.000014)
					(mid 17.999964 -115.24996)
					(end 13.24991 -120.000014)
				)
			)
		)
	)
	(zone
		(layer "B.Cu")
		(hatch none 0.5)
		(connect_pads
			(clearance 0)
		)
		(min_thickness 0.25)
		(keepout
			(tracks allowed)
			(vias allowed)
			(pads allowed)
			(copperpour allowed)
			(footprints not_allowed)
		)
		(placement
			(enabled no)
			(sheetname "")
		)
		(fill
			(thermal_gap 0.5)
			(thermal_bridge_width 0.5)
			(island_removal_mode 0)
		)
		(polygon
			(pts
				(arc
					(start 13.24991 -24.99995)
					(mid 17.999964 -29.750004)
					(end 22.750018 -24.99995)
				)
				(arc
					(start 22.750018 -24.99995)
					(mid 17.999964 -20.249896)
					(end 13.24991 -24.99995)
				)
			)
		)
	)
	(zone
		(net "GND")
		(layer "B.Cu")
		(hatch none 0.5)
		(connect_pads
			(clearance 0.5)
		)
		(min_thickness 0.25)
		(fill yes
			(thermal_gap 0.5)
			(thermal_bridge_width 0.5)
			(island_removal_mode 0)
		)
		(polygon
			(pts
				(xy 21.59 -178.2064) (xy 21.209 -178.5874) (xy 21.209 -179.9844) (xy 21.5646 -180.34) (xy 23.749 -180.34)
				(xy 24.1554 -179.9336) (xy 24.1554 -178.435) (xy 23.9268 -178.2064)
			)
		)
	)
	(zone
		(net "P12V_STBY")
		(layer "B.Cu")
		(hatch none 0.5)
		(connect_pads
			(clearance 0.5)
		)
		(min_thickness 0.25)
		(fill yes
			(thermal_gap 0.5)
			(thermal_bridge_width 0.5)
			(island_removal_mode 0)
		)
		(polygon
			(pts
				(xy 226.564698 -93.250512) (xy 223.161352 -96.653858) (xy 223.161352 -98.569018) (xy 222.625666 -99.104704)
				(xy 222.625666 -99.841812) (xy 222.699326 -99.915472) (xy 223.587564 -99.915472) (xy 223.657668 -99.845368)
				(xy 223.657668 -98.320606) (xy 224.12706 -97.851214) (xy 229.544626 -97.851214) (xy 229.749604 -97.646236)
				(xy 229.749604 -93.557598) (xy 229.442518 -93.250512)
			)
		)
	)
	(zone
		(layer "B.Cu")
		(hatch none 0.5)
		(connect_pads
			(clearance 0)
		)
		(min_thickness 0.25)
		(keepout
			(tracks not_allowed)
			(vias allowed)
			(pads allowed)
			(copperpour not_allowed)
			(footprints allowed)
		)
		(placement
			(enabled no)
			(sheetname "")
		)
		(fill
			(thermal_gap 0.5)
			(thermal_bridge_width 0.5)
			(island_removal_mode 0)
		)
		(polygon
			(pts
				(arc
					(start 154.750008 -120.000014)
					(mid 149.999954 -115.24996)
					(end 145.2499 -120.000014)
				)
				(arc
					(start 145.2499 -120.000014)
					(mid 149.999954 -124.750068)
					(end 154.750008 -120.000014)
				)
			)
		)
	)
	(zone
		(layer "B.Cu")
		(hatch none 0.5)
		(connect_pads
			(clearance 0)
		)
		(min_thickness 0.25)
		(keepout
			(tracks allowed)
			(vias allowed)
			(pads allowed)
			(copperpour allowed)
			(footprints allowed)
		)
		(placement
			(enabled no)
			(sheetname "")
		)
		(fill
			(thermal_gap 0.5)
			(thermal_bridge_width 0.5)
			(island_removal_mode 0)
		)
		(polygon
			(pts
				(xy 92.90558 -132.319014) (xy 94.117668 -132.319014) (xy 94.1578 -132.278882) (xy 94.1578 -131.291584)
				(xy 94.093538 -131.227322) (xy 92.953586 -131.227322) (xy 92.90558 -131.275328)
			)
		)
	)
	(zone
		(layer "B.Cu")
		(hatch none 0.5)
		(connect_pads
			(clearance 0)
		)
		(min_thickness 0.25)
		(keepout
			(tracks not_allowed)
			(vias allowed)
			(pads allowed)
			(copperpour not_allowed)
			(footprints allowed)
		)
		(placement
			(enabled no)
			(sheetname "")
		)
		(fill
			(thermal_gap 0.5)
			(thermal_bridge_width 0.5)
			(island_removal_mode 0)
		)
		(polygon
			(pts
				(arc
					(start 107.750102 -9.99998)
					(mid 103.000048 -5.249926)
					(end 98.249994 -9.99998)
				)
				(arc
					(start 98.249994 -9.99998)
					(mid 103.000048 -14.750034)
					(end 107.750102 -9.99998)
				)
			)
		)
	)
	(zone
		(net "GND")
		(layer "B.Cu")
		(hatch none 0.5)
		(connect_pads
			(clearance 0.5)
		)
		(min_thickness 0.25)
		(fill yes
			(thermal_gap 0.5)
			(thermal_bridge_width 0.5)
			(island_removal_mode 0)
		)
		(polygon
			(pts
				(xy 218.208352 -47.010574) (xy 217.938604 -47.280322) (xy 217.938604 -50.096674) (xy 218.154504 -50.312574)
				(xy 223.361504 -50.312574) (xy 223.949514 -49.724564) (xy 223.949514 -47.151036) (xy 223.809052 -47.010574)
			)
		)
	)
	(zone
		(net "GND")
		(layer "B.Cu")
		(hatch none 0.5)
		(connect_pads
			(clearance 0.5)
		)
		(min_thickness 0.25)
		(fill yes
			(thermal_gap 0.5)
			(thermal_bridge_width 0.5)
			(island_removal_mode 0)
		)
		(polygon
			(pts
				(xy 221.661228 -100.223828) (xy 221.121732 -100.763324) (xy 219.507054 -100.763324) (xy 219.381578 -100.8888)
				(xy 219.381578 -103.992172) (xy 219.805758 -104.416352) (xy 223.056958 -104.416352) (xy 223.355662 -104.715056)
				(xy 229.511606 -104.715056) (xy 229.885748 -104.340914) (xy 229.885748 -102.405688) (xy 229.799134 -102.319074)
				(xy 223.923098 -102.319074) (xy 223.711262 -102.107238) (xy 223.711262 -100.330508) (xy 223.604582 -100.223828)
			)
		)
	)
	(zone
		(layer "B.Cu")
		(hatch none 0.5)
		(connect_pads
			(clearance 0)
		)
		(min_thickness 0.25)
		(keepout
			(tracks allowed)
			(vias allowed)
			(pads allowed)
			(copperpour allowed)
			(footprints not_allowed)
		)
		(placement
			(enabled no)
			(sheetname "")
		)
		(fill
			(thermal_gap 0.5)
			(thermal_bridge_width 0.5)
			(island_removal_mode 0)
		)
		(polygon
			(pts
				(arc
					(start 217.749882 -187.999878)
					(mid 222.499936 -192.749932)
					(end 227.24999 -187.999878)
				)
				(arc
					(start 227.24999 -187.999878)
					(mid 222.499936 -183.249824)
					(end 217.749882 -187.999878)
				)
			)
		)
	)
	(zone
		(net "P1V8_STBY")
		(layer "B.Cu")
		(hatch none 0.5)
		(connect_pads
			(clearance 0.5)
		)
		(min_thickness 0.25)
		(fill yes
			(thermal_gap 0.5)
			(thermal_bridge_width 0.5)
			(island_removal_mode 0)
		)
		(polygon
			(pts
				(xy 177.10785 -119.503444) (xy 177.03165 -119.579644) (xy 177.03165 -120.824244) (xy 177.01895 -120.836944)
				(xy 177.01895 -121.167144) (xy 176.93005 -121.256044) (xy 176.59985 -121.256044) (xy 176.01565 -121.840244)
				(xy 176.01565 -122.954796) (xy 176.194212 -123.133358) (xy 176.995074 -123.133358) (xy 177.150776 -122.977656)
				(xy 177.150776 -121.721118) (xy 177.46345 -121.408444) (xy 177.46345 -119.554244) (xy 177.41265 -119.503444)
			)
		)
		(polygon
			(pts
				(xy 176.693576 -122.145806) (xy 176.490376 -122.145806) (xy 176.490376 -122.349006) (xy 176.693576 -122.349006)
			)
		)
		(polygon
			(pts
				(xy 176.693576 -121.587006) (xy 176.490376 -121.587006) (xy 176.490376 -121.790206) (xy 176.693576 -121.790206)
			)
		)
	)
	(zone
		(net "P1V15_STBY")
		(layer "B.Cu")
		(hatch none 0.5)
		(connect_pads
			(clearance 0.5)
		)
		(min_thickness 0.25)
		(fill yes
			(thermal_gap 0.5)
			(thermal_bridge_width 0.5)
			(island_removal_mode 0)
		)
		(polygon
			(pts
				(xy 57.3786 -130.7846) (xy 57.0738 -131.0894) (xy 57.0738 -131.6228) (xy 56.3372 -132.3594) (xy 48.4632 -132.3594)
				(xy 48.26 -132.5626) (xy 48.26 -133.604) (xy 48.6156 -133.9596) (xy 53.717952 -133.9596) (xy 53.956712 -133.72084)
				(xy 56.493918 -133.72084) (xy 57.324752 -132.890006) (xy 59.089798 -132.890006) (xy 59.2328 -132.747004)
				(xy 59.2328 -131.1656) (xy 58.8518 -130.7846)
			)
		)
		(polygon
			(pts
				(xy 55.9054 -133.1214) (xy 55.7022 -133.1214) (xy 55.7022 -133.3246) (xy 55.9054 -133.3246)
			)
		)
		(polygon
			(pts
				(xy 55.0418 -133.1214) (xy 54.8386 -133.1214) (xy 54.8386 -133.3246) (xy 55.0418 -133.3246)
			)
		)
		(polygon
			(pts
				(xy 54.6354 -133.1214) (xy 54.4322 -133.1214) (xy 54.4322 -133.3246) (xy 54.6354 -133.3246)
			)
		)
		(polygon
			(pts
				(xy 53.7718 -133.1214) (xy 53.5686 -133.1214) (xy 53.5686 -133.3246) (xy 53.7718 -133.3246)
			)
		)
		(polygon
			(pts
				(xy 53.3654 -133.1214) (xy 53.1622 -133.1214) (xy 53.1622 -133.3246) (xy 53.3654 -133.3246)
			)
		)
		(polygon
			(pts
				(xy 52.5018 -133.1214) (xy 52.2986 -133.1214) (xy 52.2986 -133.3246) (xy 52.5018 -133.3246)
			)
		)
		(polygon
			(pts
				(xy 52.0954 -133.1214) (xy 51.8922 -133.1214) (xy 51.8922 -133.3246) (xy 52.0954 -133.3246)
			)
		)
		(polygon
			(pts
				(xy 51.2318 -133.1214) (xy 51.0286 -133.1214) (xy 51.0286 -133.3246) (xy 51.2318 -133.3246)
			)
		)
		(polygon
			(pts
				(xy 50.8254 -133.1214) (xy 50.6222 -133.1214) (xy 50.6222 -133.3246) (xy 50.8254 -133.3246)
			)
		)
		(polygon
			(pts
				(xy 49.9618 -133.1214) (xy 49.7586 -133.1214) (xy 49.7586 -133.3246) (xy 49.9618 -133.3246)
			)
		)
	)
	(zone
		(layer "B.Cu")
		(hatch none 0.5)
		(connect_pads
			(clearance 0)
		)
		(min_thickness 0.25)
		(keepout
			(tracks allowed)
			(vias allowed)
			(pads allowed)
			(copperpour allowed)
			(footprints not_allowed)
		)
		(placement
			(enabled no)
			(sheetname "")
		)
		(fill
			(thermal_gap 0.5)
			(thermal_bridge_width 0.5)
			(island_removal_mode 0)
		)
		(polygon
			(pts
				(arc
					(start 209.14995 -51.250088)
					(mid 204.40015 -46.500288)
					(end 199.650096 -51.250088)
				)
				(arc
					(start 199.650096 -51.250088)
					(mid 204.40015 -56.000142)
					(end 209.14995 -51.250088)
				)
			)
		)
	)
	(zone
		(layer "B.Cu")
		(hatch none 0.5)
		(connect_pads
			(clearance 0)
		)
		(min_thickness 0.25)
		(keepout
			(tracks allowed)
			(vias allowed)
			(pads allowed)
			(copperpour allowed)
			(footprints not_allowed)
		)
		(placement
			(enabled no)
			(sheetname "")
		)
		(fill
			(thermal_gap 0.5)
			(thermal_bridge_width 0.5)
			(island_removal_mode 0)
		)
		(polygon
			(pts
				(arc
					(start 97.249996 -187.999878)
					(mid 92.499942 -183.249824)
					(end 87.749888 -187.999878)
				)
				(arc
					(start 87.749888 -187.999878)
					(mid 92.499942 -192.749932)
					(end 97.249996 -187.999878)
				)
			)
		)
	)
	(zone
		(layer "B.Cu")
		(hatch none 0.5)
		(connect_pads
			(clearance 0)
		)
		(min_thickness 0.25)
		(keepout
			(tracks allowed)
			(vias allowed)
			(pads allowed)
			(copperpour allowed)
			(footprints not_allowed)
		)
		(placement
			(enabled no)
			(sheetname "")
		)
		(fill
			(thermal_gap 0.5)
			(thermal_bridge_width 0.5)
			(island_removal_mode 0)
		)
		(polygon
			(pts
				(arc
					(start 84.749894 -120.000014)
					(mid 80.000094 -115.250214)
					(end 75.25004 -120.000014)
				)
				(arc
					(start 75.25004 -120.000014)
					(mid 80.000094 -124.750068)
					(end 84.749894 -120.000014)
				)
			)
		)
	)
	(zone
		(layer "B.Cu")
		(hatch none 0.5)
		(connect_pads
			(clearance 0)
		)
		(min_thickness 0.25)
		(keepout
			(tracks allowed)
			(vias allowed)
			(pads allowed)
			(copperpour allowed)
			(footprints not_allowed)
		)
		(placement
			(enabled no)
			(sheetname "")
		)
		(fill
			(thermal_gap 0.5)
			(thermal_bridge_width 0.5)
			(island_removal_mode 0)
		)
		(polygon
			(pts
				(arc
					(start 73.749916 -40.049958)
					(mid 78.49997 -44.800012)
					(end 83.250024 -40.049958)
				)
				(arc
					(start 83.250024 -40.049958)
					(mid 78.49997 -35.299904)
					(end 73.749916 -40.049958)
				)
			)
		)
	)
	(zone
		(net "GND")
		(layer "B.Cu")
		(hatch none 0.5)
		(connect_pads
			(clearance 0.5)
		)
		(min_thickness 0.25)
		(fill yes
			(thermal_gap 0.5)
			(thermal_bridge_width 0.5)
			(island_removal_mode 0)
		)
		(polygon
			(pts
				(xy 193.568828 -133.9342) (xy 193.516504 -133.986524) (xy 189.52464 -133.986524) (xy 189.36081 -134.150354)
				(xy 189.36081 -134.96925) (xy 188.735716 -135.594344) (xy 187.43422 -135.594344) (xy 187.170822 -135.857742)
				(xy 187.170822 -136.887458) (xy 187.270136 -136.986772) (xy 189.913006 -136.986772) (xy 190.296546 -136.603232)
				(xy 190.296546 -136.094724) (xy 190.831216 -135.560054) (xy 191.84366 -135.560054) (xy 191.990472 -135.706866)
				(xy 191.990472 -135.974074) (xy 192.348358 -136.33196) (xy 193.960496 -136.33196) (xy 194.132962 -136.159494)
				(xy 194.142868 -136.1694) (xy 194.9958 -136.1694) (xy 195.3006 -136.4742) (xy 195.3006 -137.4902)
				(xy 195.3514 -137.541) (xy 198.2216 -137.541) (xy 198.7804 -136.9822) (xy 198.7804 -134.0612) (xy 198.6534 -133.9342)
			)
		)
		(polygon
			(pts
				(xy 196.010276 -136.837674) (xy 195.807076 -136.837674) (xy 195.807076 -137.040874) (xy 196.010276 -137.040874)
			)
		)
		(polygon
			(pts
				(xy 196.863462 -134.49935) (xy 196.660262 -134.49935) (xy 196.660262 -134.70255) (xy 196.863462 -134.70255)
			)
		)
		(polygon
			(pts
				(xy 196.253862 -134.49935) (xy 196.050662 -134.49935) (xy 196.050662 -134.70255) (xy 196.253862 -134.70255)
			)
		)
		(polygon
			(pts
				(xy 195.847462 -134.49935) (xy 195.644262 -134.49935) (xy 195.644262 -134.70255) (xy 195.847462 -134.70255)
			)
		)
		(polygon
			(pts
				(xy 195.237862 -134.49935) (xy 195.034662 -134.49935) (xy 195.034662 -134.70255) (xy 195.237862 -134.70255)
			)
		)
		(polygon
			(pts
				(xy 194.831462 -134.49935) (xy 194.628262 -134.49935) (xy 194.628262 -134.70255) (xy 194.831462 -134.70255)
			)
		)
		(polygon
			(pts
				(xy 194.221862 -134.49935) (xy 194.018662 -134.49935) (xy 194.018662 -134.70255) (xy 194.221862 -134.70255)
			)
		)
		(polygon
			(pts
				(xy 193.54165 -134.491984) (xy 193.33845 -134.491984) (xy 193.33845 -134.695184) (xy 193.54165 -134.695184)
			)
		)
		(polygon
			(pts
				(xy 192.93205 -134.491984) (xy 192.72885 -134.491984) (xy 192.72885 -134.695184) (xy 192.93205 -134.695184)
			)
		)
		(polygon
			(pts
				(xy 192.52565 -134.491984) (xy 192.32245 -134.491984) (xy 192.32245 -134.695184) (xy 192.52565 -134.695184)
			)
		)
		(polygon
			(pts
				(xy 191.91605 -134.491984) (xy 191.71285 -134.491984) (xy 191.71285 -134.695184) (xy 191.91605 -134.695184)
			)
		)
	)
	(zone
		(net "GND")
		(layer "B.Cu")
		(hatch none 0.5)
		(connect_pads
			(clearance 0.5)
		)
		(min_thickness 0.25)
		(fill yes
			(thermal_gap 0.5)
			(thermal_bridge_width 0.5)
			(island_removal_mode 0)
		)
		(polygon
			(pts
				(xy 24.8412 -170.6626) (xy 24.4094 -171.0944) (xy 22.987 -171.0944) (xy 22.8854 -171.196) (xy 22.8854 -172.3136)
				(xy 22.3774 -172.8216) (xy 22.3774 -174.0916) (xy 22.5298 -174.244) (xy 25.4508 -174.244) (xy 25.8572 -173.8376)
				(xy 25.8572 -170.9166) (xy 25.6032 -170.6626)
			)
		)
		(polygon
			(pts
				(xy 23.0886 -173.2788) (xy 22.8854 -173.2788) (xy 22.8854 -173.482) (xy 23.0886 -173.482)
			)
		)
		(polygon
			(pts
				(xy 23.0886 -172.6692) (xy 22.8854 -172.6692) (xy 22.8854 -172.8724) (xy 23.0886 -172.8724)
			)
		)
		(polygon
			(pts
				(xy 23.8506 -172.3644) (xy 23.6474 -172.3644) (xy 23.6474 -172.5676) (xy 23.8506 -172.5676)
			)
		)
		(polygon
			(pts
				(xy 23.8506 -171.5008) (xy 23.6474 -171.5008) (xy 23.6474 -171.704) (xy 23.8506 -171.704)
			)
		)
	)
	(zone
		(layer "B.Cu")
		(hatch none 0.5)
		(connect_pads
			(clearance 0)
		)
		(min_thickness 0.25)
		(keepout
			(tracks allowed)
			(vias allowed)
			(pads allowed)
			(copperpour allowed)
			(footprints not_allowed)
		)
		(placement
			(enabled no)
			(sheetname "")
		)
		(fill
			(thermal_gap 0.5)
			(thermal_bridge_width 0.5)
			(island_removal_mode 0)
		)
		(polygon
			(pts
				(arc
					(start 73.799954 -105.050082)
					(mid 78.550008 -109.800136)
					(end 83.300062 -105.050082)
				)
				(arc
					(start 83.300062 -105.050082)
					(mid 78.550008 -100.300028)
					(end 73.799954 -105.050082)
				)
			)
		)
	)
	(zone
		(layer "B.Cu")
		(hatch none 0.5)
		(connect_pads
			(clearance 0)
		)
		(min_thickness 0.25)
		(keepout
			(tracks allowed)
			(vias allowed)
			(pads allowed)
			(copperpour allowed)
			(footprints allowed)
		)
		(placement
			(enabled no)
			(sheetname "")
		)
		(fill
			(thermal_gap 0.5)
			(thermal_bridge_width 0.5)
			(island_removal_mode 0)
		)
		(polygon
			(pts
				(xy 77.414628 -134.198106) (xy 77.414628 -133.56971) (xy 79.052928 -133.56971) (xy 79.052928 -134.198106)
			)
		)
	)
	(zone
		(layer "B.Cu")
		(hatch none 0.5)
		(connect_pads
			(clearance 0)
		)
		(min_thickness 0.25)
		(keepout
			(tracks allowed)
			(vias allowed)
			(pads allowed)
			(copperpour allowed)
			(footprints not_allowed)
		)
		(placement
			(enabled no)
			(sheetname "")
		)
		(fill
			(thermal_gap 0.5)
			(thermal_bridge_width 0.5)
			(island_removal_mode 0)
		)
		(polygon
			(pts
				(arc
					(start 37.69995 -169.999914)
					(mid 41.450006 -173.74997)
					(end 45.200062 -169.999914)
				)
				(arc
					(start 45.200062 -169.999914)
					(mid 41.450006 -166.249858)
					(end 37.69995 -169.999914)
				)
			)
		)
	)
	(zone
		(net "P3V3_STBY")
		(layer "B.Cu")
		(hatch none 0.5)
		(connect_pads
			(clearance 0.5)
		)
		(min_thickness 0.25)
		(fill yes
			(thermal_gap 0.5)
			(thermal_bridge_width 0.5)
			(island_removal_mode 0)
		)
		(polygon
			(pts
				(xy 64.529208 -154.3304) (xy 64.416178 -154.44343) (xy 64.416178 -155.310078) (xy 64.189356 -155.5369)
				(xy 61.0235 -155.5369) (xy 60.452 -156.1084) (xy 60.452 -157.274006) (xy 60.627006 -157.449012)
				(xy 65.02527 -157.449012) (xy 65.195704 -157.278578) (xy 65.195704 -156.107384) (xy 65.07099 -155.98267)
				(xy 65.07099 -154.42184) (xy 64.97955 -154.3304)
			)
		)
	)
	(zone
		(layer "B.Cu")
		(hatch none 0.5)
		(connect_pads
			(clearance 0)
		)
		(min_thickness 0.25)
		(keepout
			(tracks allowed)
			(vias allowed)
			(pads allowed)
			(copperpour allowed)
			(footprints not_allowed)
		)
		(placement
			(enabled no)
			(sheetname "")
		)
		(fill
			(thermal_gap 0.5)
			(thermal_bridge_width 0.5)
			(island_removal_mode 0)
		)
		(polygon
			(pts
				(arc
					(start 174.649892 -21.249894)
					(mid 179.399946 -25.999948)
					(end 184.15 -21.249894)
				)
				(arc
					(start 184.15 -21.249894)
					(mid 179.399946 -16.49984)
					(end 174.649892 -21.249894)
				)
			)
		)
	)
	(zone
		(layer "B.Cu")
		(hatch none 0.5)
		(connect_pads
			(clearance 0)
		)
		(min_thickness 0.25)
		(keepout
			(tracks not_allowed)
			(vias allowed)
			(pads allowed)
			(copperpour not_allowed)
			(footprints allowed)
		)
		(placement
			(enabled no)
			(sheetname "")
		)
		(fill
			(thermal_gap 0.5)
			(thermal_bridge_width 0.5)
			(island_removal_mode 0)
		)
		(polygon
			(pts
				(arc
					(start 22.750018 -24.99995)
					(mid 17.999964 -20.249896)
					(end 13.24991 -24.99995)
				)
				(arc
					(start 13.24991 -24.99995)
					(mid 17.999964 -29.750004)
					(end 22.750018 -24.99995)
				)
			)
		)
	)
	(zone
		(layer "B.Cu")
		(hatch none 0.5)
		(connect_pads
			(clearance 0)
		)
		(min_thickness 0.25)
		(keepout
			(tracks not_allowed)
			(vias allowed)
			(pads allowed)
			(copperpour not_allowed)
			(footprints allowed)
		)
		(placement
			(enabled no)
			(sheetname "")
		)
		(fill
			(thermal_gap 0.5)
			(thermal_bridge_width 0.5)
			(island_removal_mode 0)
		)
		(polygon
			(pts
				(arc
					(start 27.55011 -60.550044)
					(mid 22.800056 -55.79999)
					(end 18.050002 -60.550044)
				)
				(arc
					(start 18.050002 -60.550044)
					(mid 22.800056 -65.300098)
					(end 27.55011 -60.550044)
				)
			)
		)
	)
	(zone
		(layer "B.Cu")
		(hatch none 0.5)
		(connect_pads
			(clearance 0)
		)
		(min_thickness 0.25)
		(keepout
			(tracks not_allowed)
			(vias allowed)
			(pads allowed)
			(copperpour not_allowed)
			(footprints allowed)
		)
		(placement
			(enabled no)
			(sheetname "")
		)
		(fill
			(thermal_gap 0.5)
			(thermal_bridge_width 0.5)
			(island_removal_mode 0)
		)
		(polygon
			(pts
				(arc
					(start 227.24999 -7.999984)
					(mid 222.499936 -3.24993)
					(end 217.749882 -7.999984)
				)
				(arc
					(start 217.749882 -7.999984)
					(mid 222.499936 -12.750038)
					(end 227.24999 -7.999984)
				)
			)
		)
	)
	(zone
		(net "GND")
		(layer "B.Cu")
		(hatch none 0.5)
		(connect_pads
			(clearance 0.5)
		)
		(min_thickness 0.25)
		(fill yes
			(thermal_gap 0.5)
			(thermal_bridge_width 0.5)
			(island_removal_mode 0)
		)
		(polygon
			(pts
				(xy 58.039 -128.016) (xy 56.2356 -129.8194) (xy 51.495706 -129.8194) (xy 51.49088 -129.82448) (xy 50.0126 -129.82448)
				(xy 49.6062 -130.23088) (xy 49.6062 -131.699) (xy 49.7586 -131.8514) (xy 56.3118 -131.8514) (xy 56.769 -131.3942)
				(xy 56.769 -130.8354) (xy 57.1754 -130.429) (xy 58.5724 -130.429) (xy 58.667904 -130.333496) (xy 58.667904 -128.016)
			)
		)
		(polygon
			(pts
				(xy 55.9054 -130.8354) (xy 55.7022 -130.8354) (xy 55.7022 -131.0386) (xy 55.9054 -131.0386)
			)
		)
		(polygon
			(pts
				(xy 55.0418 -130.8354) (xy 54.8386 -130.8354) (xy 54.8386 -131.0386) (xy 55.0418 -131.0386)
			)
		)
		(polygon
			(pts
				(xy 54.6354 -130.8354) (xy 54.4322 -130.8354) (xy 54.4322 -131.0386) (xy 54.6354 -131.0386)
			)
		)
		(polygon
			(pts
				(xy 53.7718 -130.8354) (xy 53.5686 -130.8354) (xy 53.5686 -131.0386) (xy 53.7718 -131.0386)
			)
		)
		(polygon
			(pts
				(xy 53.3654 -130.8354) (xy 53.1622 -130.8354) (xy 53.1622 -131.0386) (xy 53.3654 -131.0386)
			)
		)
		(polygon
			(pts
				(xy 52.5018 -130.8354) (xy 52.2986 -130.8354) (xy 52.2986 -131.0386) (xy 52.5018 -131.0386)
			)
		)
		(polygon
			(pts
				(xy 52.0954 -130.8354) (xy 51.8922 -130.8354) (xy 51.8922 -131.0386) (xy 52.0954 -131.0386)
			)
		)
		(polygon
			(pts
				(xy 51.2318 -130.8354) (xy 51.0286 -130.8354) (xy 51.0286 -131.0386) (xy 51.2318 -131.0386)
			)
		)
		(polygon
			(pts
				(xy 50.8254 -130.8354) (xy 50.6222 -130.8354) (xy 50.6222 -131.0386) (xy 50.8254 -131.0386)
			)
		)
	)
	(zone
		(layer "B.Cu")
		(hatch none 0.5)
		(connect_pads
			(clearance 0)
		)
		(min_thickness 0.25)
		(keepout
			(tracks not_allowed)
			(vias allowed)
			(pads allowed)
			(copperpour not_allowed)
			(footprints allowed)
		)
		(placement
			(enabled no)
			(sheetname "")
		)
		(fill
			(thermal_gap 0.5)
			(thermal_bridge_width 0.5)
			(island_removal_mode 0)
		)
		(polygon
			(pts
				(arc
					(start 141.785086 -32.00019)
					(mid 141.299946 -31.51505)
					(end 140.814806 -32.00019)
				)
				(xy 140.814806 -32.45866) (xy 141.132052 -32.45866)
				(arc
					(start 141.136624 -32.45866)
					(mid 141.190224 -32.437124)
					(end 141.214094 -32.384492)
				)
				(arc
					(start 141.214094 -32.384492)
					(mid 141.299946 -31.606415)
					(end 141.385798 -32.384492)
				)
				(xy 141.385544 -32.389064) (xy 141.385544 -32.41675)
				(arc
					(start 141.38275 -32.419544)
					(mid 141.312762 -32.557328)
					(end 141.174978 -32.627316)
				)
				(xy 141.172184 -32.630364) (xy 141.144498 -32.630364) (xy 141.136624 -32.630364) (xy 141.132052 -32.630364)
				(xy 140.814806 -32.630364) (xy 140.814806 -32.770064) (xy 141.132052 -32.770064) (xy 141.136624 -32.76981)
				(xy 141.144498 -32.770064) (xy 141.172184 -32.770064)
				(arc
					(start 141.174978 -32.772858)
					(mid 141.312762 -32.842846)
					(end 141.38275 -32.98063)
				)
				(xy 141.385544 -32.983424) (xy 141.385544 -33.01111)
				(arc
					(start 141.385798 -33.015682)
					(mid 141.299946 -33.793759)
					(end 141.214094 -33.015682)
				)
				(arc
					(start 141.214094 -33.015682)
					(mid 141.190273 -32.962999)
					(end 141.136624 -32.941514)
				)
				(xy 141.132052 -32.94126) (xy 140.814806 -32.94126)
				(arc
					(start 140.814806 -33.39973)
					(mid 141.299819 -33.885124)
					(end 141.785086 -33.399984)
				)
			)
		)
	)
	(zone
		(layer "B.Cu")
		(hatch none 0.5)
		(connect_pads
			(clearance 0)
		)
		(min_thickness 0.25)
		(keepout
			(tracks not_allowed)
			(vias allowed)
			(pads allowed)
			(copperpour not_allowed)
			(footprints allowed)
		)
		(placement
			(enabled no)
			(sheetname "")
		)
		(fill
			(thermal_gap 0.5)
			(thermal_bridge_width 0.5)
			(island_removal_mode 0)
		)
		(polygon
			(pts
				(arc
					(start 111.185198 -33.20034)
					(mid 110.700185 -32.714946)
					(end 110.214918 -33.200086)
				)
				(xy 110.214918 -33.659064) (xy 110.53191 -33.659064)
				(arc
					(start 110.536482 -33.65881)
					(mid 110.590262 -33.637199)
					(end 110.614206 -33.584388)
				)
				(arc
					(start 110.614206 -33.584388)
					(mid 110.700058 -32.806311)
					(end 110.78591 -33.584388)
				)
				(xy 110.785656 -33.58896) (xy 110.785656 -33.616646)
				(arc
					(start 110.782862 -33.61944)
					(mid 110.712797 -33.757401)
					(end 110.574836 -33.827466)
				)
				(xy 110.572042 -33.83026) (xy 110.544356 -33.83026) (xy 110.536482 -33.830514) (xy 110.53191 -33.83026)
				(xy 110.214918 -33.83026) (xy 110.214918 -33.96996) (xy 110.532164 -33.96996) (xy 110.536736 -33.96996)
				(xy 110.54461 -33.96996) (xy 110.572296 -33.96996)
				(arc
					(start 110.57509 -33.973008)
					(mid 110.712874 -34.042996)
					(end 110.782862 -34.18078)
				)
				(xy 110.785656 -34.183574) (xy 110.785656 -34.21126)
				(arc
					(start 110.78591 -34.215832)
					(mid 110.700058 -34.993909)
					(end 110.614206 -34.215832)
				)
				(arc
					(start 110.614206 -34.215832)
					(mid 110.590385 -34.163149)
					(end 110.536736 -34.141664)
				)
				(xy 110.532164 -34.141664) (xy 110.214918 -34.141664)
				(arc
					(start 110.214918 -34.600134)
					(mid 110.700058 -35.085274)
					(end 111.185198 -34.600134)
				)
			)
		)
	)
	(zone
		(layer "B.Cu")
		(hatch none 0.5)
		(connect_pads
			(clearance 0)
		)
		(min_thickness 0.25)
		(keepout
			(tracks allowed)
			(vias allowed)
			(pads allowed)
			(copperpour allowed)
			(footprints not_allowed)
		)
		(placement
			(enabled no)
			(sheetname "")
		)
		(fill
			(thermal_gap 0.5)
			(thermal_bridge_width 0.5)
			(island_removal_mode 0)
		)
		(polygon
			(pts
				(arc
					(start 227.24999 -120.000014)
					(mid 222.499936 -115.24996)
					(end 217.749882 -120.000014)
				)
				(arc
					(start 217.749882 -120.000014)
					(mid 222.499936 -124.750068)
					(end 227.24999 -120.000014)
				)
			)
		)
	)
	(zone
		(layer "B.Cu")
		(hatch none 0.5)
		(connect_pads
			(clearance 0)
		)
		(min_thickness 0.25)
		(keepout
			(tracks allowed)
			(vias allowed)
			(pads allowed)
			(copperpour allowed)
			(footprints allowed)
		)
		(placement
			(enabled no)
			(sheetname "")
		)
		(fill
			(thermal_gap 0.5)
			(thermal_bridge_width 0.5)
			(island_removal_mode 0)
		)
		(polygon
			(pts
				(xy 177.5206 -124.333) (xy 178.2826 -124.333) (xy 178.4858 -124.1298) (xy 178.4858 -122.5804) (xy 178.9176 -122.1486)
				(xy 178.9176 -120.0404) (xy 177.3428 -120.0404) (xy 177.1396 -120.2436) (xy 175.6918 -120.2436)
				(xy 175.4632 -120.4722) (xy 175.4632 -120.8532) (xy 175.768 -121.158) (xy 176.7332 -121.158) (xy 177.419 -121.8438)
				(xy 177.419 -124.2314)
			)
		)
	)
	(zone
		(layer "B.Cu")
		(hatch none 0.5)
		(connect_pads
			(clearance 0)
		)
		(min_thickness 0.25)
		(keepout
			(tracks not_allowed)
			(vias allowed)
			(pads allowed)
			(copperpour not_allowed)
			(footprints allowed)
		)
		(placement
			(enabled no)
			(sheetname "")
		)
		(fill
			(thermal_gap 0.5)
			(thermal_bridge_width 0.5)
			(island_removal_mode 0)
		)
		(polygon
			(pts
				(arc
					(start 227.24999 -187.999878)
					(mid 222.499936 -183.249824)
					(end 217.749882 -187.999878)
				)
				(arc
					(start 217.749882 -187.999878)
					(mid 222.499936 -192.749932)
					(end 227.24999 -187.999878)
				)
			)
		)
	)
	(zone
		(net "GND")
		(layer "B.Cu")
		(hatch none 0.5)
		(connect_pads
			(clearance 0.5)
		)
		(min_thickness 0.25)
		(fill yes
			(thermal_gap 0.5)
			(thermal_bridge_width 0.5)
			(island_removal_mode 0)
		)
		(polygon
			(pts
				(xy 227.030788 -50.206656) (xy 226.759262 -50.478182) (xy 226.759262 -51.80076) (xy 226.076256 -52.483766)
				(xy 226.076256 -55.362856) (xy 226.3902 -55.6768) (xy 229.616 -55.6768) (xy 230.106982 -55.185818)
				(xy 230.106982 -50.603912) (xy 229.709726 -50.206656)
			)
		)
	)
	(zone
		(layer "B.Cu")
		(hatch none 0.5)
		(connect_pads
			(clearance 0)
		)
		(min_thickness 0.25)
		(keepout
			(tracks allowed)
			(vias allowed)
			(pads allowed)
			(copperpour allowed)
			(footprints not_allowed)
		)
		(placement
			(enabled no)
			(sheetname "")
		)
		(fill
			(thermal_gap 0.5)
			(thermal_bridge_width 0.5)
			(island_removal_mode 0)
		)
		(polygon
			(pts
				(arc
					(start 125.365002 -41.839896)
					(mid 124.160026 -40.63492)
					(end 122.95505 -41.839896)
				)
				(arc
					(start 122.95505 -41.839896)
					(mid 124.160026 -43.044872)
					(end 125.365002 -41.839896)
				)
			)
		)
	)
	(zone
		(layer "B.Cu")
		(hatch none 0.5)
		(connect_pads
			(clearance 0)
		)
		(min_thickness 0.25)
		(keepout
			(tracks not_allowed)
			(vias allowed)
			(pads allowed)
			(copperpour not_allowed)
			(footprints allowed)
		)
		(placement
			(enabled no)
			(sheetname "")
		)
		(fill
			(thermal_gap 0.5)
			(thermal_bridge_width 0.5)
			(island_removal_mode 0)
		)
		(polygon
			(pts
				(arc
					(start 22.750018 -120.000014)
					(mid 17.999964 -115.24996)
					(end 13.24991 -120.000014)
				)
				(arc
					(start 13.24991 -120.000014)
					(mid 17.999964 -124.750068)
					(end 22.750018 -120.000014)
				)
			)
		)
	)
	(zone
		(layer "B.Cu")
		(hatch none 0.5)
		(connect_pads
			(clearance 0)
		)
		(min_thickness 0.25)
		(keepout
			(tracks allowed)
			(vias allowed)
			(pads allowed)
			(copperpour allowed)
			(footprints allowed)
		)
		(placement
			(enabled no)
			(sheetname "")
		)
		(fill
			(thermal_gap 0.5)
			(thermal_bridge_width 0.5)
			(island_removal_mode 0)
		)
		(polygon
			(pts
				(xy 90.182954 -136.135618) (xy 91.695524 -136.135618) (xy 91.764358 -136.066784) (xy 91.764358 -135.717788)
				(xy 91.683332 -135.636762) (xy 90.171016 -135.636762) (xy 90.077544 -135.730234) (xy 90.077544 -136.030208)
			)
		)
	)
	(zone
		(net "P12V_STBY")
		(layer "B.Cu")
		(hatch none 0.5)
		(connect_pads
			(clearance 0.5)
		)
		(min_thickness 0.25)
		(fill yes
			(thermal_gap 0.5)
			(thermal_bridge_width 0.5)
			(island_removal_mode 0)
		)
		(polygon
			(pts
				(xy 77.216 -47.8536) (xy 77.1144 -47.9552) (xy 77.1144 -49.911) (xy 77.1906 -49.9872) (xy 79.6036 -49.9872)
				(xy 79.7052 -49.8856) (xy 79.7052 -48.133) (xy 79.4258 -47.8536)
			)
		)
	)
	(zone
		(net "P12V_STBY_VIN_U81")
		(layer "B.Cu")
		(hatch none 0.5)
		(connect_pads
			(clearance 0.5)
		)
		(min_thickness 0.25)
		(fill yes
			(thermal_gap 0.5)
			(thermal_bridge_width 0.5)
			(island_removal_mode 0)
		)
		(polygon
			(pts
				(xy 224.240852 -98.193352) (xy 224.046288 -98.387916) (xy 224.046288 -101.682804) (xy 224.380044 -102.01656)
				(xy 229.478586 -102.01656) (xy 229.769162 -101.725984) (xy 229.769162 -98.575368) (xy 229.387146 -98.193352)
			)
		)
	)
	(zone
		(layer "B.Cu")
		(hatch none 0.5)
		(connect_pads
			(clearance 0)
		)
		(min_thickness 0.25)
		(keepout
			(tracks not_allowed)
			(vias allowed)
			(pads allowed)
			(copperpour not_allowed)
			(footprints allowed)
		)
		(placement
			(enabled no)
			(sheetname "")
		)
		(fill
			(thermal_gap 0.5)
			(thermal_bridge_width 0.5)
			(island_removal_mode 0)
		)
		(polygon
			(pts
				(arc
					(start 227.24999 -153.999946)
					(mid 222.499936 -149.249892)
					(end 217.749882 -153.999946)
				)
				(arc
					(start 217.749882 -153.999946)
					(mid 222.499936 -158.75)
					(end 227.24999 -153.999946)
				)
			)
		)
	)
	(zone
		(net "GND")
		(layer "B.Cu")
		(hatch none 0.5)
		(connect_pads
			(clearance 0.5)
		)
		(min_thickness 0.25)
		(fill yes
			(thermal_gap 0.5)
			(thermal_bridge_width 0.5)
			(island_removal_mode 0)
		)
		(polygon
			(pts
				(xy 77.978 -57.3786) (xy 77.851 -57.5056) (xy 77.2922 -57.5056) (xy 77.2414 -57.5564) (xy 77.2414 -58.0898)
				(xy 77.2668 -58.1152) (xy 78.0288 -58.1152) (xy 78.2447 -58.3311) (xy 78.2447 -58.6867) (xy 80.2132 -60.6552)
				(xy 82.296 -60.6552) (xy 82.5246 -60.4266) (xy 82.5246 -57.4294) (xy 82.4738 -57.3786)
			)
		)
	)
	(zone
		(net "P3V3_STBY")
		(layer "B.Cu")
		(hatch none 0.5)
		(connect_pads
			(clearance 0.5)
		)
		(min_thickness 0.25)
		(fill yes
			(thermal_gap 0.5)
			(thermal_bridge_width 0.5)
			(island_removal_mode 0)
		)
		(polygon
			(pts
				(xy 50.341276 -117.401086) (xy 49.8983 -117.844062) (xy 49.8983 -119.1387) (xy 50.038 -119.2784)
				(xy 51.9176 -119.2784) (xy 52.1462 -119.0498) (xy 55.1688 -119.0498) (xy 55.2196 -118.999) (xy 55.2196 -118.3386)
				(xy 55.1434 -118.2624) (xy 54.102762 -118.2624) (xy 53.92166 -118.081298) (xy 53.239162 -117.401086)
			)
		)
		(polygon
			(pts
				(xy 54.258972 -118.387622) (xy 54.055772 -118.387622) (xy 54.055772 -118.590822) (xy 54.258972 -118.590822)
			)
		)
		(polygon
			(pts
				(xy 53.700172 -118.387622) (xy 53.496972 -118.387622) (xy 53.496972 -118.590822) (xy 53.700172 -118.590822)
			)
		)
	)
	(zone
		(net "GND")
		(layer "B.Cu")
		(hatch none 0.5)
		(connect_pads
			(clearance 0.5)
		)
		(min_thickness 0.25)
		(fill yes
			(thermal_gap 0.5)
			(thermal_bridge_width 0.5)
			(island_removal_mode 0)
		)
		(polygon
			(pts
				(xy 32.723074 -178.729386) (xy 32.410908 -179.041552) (xy 32.410908 -184.28716) (xy 32.66059 -184.536842)
				(xy 36.043362 -184.536842) (xy 36.28263 -184.297574) (xy 36.28263 -179.06238) (xy 35.949636 -178.729386)
			)
		)
	)
	(zone
		(net "P3V3_M2")
		(layer "B.Cu")
		(hatch none 0.5)
		(connect_pads
			(clearance 0.5)
		)
		(min_thickness 0.25)
		(fill yes
			(thermal_gap 0.5)
			(thermal_bridge_width 0.5)
			(island_removal_mode 0)
		)
		(polygon
			(pts
				(xy 218.03106 -68.195444) (xy 217.58148 -68.645024) (xy 217.58148 -79.122016) (xy 218.92387 -80.464406)
				(xy 224.032064 -80.464406) (xy 224.841308 -79.655162) (xy 224.841308 -68.268088) (xy 224.768664 -68.195444)
			)
		)
		(polygon
			(pts
				(xy 224.329244 -68.71843) (xy 224.126044 -68.71843) (xy 224.126044 -68.92163) (xy 224.329244 -68.92163)
			)
		)
	)
	(zone
		(net "P3V3_STBY")
		(layer "B.Cu")
		(hatch none 0.5)
		(connect_pads
			(clearance 0.5)
		)
		(min_thickness 0.25)
		(fill yes
			(thermal_gap 0.5)
			(thermal_bridge_width 0.5)
			(island_removal_mode 0)
		)
		(polygon
			(pts
				(xy 29.4386 -158.9024) (xy 29.2608 -159.0802) (xy 29.2608 -159.8422) (xy 30.988 -161.5694) (xy 32.3596 -161.5694)
				(xy 32.385 -161.544) (xy 32.385 -159.8676) (xy 32.2072 -159.6898) (xy 31.0134 -159.6898) (xy 30.226 -158.9024)
			)
		)
		(polygon
			(pts
				(xy 31.9278 -160.8836) (xy 31.7246 -160.8836) (xy 31.7246 -161.0868) (xy 31.9278 -161.0868)
			)
		)
		(polygon
			(pts
				(xy 31.9278 -160.401) (xy 31.7246 -160.401) (xy 31.7246 -160.6042) (xy 31.9278 -160.6042)
			)
		)
		(polygon
			(pts
				(xy 31.9278 -159.8422) (xy 31.7246 -159.8422) (xy 31.7246 -160.0454) (xy 31.9278 -160.0454)
			)
		)
	)
	(zone
		(layer "B.Cu")
		(hatch none 0.5)
		(connect_pads
			(clearance 0)
		)
		(min_thickness 0.25)
		(keepout
			(tracks allowed)
			(vias allowed)
			(pads allowed)
			(copperpour allowed)
			(footprints allowed)
		)
		(placement
			(enabled no)
			(sheetname "")
		)
		(fill
			(thermal_gap 0.5)
			(thermal_bridge_width 0.5)
			(island_removal_mode 0)
		)
		(polygon
			(pts
				(xy 63.213996 -161.23666) (xy 63.213996 -159.728408) (xy 63.919608 -159.728408) (xy 63.919608 -161.23666)
			)
		)
	)
	(zone
		(net "P3V3_STBY")
		(layer "B.Cu")
		(hatch none 0.5)
		(connect_pads
			(clearance 0.5)
		)
		(min_thickness 0.25)
		(fill yes
			(thermal_gap 0.5)
			(thermal_bridge_width 0.5)
			(island_removal_mode 0)
		)
		(polygon
			(pts
				(xy 49.194466 -141.4526) (xy 49.001934 -141.645132) (xy 49.001934 -142.32255) (xy 49.168304 -142.48892)
				(xy 51.35626 -142.48892) (xy 51.50358 -142.3416) (xy 51.8668 -142.3416) (xy 52.0446 -142.5194) (xy 52.0446 -144.22882)
				(xy 52.34178 -144.526) (xy 52.7558 -144.526) (xy 52.959 -144.3228) (xy 52.959 -141.7828) (xy 52.6288 -141.4526)
			)
		)
		(polygon
			(pts
				(xy 51.41214 -141.80566) (xy 51.20894 -141.80566) (xy 51.20894 -142.00886) (xy 51.41214 -142.00886)
			)
		)
		(polygon
			(pts
				(xy 50.85334 -141.80566) (xy 50.65014 -141.80566) (xy 50.65014 -142.00886) (xy 50.85334 -142.00886)
			)
		)
	)
	(zone
		(net "GND")
		(layer "B.Cu")
		(hatch none 0.5)
		(connect_pads
			(clearance 0.5)
		)
		(min_thickness 0.25)
		(fill yes
			(thermal_gap 0.5)
			(thermal_bridge_width 0.5)
			(island_removal_mode 0)
		)
		(polygon
			(pts
				(xy 79.883 -45.5676) (xy 79.7814 -45.6692) (xy 79.7814 -47.752) (xy 80.01 -47.9806) (xy 80.01 -50.1142)
				(xy 79.8322 -50.292) (xy 78.359 -50.292) (xy 78.2066 -50.4444) (xy 78.2066 -50.8762) (xy 77.9018 -51.181)
				(xy 77.343 -51.181) (xy 77.2414 -51.2826) (xy 77.2414 -52.5526) (xy 77.343 -52.6542) (xy 79.5528 -52.6542)
				(xy 80.7974 -51.4096) (xy 80.7974 -49.6824) (xy 81.0768 -49.403) (xy 81.4832 -49.403) (xy 81.534 -49.3522)
				(xy 81.534 -45.6946) (xy 81.407 -45.5676)
			)
		)
	)
	(zone
		(layer "B.Cu")
		(hatch none 0.5)
		(connect_pads
			(clearance 0)
		)
		(min_thickness 0.25)
		(keepout
			(tracks allowed)
			(vias allowed)
			(pads allowed)
			(copperpour allowed)
			(footprints not_allowed)
		)
		(placement
			(enabled no)
			(sheetname "")
		)
		(fill
			(thermal_gap 0.5)
			(thermal_bridge_width 0.5)
			(island_removal_mode 0)
		)
		(polygon
			(pts
				(arc
					(start 199.650096 -21.249894)
					(mid 204.40015 -25.999948)
					(end 209.14995 -21.249894)
				)
				(arc
					(start 209.14995 -21.249894)
					(mid 204.40015 -16.500094)
					(end 199.650096 -21.249894)
				)
			)
		)
	)
	(zone
		(net "U83_VREF2")
		(layer "B.Cu")
		(hatch none 0.5)
		(connect_pads
			(clearance 0.5)
		)
		(min_thickness 0.25)
		(fill yes
			(thermal_gap 0.5)
			(thermal_bridge_width 0.5)
			(island_removal_mode 0)
		)
		(polygon
			(pts
				(xy 176.9872 -112.014) (xy 176.7078 -112.2934) (xy 176.7078 -115.951) (xy 176.3522 -116.3066) (xy 176.3522 -117.7544)
				(xy 176.4538 -117.856) (xy 177.3682 -117.856) (xy 177.3936 -117.8306) (xy 177.3936 -114.5794) (xy 177.6349 -114.3381)
				(xy 177.6349 -112.0775) (xy 177.5714 -112.014)
			)
		)
		(polygon
			(pts
				(xy 177.14595 -113.483644) (xy 176.94275 -113.483644) (xy 176.94275 -113.686844) (xy 177.14595 -113.686844)
			)
		)
		(polygon
			(pts
				(xy 177.14595 -112.874044) (xy 176.94275 -112.874044) (xy 176.94275 -113.077244) (xy 177.14595 -113.077244)
			)
		)
		(polygon
			(pts
				(xy 177.1904 -112.4712) (xy 176.9872 -112.4712) (xy 176.9872 -112.6744) (xy 177.1904 -112.6744)
			)
		)
	)
	(zone
		(layer "B.Cu")
		(hatch none 0.5)
		(connect_pads
			(clearance 0)
		)
		(min_thickness 0.25)
		(keepout
			(tracks not_allowed)
			(vias allowed)
			(pads allowed)
			(copperpour not_allowed)
			(footprints allowed)
		)
		(placement
			(enabled no)
			(sheetname "")
		)
		(fill
			(thermal_gap 0.5)
			(thermal_bridge_width 0.5)
			(island_removal_mode 0)
		)
		(polygon
			(pts
				(arc
					(start 120.18518 -42.800016)
					(mid 119.70004 -42.314876)
					(end 119.2149 -42.800016)
				)
				(arc
					(start 119.2149 -44.19981)
					(mid 119.699913 -44.685204)
					(end 120.18518 -44.200064)
				)
				(xy 120.18518 -43.74134) (xy 119.867934 -43.74134)
				(arc
					(start 119.863362 -43.741594)
					(mid 119.809762 -43.76313)
					(end 119.785892 -43.815762)
				)
				(arc
					(start 119.785892 -43.815762)
					(mid 119.70004 -44.593839)
					(end 119.614188 -43.815762)
				)
				(xy 119.614188 -43.81119) (xy 119.614188 -43.783504)
				(arc
					(start 119.617236 -43.78071)
					(mid 119.687224 -43.642926)
					(end 119.825008 -43.572938)
				)
				(xy 119.827802 -43.570144) (xy 119.855488 -43.570144) (xy 119.863362 -43.56989) (xy 119.867934 -43.570144)
				(xy 120.18518 -43.570144) (xy 120.18518 -43.430444) (xy 119.868188 -43.430444) (xy 119.863616 -43.430444)
				(xy 119.855742 -43.430444) (xy 119.828056 -43.430444)
				(arc
					(start 119.825262 -43.427396)
					(mid 119.687301 -43.357331)
					(end 119.617236 -43.21937)
				)
				(xy 119.614188 -43.216576) (xy 119.614188 -43.18889)
				(arc
					(start 119.614188 -43.184318)
					(mid 119.70004 -42.406241)
					(end 119.785892 -43.184318)
				)
				(arc
					(start 119.785892 -43.184318)
					(mid 119.809787 -43.23718)
					(end 119.863616 -43.25874)
				)
				(xy 119.868188 -43.25874) (xy 120.18518 -43.25874)
			)
		)
	)
	(zone
		(net "DDR_VREF")
		(layer "B.Cu")
		(hatch none 0.5)
		(connect_pads
			(clearance 0.5)
		)
		(min_thickness 0.25)
		(fill yes
			(thermal_gap 0.5)
			(thermal_bridge_width 0.5)
			(island_removal_mode 0)
		)
		(polygon
			(pts
				(xy 43.621706 -145.481802) (xy 43.230292 -145.873216) (xy 42.6974 -145.873216) (xy 42.62755 -145.943066)
				(xy 42.62755 -146.249644) (xy 42.678858 -146.300952) (xy 43.076368 -146.300952) (xy 43.255184 -146.479768)
				(xy 43.255184 -149.371304) (xy 43.313604 -149.429724) (xy 44.074334 -149.429724) (xy 44.102782 -149.401276)
				(xy 44.102782 -145.560542) (xy 44.024042 -145.481802)
			)
		)
		(polygon
			(pts
				(xy 43.612308 -145.988532) (xy 43.409108 -145.988532) (xy 43.409108 -146.191732) (xy 43.612308 -146.191732)
			)
		)
	)
	(zone
		(layer "B.Cu")
		(hatch none 0.5)
		(connect_pads
			(clearance 0)
		)
		(min_thickness 0.25)
		(keepout
			(tracks not_allowed)
			(vias allowed)
			(pads allowed)
			(copperpour not_allowed)
			(footprints allowed)
		)
		(placement
			(enabled no)
			(sheetname "")
		)
		(fill
			(thermal_gap 0.5)
			(thermal_bridge_width 0.5)
			(island_removal_mode 0)
		)
		(polygon
			(pts
				(arc
					(start 120.18518 -32.00019)
					(mid 119.70004 -31.51505)
					(end 119.2149 -32.00019)
				)
				(xy 119.2149 -32.45866) (xy 119.532146 -32.45866)
				(arc
					(start 119.536718 -32.45866)
					(mid 119.590318 -32.437124)
					(end 119.614188 -32.384492)
				)
				(arc
					(start 119.614188 -32.384492)
					(mid 119.70004 -31.606415)
					(end 119.785892 -32.384492)
				)
				(xy 119.785892 -32.389064) (xy 119.785892 -32.41675)
				(arc
					(start 119.782844 -32.419544)
					(mid 119.712856 -32.557328)
					(end 119.575072 -32.627316)
				)
				(xy 119.572278 -32.630364) (xy 119.544592 -32.630364) (xy 119.536718 -32.630364) (xy 119.532146 -32.630364)
				(xy 119.2149 -32.630364) (xy 119.2149 -32.770064) (xy 119.532146 -32.770064) (xy 119.536718 -32.76981)
				(xy 119.544592 -32.770064) (xy 119.572278 -32.770064)
				(arc
					(start 119.575072 -32.772858)
					(mid 119.712856 -32.842846)
					(end 119.782844 -32.98063)
				)
				(xy 119.785892 -32.983424) (xy 119.785892 -33.01111)
				(arc
					(start 119.785892 -33.015682)
					(mid 119.70004 -33.793759)
					(end 119.614188 -33.015682)
				)
				(arc
					(start 119.614188 -33.015682)
					(mid 119.590367 -32.962999)
					(end 119.536718 -32.941514)
				)
				(xy 119.532146 -32.94126) (xy 119.2149 -32.94126)
				(arc
					(start 119.2149 -33.39973)
					(mid 119.699913 -33.885124)
					(end 120.18518 -33.399984)
				)
			)
		)
	)
	(zone
		(layer "B.Cu")
		(hatch none 0.5)
		(connect_pads
			(clearance 0)
		)
		(min_thickness 0.25)
		(keepout
			(tracks allowed)
			(vias allowed)
			(pads allowed)
			(copperpour allowed)
			(footprints not_allowed)
		)
		(placement
			(enabled no)
			(sheetname "")
		)
		(fill
			(thermal_gap 0.5)
			(thermal_bridge_width 0.5)
			(island_removal_mode 0)
		)
		(polygon
			(pts
				(arc
					(start 199.650096 -51.250088)
					(mid 204.40015 -56.000142)
					(end 209.14995 -51.250088)
				)
				(arc
					(start 209.14995 -51.250088)
					(mid 204.40015 -46.500288)
					(end 199.650096 -51.250088)
				)
			)
		)
	)
	(zone
		(net "GND")
		(layer "B.Cu")
		(hatch none 0.5)
		(connect_pads
			(clearance 0.5)
		)
		(min_thickness 0.25)
		(fill yes
			(thermal_gap 0.5)
			(thermal_bridge_width 0.5)
			(island_removal_mode 0)
		)
		(polygon
			(pts
				(xy 46.654974 -141.404594) (xy 46.27245 -141.787118) (xy 46.27245 -142.53591) (xy 46.501558 -142.765018)
				(xy 46.501558 -143.670782) (xy 46.37913 -143.79321) (xy 45.589952 -143.79321) (xy 45.42917 -143.953992)
				(xy 45.42917 -144.58061) (xy 45.66158 -144.81302) (xy 45.66158 -146.70786) (xy 45.81652 -146.8628)
				(xy 47.84598 -146.8628) (xy 48.25492 -147.27174) (xy 48.25492 -148.45284) (xy 48.34382 -148.54174)
				(xy 49.35982 -148.54174) (xy 49.472088 -148.654008) (xy 50.430684 -148.654008) (xy 50.505614 -148.579078)
				(xy 50.505614 -147.813776) (xy 49.9618 -147.269962) (xy 49.302162 -147.269962) (xy 48.934116 -146.901916)
				(xy 48.934116 -146.247612) (xy 49.06391 -146.117818) (xy 50.312066 -146.117818) (xy 50.58918 -145.840704)
				(xy 50.597816 -145.840704) (xy 50.799746 -145.638774) (xy 50.799746 -144.052798) (xy 50.457354 -143.710406)
				(xy 49.740566 -143.710406) (xy 49.57572 -143.54556) (xy 49.57572 -142.769082) (xy 49.449482 -142.642844)
				(xy 48.949102 -142.642844) (xy 48.76546 -142.459202) (xy 48.76546 -141.588744) (xy 48.58131 -141.404594)
			)
		)
		(polygon
			(pts
				(xy 49.71542 -147.66036) (xy 49.51222 -147.66036) (xy 49.51222 -147.86356) (xy 49.71542 -147.86356)
			)
		)
		(polygon
			(pts
				(xy 49.324006 -147.45335) (xy 49.120806 -147.45335) (xy 49.120806 -147.65655) (xy 49.324006 -147.65655)
			)
		)
		(polygon
			(pts
				(xy 46.63567 -145.717514) (xy 46.43247 -145.717514) (xy 46.43247 -145.920714) (xy 46.63567 -145.920714)
			)
		)
		(polygon
			(pts
				(xy 49.76622 -145.58518) (xy 49.56302 -145.58518) (xy 49.56302 -145.78838) (xy 49.76622 -145.78838)
			)
		)
		(polygon
			(pts
				(xy 50.62982 -144.72158) (xy 50.42662 -144.72158) (xy 50.42662 -144.92478) (xy 50.62982 -144.92478)
			)
		)
		(polygon
			(pts
				(xy 49.76622 -144.72158) (xy 49.56302 -144.72158) (xy 49.56302 -144.92478) (xy 49.76622 -144.92478)
			)
		)
		(polygon
			(pts
				(xy 46.544992 -144.665954) (xy 46.341792 -144.665954) (xy 46.341792 -144.869154) (xy 46.544992 -144.869154)
			)
		)
		(polygon
			(pts
				(xy 50.39106 -144.272) (xy 50.18786 -144.272) (xy 50.18786 -144.4752) (xy 50.39106 -144.4752)
			)
		)
		(polygon
			(pts
				(xy 49.83226 -144.272) (xy 49.62906 -144.272) (xy 49.62906 -144.4752) (xy 49.83226 -144.4752)
			)
		)
		(polygon
			(pts
				(xy 47.871634 -142.36954) (xy 47.668434 -142.36954) (xy 47.668434 -142.57274) (xy 47.871634 -142.57274)
			)
		)
	)
	(zone
		(layer "B.Cu")
		(hatch none 0.5)
		(connect_pads
			(clearance 0)
		)
		(min_thickness 0.25)
		(keepout
			(tracks allowed)
			(vias allowed)
			(pads allowed)
			(copperpour allowed)
			(footprints not_allowed)
		)
		(placement
			(enabled no)
			(sheetname "")
		)
		(fill
			(thermal_gap 0.5)
			(thermal_bridge_width 0.5)
			(island_removal_mode 0)
		)
		(polygon
			(pts
				(arc
					(start 154.750008 -120.000014)
					(mid 149.999954 -115.24996)
					(end 145.2499 -120.000014)
				)
				(arc
					(start 145.2499 -120.000014)
					(mid 149.999954 -124.750068)
					(end 154.750008 -120.000014)
				)
			)
		)
	)
	(zone
		(net "GND")
		(layer "B.Cu")
		(hatch none 0.5)
		(connect_pads
			(clearance 0.5)
		)
		(min_thickness 0.25)
		(fill yes
			(thermal_gap 0.5)
			(thermal_bridge_width 0.5)
			(island_removal_mode 0)
		)
		(polygon
			(pts
				(xy 152.933654 -9.898126) (xy 152.682448 -10.149332) (xy 152.682448 -12.596368) (xy 153.05913 -12.97305)
				(xy 154.815794 -12.97305) (xy 155.479242 -12.309602) (xy 155.479242 -10.220706) (xy 155.156662 -9.898126)
			)
		)
	)
	(zone
		(layer "B.Cu")
		(hatch none 0.5)
		(connect_pads
			(clearance 0)
		)
		(min_thickness 0.25)
		(keepout
			(tracks allowed)
			(vias allowed)
			(pads allowed)
			(copperpour allowed)
			(footprints not_allowed)
		)
		(placement
			(enabled no)
			(sheetname "")
		)
		(fill
			(thermal_gap 0.5)
			(thermal_bridge_width 0.5)
			(island_removal_mode 0)
		)
		(polygon
			(pts
				(arc
					(start 127.16002 -34.85007)
					(mid 124.160026 -31.850076)
					(end 121.160032 -34.85007)
				)
				(arc
					(start 121.160032 -34.85007)
					(mid 124.160026 -37.850064)
					(end 127.16002 -34.85007)
				)
			)
		)
	)
	(zone
		(net "U82_VREF2")
		(layer "B.Cu")
		(hatch none 0.5)
		(connect_pads
			(clearance 0.5)
		)
		(min_thickness 0.25)
		(fill yes
			(thermal_gap 0.5)
			(thermal_bridge_width 0.5)
			(island_removal_mode 0)
		)
		(polygon
			(pts
				(xy 206.7814 -99.7204) (xy 206.6798 -99.822) (xy 206.6798 -102.108) (xy 206.7052 -102.1334) (xy 206.629 -102.2096)
				(xy 206.629 -102.6922) (xy 206.2734 -103.0478) (xy 206.0448 -103.0478) (xy 205.994 -103.0986) (xy 205.994 -104.902)
				(xy 207.01 -104.902) (xy 207.0608 -104.8512) (xy 207.0608 -104.4194) (xy 207.0354 -104.394) (xy 207.0354 -102.9462)
				(xy 207.264 -102.7176) (xy 207.264 -102.108) (xy 207.3402 -102.0318) (xy 207.3402 -101.7778) (xy 207.4672 -101.6508)
				(xy 208.0006 -101.6508) (xy 208.3816 -101.2698) (xy 208.3816 -99.8474) (xy 208.2546 -99.7204)
			)
		)
		(polygon
			(pts
				(xy 207.501236 -100.193348) (xy 207.298036 -100.193348) (xy 207.298036 -100.396548) (xy 207.501236 -100.396548)
			)
		)
		(polygon
			(pts
				(xy 207.8736 -100.1522) (xy 207.6704 -100.1522) (xy 207.6704 -100.3554) (xy 207.8736 -100.3554)
			)
		)
	)
	(zone
		(layer "B.Cu")
		(hatch none 0.5)
		(connect_pads
			(clearance 0)
		)
		(min_thickness 0.25)
		(keepout
			(tracks allowed)
			(vias allowed)
			(pads allowed)
			(copperpour allowed)
			(footprints not_allowed)
		)
		(placement
			(enabled no)
			(sheetname "")
		)
		(fill
			(thermal_gap 0.5)
			(thermal_bridge_width 0.5)
			(island_removal_mode 0)
		)
		(polygon
			(pts
				(arc
					(start 22.750018 -24.99995)
					(mid 17.999964 -20.249896)
					(end 13.24991 -24.99995)
				)
				(arc
					(start 13.24991 -24.99995)
					(mid 17.999964 -29.750004)
					(end 22.750018 -24.99995)
				)
			)
		)
	)
	(zone
		(layer "B.Cu")
		(hatch none 0.5)
		(connect_pads
			(clearance 0)
		)
		(min_thickness 0.25)
		(keepout
			(tracks allowed)
			(vias allowed)
			(pads allowed)
			(copperpour allowed)
			(footprints not_allowed)
		)
		(placement
			(enabled no)
			(sheetname "")
		)
		(fill
			(thermal_gap 0.5)
			(thermal_bridge_width 0.5)
			(island_removal_mode 0)
		)
		(polygon
			(pts
				(arc
					(start 7.750048 -187.999878)
					(mid 12.500102 -192.749932)
					(end 17.249902 -187.999878)
				)
				(arc
					(start 17.249902 -187.999878)
					(mid 12.500102 -183.250078)
					(end 7.750048 -187.999878)
				)
			)
		)
	)
	(zone
		(layer "B.Cu")
		(hatch none 0.5)
		(connect_pads
			(clearance 0)
		)
		(min_thickness 0.25)
		(keepout
			(tracks allowed)
			(vias allowed)
			(pads allowed)
			(copperpour allowed)
			(footprints not_allowed)
		)
		(placement
			(enabled no)
			(sheetname "")
		)
		(fill
			(thermal_gap 0.5)
			(thermal_bridge_width 0.5)
			(island_removal_mode 0)
		)
		(polygon
			(pts
				(arc
					(start 22.750018 -120.000014)
					(mid 17.999964 -115.24996)
					(end 13.24991 -120.000014)
				)
				(arc
					(start 13.24991 -120.000014)
					(mid 17.999964 -124.750068)
					(end 22.750018 -120.000014)
				)
			)
		)
	)
	(zone
		(layer "B.Cu")
		(hatch none 0.5)
		(connect_pads
			(clearance 0)
		)
		(min_thickness 0.25)
		(keepout
			(tracks allowed)
			(vias allowed)
			(pads allowed)
			(copperpour allowed)
			(footprints allowed)
		)
		(placement
			(enabled no)
			(sheetname "")
		)
		(fill
			(thermal_gap 0.5)
			(thermal_bridge_width 0.5)
			(island_removal_mode 0)
		)
		(polygon
			(pts
				(xy 86.958424 -168.324784) (xy 88.470994 -168.324784) (xy 88.539828 -168.25595) (xy 88.539828 -167.906954)
				(xy 88.458802 -167.825928) (xy 86.946486 -167.825928) (xy 86.853014 -167.9194) (xy 86.853014 -168.219374)
			)
		)
	)
	(zone
		(net "P1V2_STBY")
		(layer "B.Cu")
		(hatch none 0.5)
		(connect_pads
			(clearance 0.5)
		)
		(min_thickness 0.25)
		(fill yes
			(thermal_gap 0.5)
			(thermal_bridge_width 0.5)
			(island_removal_mode 0)
		)
		(polygon
			(pts
				(xy 14.682978 -145.850356) (xy 14.585696 -145.947638) (xy 14.585696 -146.654266) (xy 14.383766 -146.856196)
				(xy 13.648436 -146.856196) (xy 13.442442 -147.06219) (xy 13.442442 -147.926806) (xy 13.167614 -148.201634)
				(xy 13.167614 -149.760686) (xy 13.61186 -150.204932) (xy 15.270734 -150.204932) (xy 15.904464 -149.571202)
				(xy 15.904464 -147.332954) (xy 15.997428 -147.23999) (xy 17.376902 -147.23999) (xy 17.534382 -147.08251)
				(xy 17.534382 -146.306794) (xy 17.449546 -146.221958) (xy 16.924274 -146.221958) (xy 16.552672 -145.850356)
			)
		)
		(polygon
			(pts
				(xy 16.8783 -146.8628) (xy 16.6751 -146.8628) (xy 16.6751 -147.066) (xy 16.8783 -147.066)
			)
		)
		(polygon
			(pts
				(xy 16.0147 -146.8628) (xy 15.8115 -146.8628) (xy 15.8115 -147.066) (xy 16.0147 -147.066)
			)
		)
		(polygon
			(pts
				(xy 15.24 -146.4437) (xy 15.0368 -146.4437) (xy 15.0368 -146.6469) (xy 15.24 -146.6469)
			)
		)
		(polygon
			(pts
				(xy 16.0147 -145.9992) (xy 15.8115 -145.9992) (xy 15.8115 -146.2024) (xy 16.0147 -146.2024)
			)
		)
	)
	(zone
		(net "P1V15_STBY")
		(layer "B.Cu")
		(hatch none 0.5)
		(connect_pads
			(clearance 0.5)
		)
		(min_thickness 0.25)
		(fill yes
			(thermal_gap 0.5)
			(thermal_bridge_width 0.5)
			(island_removal_mode 0)
		)
		(polygon
			(pts
				(xy 45.18533 -146.9898) (xy 45.085762 -147.089368) (xy 45.085762 -149.174962) (xy 45.2882 -149.3774)
				(xy 46.0248 -149.3774) (xy 46.8122 -148.59) (xy 47.8917 -148.59) (xy 47.96028 -148.52142) (xy 47.96028 -147.21078)
				(xy 47.7393 -146.9898)
			)
		)
		(polygon
			(pts
				(xy 46.63567 -148.003514) (xy 46.43247 -148.003514) (xy 46.43247 -148.206714) (xy 46.63567 -148.206714)
			)
		)
		(polygon
			(pts
				(xy 45.77207 -148.003514) (xy 45.56887 -148.003514) (xy 45.56887 -148.206714) (xy 45.77207 -148.206714)
			)
		)
		(polygon
			(pts
				(xy 47.038006 -147.45335) (xy 46.834806 -147.45335) (xy 46.834806 -147.65655) (xy 47.038006 -147.65655)
			)
		)
		(polygon
			(pts
				(xy 46.63567 -147.139914) (xy 46.43247 -147.139914) (xy 46.43247 -147.343114) (xy 46.63567 -147.343114)
			)
		)
		(polygon
			(pts
				(xy 45.77207 -147.139914) (xy 45.56887 -147.139914) (xy 45.56887 -147.343114) (xy 45.77207 -147.343114)
			)
		)
	)
	(zone
		(layer "B.Cu")
		(hatch none 0.5)
		(connect_pads
			(clearance 0)
		)
		(min_thickness 0.25)
		(keepout
			(tracks allowed)
			(vias allowed)
			(pads allowed)
			(copperpour allowed)
			(footprints not_allowed)
		)
		(placement
			(enabled no)
			(sheetname "")
		)
		(fill
			(thermal_gap 0.5)
			(thermal_bridge_width 0.5)
			(island_removal_mode 0)
		)
		(polygon
			(pts
				(arc
					(start 98.249994 -9.99998)
					(mid 103.000048 -14.750034)
					(end 107.750102 -9.99998)
				)
				(arc
					(start 107.750102 -9.99998)
					(mid 103.000048 -5.249926)
					(end 98.249994 -9.99998)
				)
			)
		)
	)
	(zone
		(layer "B.Cu")
		(hatch none 0.5)
		(connect_pads
			(clearance 0)
		)
		(min_thickness 0.25)
		(keepout
			(tracks allowed)
			(vias allowed)
			(pads allowed)
			(copperpour allowed)
			(footprints allowed)
		)
		(placement
			(enabled no)
			(sheetname "")
		)
		(fill
			(thermal_gap 0.5)
			(thermal_bridge_width 0.5)
			(island_removal_mode 0)
		)
		(polygon
			(pts
				(xy 202.4888 -124.333) (xy 203.2762 -124.333) (xy 203.4794 -124.1298) (xy 203.4794 -122.555) (xy 203.8858 -122.1486)
				(xy 203.8858 -120.1166) (xy 203.8096 -120.0404) (xy 202.6158 -120.0404) (xy 202.1078 -120.5484)
				(xy 200.6854 -120.5484) (xy 200.5076 -120.7262) (xy 200.5076 -121.3358) (xy 200.5584 -121.3866)
				(xy 200.6346 -121.3866) (xy 200.66 -121.3612) (xy 202.0824 -121.3612) (xy 202.4888 -121.7676)
			)
		)
	)
	(zone
		(net "P12V_STBY")
		(layer "B.Cu")
		(hatch none 0.5)
		(connect_pads
			(clearance 0.5)
		)
		(min_thickness 0.25)
		(fill yes
			(thermal_gap 0.5)
			(thermal_bridge_width 0.5)
			(island_removal_mode 0)
		)
		(polygon
			(pts
				(xy 128.7526 -6.9596) (xy 128.744472 -6.967728) (xy 127.600964 -6.967728) (xy 126.293118 -8.275574)
				(xy 125.188472 -8.275574) (xy 125.105922 -8.358124) (xy 125.105922 -9.95045) (xy 125.268228 -10.112756)
				(xy 125.563122 -10.112756) (xy 125.56744 -10.108438) (xy 125.791976 -10.108438) (xy 126.014734 -10.331196)
				(xy 126.014734 -11.051032) (xy 126.064518 -11.100816) (xy 128.575816 -11.100816) (xy 129.2352 -11.7602)
				(xy 130.530092 -11.7602) (xy 132.930646 -14.160754) (xy 135.394954 -14.160754) (xy 139.907264 -18.673064)
				(xy 140.0937 -18.673064) (xy 141.09446 -19.673824) (xy 148.080984 -19.673824) (xy 148.083016 -19.675856)
				(xy 150.76043 -19.675856) (xy 151.382476 -19.05381) (xy 151.382476 -16.946118) (xy 151.1681 -16.731742)
				(xy 147.788884 -16.731742) (xy 138.016742 -6.9596)
			)
		)
		(polygon
			(pts
				(xy 126.674372 -10.441178) (xy 126.471172 -10.441178) (xy 126.471172 -10.644378) (xy 126.674372 -10.644378)
			)
		)
		(polygon
			(pts
				(xy 125.77064 -9.800082) (xy 125.56744 -9.800082) (xy 125.56744 -10.003282) (xy 125.77064 -10.003282)
			)
		)
		(polygon
			(pts
				(xy 125.77064 -9.241282) (xy 125.56744 -9.241282) (xy 125.56744 -9.444482) (xy 125.77064 -9.444482)
			)
		)
		(polygon
			(pts
				(xy 125.7681 -8.758174) (xy 125.5649 -8.758174) (xy 125.5649 -8.961374) (xy 125.7681 -8.961374)
			)
		)
	)
	(zone
		(layer "B.Cu")
		(hatch none 0.5)
		(connect_pads
			(clearance 0)
		)
		(min_thickness 0.25)
		(keepout
			(tracks not_allowed)
			(vias allowed)
			(pads allowed)
			(copperpour not_allowed)
			(footprints allowed)
		)
		(placement
			(enabled no)
			(sheetname "")
		)
		(fill
			(thermal_gap 0.5)
			(thermal_bridge_width 0.5)
			(island_removal_mode 0)
		)
		(polygon
			(pts
				(arc
					(start 184.15 -21.249894)
					(mid 179.399946 -16.49984)
					(end 174.649892 -21.249894)
				)
				(arc
					(start 174.649892 -21.249894)
					(mid 179.399946 -25.999948)
					(end 184.15 -21.249894)
				)
			)
		)
	)
	(zone
		(layer "B.Cu")
		(hatch none 0.5)
		(connect_pads
			(clearance 0)
		)
		(min_thickness 0.25)
		(keepout
			(tracks allowed)
			(vias allowed)
			(pads allowed)
			(copperpour allowed)
			(footprints not_allowed)
		)
		(placement
			(enabled no)
			(sheetname "")
		)
		(fill
			(thermal_gap 0.5)
			(thermal_bridge_width 0.5)
			(island_removal_mode 0)
		)
		(polygon
			(pts
				(arc
					(start 83.300062 -105.050082)
					(mid 78.550008 -100.300028)
					(end 73.799954 -105.050082)
				)
				(arc
					(start 73.799954 -105.050082)
					(mid 78.550008 -109.800136)
					(end 83.300062 -105.050082)
				)
			)
		)
	)
	(zone
		(layer "B.Cu")
		(hatch none 0.5)
		(connect_pads
			(clearance 0)
		)
		(min_thickness 0.25)
		(keepout
			(tracks allowed)
			(vias allowed)
			(pads allowed)
			(copperpour allowed)
			(footprints not_allowed)
		)
		(placement
			(enabled no)
			(sheetname "")
		)
		(fill
			(thermal_gap 0.5)
			(thermal_bridge_width 0.5)
			(island_removal_mode 0)
		)
		(polygon
			(pts
				(arc
					(start 45.200062 -169.999914)
					(mid 41.450006 -166.249858)
					(end 37.69995 -169.999914)
				)
				(arc
					(start 37.69995 -169.999914)
					(mid 41.450006 -173.74997)
					(end 45.200062 -169.999914)
				)
			)
		)
	)
	(zone
		(layer "B.Cu")
		(hatch none 0.5)
		(connect_pads
			(clearance 0)
		)
		(min_thickness 0.25)
		(keepout
			(tracks allowed)
			(vias allowed)
			(pads allowed)
			(copperpour allowed)
			(footprints allowed)
		)
		(placement
			(enabled no)
			(sheetname "")
		)
		(fill
			(thermal_gap 0.5)
			(thermal_bridge_width 0.5)
			(island_removal_mode 0)
		)
		(polygon
			(pts
				(xy 62.8142 -141.9606) (xy 62.8142 -140.8684) (xy 64.1858 -140.8684) (xy 64.1858 -141.9606)
			)
		)
	)
	(zone
		(layer "B.Cu")
		(hatch none 0.5)
		(connect_pads
			(clearance 0)
		)
		(min_thickness 0.25)
		(keepout
			(tracks not_allowed)
			(vias allowed)
			(pads allowed)
			(copperpour not_allowed)
			(footprints allowed)
		)
		(placement
			(enabled no)
			(sheetname "")
		)
		(fill
			(thermal_gap 0.5)
			(thermal_bridge_width 0.5)
			(island_removal_mode 0)
		)
		(polygon
			(pts
				(arc
					(start 209.14995 -51.250088)
					(mid 204.40015 -46.500288)
					(end 199.650096 -51.250088)
				)
				(arc
					(start 199.650096 -51.250088)
					(mid 204.40015 -56.000142)
					(end 209.14995 -51.250088)
				)
			)
		)
	)
	(zone
		(layer "B.Cu")
		(hatch none 0.5)
		(connect_pads
			(clearance 0)
		)
		(min_thickness 0.25)
		(keepout
			(tracks not_allowed)
			(vias allowed)
			(pads allowed)
			(copperpour not_allowed)
			(footprints allowed)
		)
		(placement
			(enabled no)
			(sheetname "")
		)
		(fill
			(thermal_gap 0.5)
			(thermal_bridge_width 0.5)
			(island_removal_mode 0)
		)
		(polygon
			(pts
				(arc
					(start 78.503018 -76.909422)
					(mid 78.122145 -76.528168)
					(end 77.741018 -76.909168)
				)
				(arc
					(start 77.741018 -77.798168)
					(mid 78.122018 -78.179168)
					(end 78.503018 -77.798168)
				)
				(xy 78.503018 -77.594968) (xy 78.446376 -77.594968)
				(arc
					(start 78.361286 -77.680312)
					(mid 77.933419 -77.986767)
					(end 78.239874 -77.5589)
				)
				(xy 78.375256 -77.423772) (xy 78.503018 -77.423772) (xy 78.503018 -77.284072) (xy 78.37551 -77.284072)
				(xy 78.37551 -77.283818)
				(arc
					(start 78.239874 -77.148436)
					(mid 77.933419 -76.720569)
					(end 78.361286 -77.027024)
				)
				(xy 78.44663 -77.112368) (xy 78.503018 -77.112368)
			)
		)
	)
	(zone
		(net "GND")
		(layer "B.Cu")
		(hatch none 0.5)
		(connect_pads
			(clearance 0.5)
		)
		(min_thickness 0.25)
		(fill yes
			(thermal_gap 0.5)
			(thermal_bridge_width 0.5)
			(island_removal_mode 0)
		)
		(polygon
			(pts
				(xy 96.2914 -152.5778) (xy 95.95993 -152.90927) (xy 92.416376 -152.90927) (xy 92.338906 -152.98674)
				(xy 90.95486 -152.98674) (xy 89.8144 -154.1272) (xy 89.8144 -156.718) (xy 90.805 -157.7086) (xy 92.583 -157.7086)
				(xy 93.276674 -158.402274) (xy 94.175326 -158.402274) (xy 94.237302 -158.340298) (xy 94.237302 -157.730698)
				(xy 94.4626 -157.5054) (xy 95.123 -157.5054) (xy 95.4278 -157.2006) (xy 95.631 -157.2006) (xy 95.758 -157.0736)
				(xy 95.758 -154.7622) (xy 96.266 -154.2542) (xy 96.647 -154.2542) (xy 97.282 -153.6192) (xy 97.282 -152.781)
				(xy 97.0788 -152.5778)
			)
		)
		(polygon
			(pts
				(xy 93.59392 -157.692344) (xy 93.39072 -157.692344) (xy 93.39072 -157.895544) (xy 93.59392 -157.895544)
			)
		)
		(polygon
			(pts
				(xy 95.30461 -156.44495) (xy 95.10141 -156.44495) (xy 95.10141 -156.64815) (xy 95.30461 -156.64815)
			)
		)
		(polygon
			(pts
				(xy 90.5256 -155.8544) (xy 90.3224 -155.8544) (xy 90.3224 -156.0576) (xy 90.5256 -156.0576)
			)
		)
		(polygon
			(pts
				(xy 90.5256 -155.1432) (xy 90.3224 -155.1432) (xy 90.3224 -155.3464) (xy 90.5256 -155.3464)
			)
		)
		(polygon
			(pts
				(xy 95.9358 -153.797) (xy 95.7326 -153.797) (xy 95.7326 -154.0002) (xy 95.9358 -154.0002)
			)
		)
		(polygon
			(pts
				(xy 95.0722 -153.797) (xy 94.869 -153.797) (xy 94.869 -154.0002) (xy 95.0722 -154.0002)
			)
		)
		(polygon
			(pts
				(xy 92.3544 -153.4922) (xy 92.1512 -153.4922) (xy 92.1512 -153.6954) (xy 92.3544 -153.6954)
			)
		)
		(polygon
			(pts
				(xy 91.6432 -153.4922) (xy 91.44 -153.4922) (xy 91.44 -153.6954) (xy 91.6432 -153.6954)
			)
		)
		(polygon
			(pts
				(xy 93.83268 -153.406856) (xy 93.62948 -153.406856) (xy 93.62948 -153.610056) (xy 93.83268 -153.610056)
			)
		)
		(polygon
			(pts
				(xy 93.12148 -153.406856) (xy 92.91828 -153.406856) (xy 92.91828 -153.610056) (xy 93.12148 -153.610056)
			)
		)
		(polygon
			(pts
				(xy 96.901 -153.035) (xy 96.6978 -153.035) (xy 96.6978 -153.2382) (xy 96.901 -153.2382)
			)
		)
		(polygon
			(pts
				(xy 96.3422 -153.035) (xy 96.139 -153.035) (xy 96.139 -153.2382) (xy 96.3422 -153.2382)
			)
		)
	)
	(zone
		(layer "B.Cu")
		(hatch none 0.5)
		(connect_pads
			(clearance 0)
		)
		(min_thickness 0.25)
		(keepout
			(tracks not_allowed)
			(vias allowed)
			(pads allowed)
			(copperpour not_allowed)
			(footprints allowed)
		)
		(placement
			(enabled no)
			(sheetname "")
		)
		(fill
			(thermal_gap 0.5)
			(thermal_bridge_width 0.5)
			(island_removal_mode 0)
		)
		(polygon
			(pts
				(arc
					(start 77.664818 -80.109822)
					(mid 77.283945 -79.728568)
					(end 76.902818 -80.109568)
				)
				(arc
					(start 76.902818 -80.998568)
					(mid 77.283818 -81.379568)
					(end 77.664818 -80.998568)
				)
				(xy 77.664818 -80.795368) (xy 77.608176 -80.795368)
				(arc
					(start 77.523086 -80.880712)
					(mid 77.095219 -81.187167)
					(end 77.401674 -80.7593)
				)
				(xy 77.537056 -80.624172) (xy 77.664818 -80.624172) (xy 77.664818 -80.484472) (xy 77.53731 -80.484472)
				(xy 77.53731 -80.484218)
				(arc
					(start 77.401674 -80.348836)
					(mid 77.095219 -79.920969)
					(end 77.523086 -80.227424)
				)
				(xy 77.60843 -80.312768) (xy 77.664818 -80.312768)
			)
		)
	)
	(zone
		(layer "B.Cu")
		(hatch none 0.5)
		(connect_pads
			(clearance 0)
		)
		(min_thickness 0.25)
		(keepout
			(tracks allowed)
			(vias allowed)
			(pads allowed)
			(copperpour allowed)
			(footprints not_allowed)
		)
		(placement
			(enabled no)
			(sheetname "")
		)
		(fill
			(thermal_gap 0.5)
			(thermal_bridge_width 0.5)
			(island_removal_mode 0)
		)
		(polygon
			(pts
				(arc
					(start 227.24999 -7.999984)
					(mid 222.499936 -3.24993)
					(end 217.749882 -7.999984)
				)
				(arc
					(start 217.749882 -7.999984)
					(mid 222.499936 -12.750038)
					(end 227.24999 -7.999984)
				)
			)
		)
	)
	(zone
		(layer "B.Cu")
		(hatch none 0.5)
		(connect_pads
			(clearance 0)
		)
		(min_thickness 0.25)
		(keepout
			(tracks allowed)
			(vias allowed)
			(pads allowed)
			(copperpour allowed)
			(footprints not_allowed)
		)
		(placement
			(enabled no)
			(sheetname "")
		)
		(fill
			(thermal_gap 0.5)
			(thermal_bridge_width 0.5)
			(island_removal_mode 0)
		)
		(polygon
			(pts
				(arc
					(start 217.749882 -7.999984)
					(mid 222.499936 -12.750038)
					(end 227.24999 -7.999984)
				)
				(arc
					(start 227.24999 -7.999984)
					(mid 222.499936 -3.24993)
					(end 217.749882 -7.999984)
				)
			)
		)
	)
	(zone
		(net "GND")
		(layer "B.Cu")
		(hatch none 0.5)
		(connect_pads
			(clearance 0.5)
		)
		(min_thickness 0.25)
		(fill yes
			(thermal_gap 0.5)
			(thermal_bridge_width 0.5)
			(island_removal_mode 0)
		)
		(polygon
			(pts
				(xy 171.44492 -118.157244) (xy 170.844972 -118.757192) (xy 170.844972 -120.181624) (xy 171.208446 -120.545098)
				(xy 173.57852 -120.545098) (xy 173.580044 -120.546622) (xy 174.401988 -120.546622) (xy 175.109378 -121.254012)
				(xy 175.109378 -123.585478) (xy 175.107346 -123.585478) (xy 175.107346 -123.990608) (xy 175.1076 -123.990862)
				(xy 175.1076 -127.738886) (xy 175.26 -127.891286) (xy 176.5046 -127.891286) (xy 176.7078 -127.688086)
				(xy 176.7078 -123.881134) (xy 175.790606 -122.96394) (xy 175.790606 -121.740422) (xy 176.417224 -121.113804)
				(xy 176.812448 -121.113804) (xy 176.871122 -121.05513) (xy 176.871122 -119.558562) (xy 176.72812 -119.41556)
				(xy 176.072546 -119.41556) (xy 175.791368 -119.696738) (xy 174.800006 -119.696738) (xy 174.236126 -119.132858)
				(xy 174.236126 -118.405402) (xy 173.987968 -118.157244)
			)
		)
		(polygon
			(pts
				(xy 175.8188 -127.256286) (xy 175.6156 -127.256286) (xy 175.6156 -127.459486) (xy 175.8188 -127.459486)
			)
		)
		(polygon
			(pts
				(xy 175.8188 -126.646686) (xy 175.6156 -126.646686) (xy 175.6156 -126.849886) (xy 175.8188 -126.849886)
			)
		)
		(polygon
			(pts
				(xy 175.8188 -126.316486) (xy 175.6156 -126.316486) (xy 175.6156 -126.519686) (xy 175.8188 -126.519686)
			)
		)
		(polygon
			(pts
				(xy 175.8188 -125.706886) (xy 175.6156 -125.706886) (xy 175.6156 -125.910086) (xy 175.8188 -125.910086)
			)
		)
		(polygon
			(pts
				(xy 175.63465 -120.201944) (xy 175.43145 -120.201944) (xy 175.43145 -120.405144) (xy 175.63465 -120.405144)
			)
		)
		(polygon
			(pts
				(xy 175.02505 -120.201944) (xy 174.82185 -120.201944) (xy 174.82185 -120.405144) (xy 175.02505 -120.405144)
			)
		)
	)
	(zone
		(net "GND")
		(layer "B.Cu")
		(hatch none 0.5)
		(connect_pads
			(clearance 0.5)
		)
		(min_thickness 0.25)
		(fill yes
			(thermal_gap 0.5)
			(thermal_bridge_width 0.5)
			(island_removal_mode 0)
		)
		(polygon
			(pts
				(xy 173.111668 -130.8862) (xy 172.980604 -131.017264) (xy 172.980604 -132.38226) (xy 173.157896 -132.559552)
				(xy 178.449224 -132.559552) (xy 178.638454 -132.748782) (xy 179.28209 -132.748782) (xy 179.632356 -132.398516)
				(xy 179.632356 -131.214622) (xy 179.413662 -130.995928) (xy 176.623218 -130.995928) (xy 176.51349 -130.8862)
			)
		)
		(polygon
			(pts
				(xy 175.090836 -131.393184) (xy 174.887636 -131.393184) (xy 174.887636 -131.596384) (xy 175.090836 -131.596384)
			)
		)
		(polygon
			(pts
				(xy 176.604168 -131.384548) (xy 176.400968 -131.384548) (xy 176.400968 -131.587748) (xy 176.604168 -131.587748)
			)
		)
		(polygon
			(pts
				(xy 175.994568 -131.384548) (xy 175.791368 -131.384548) (xy 175.700436 -131.393184) (xy 175.497236 -131.393184)
				(xy 175.497236 -131.596384) (xy 175.700436 -131.596384) (xy 175.791368 -131.587748) (xy 175.994568 -131.587748)
			)
		)
		(polygon
			(pts
				(xy 174.776384 -131.380738) (xy 174.573184 -131.380738) (xy 174.573184 -131.583938) (xy 174.776384 -131.583938)
			)
		)
		(polygon
			(pts
				(xy 174.166784 -131.380738) (xy 173.963584 -131.380738) (xy 173.963584 -131.583938) (xy 174.166784 -131.583938)
			)
		)
	)
	(zone
		(layer "B.Cu")
		(hatch none 0.5)
		(connect_pads
			(clearance 0)
		)
		(min_thickness 0.25)
		(keepout
			(tracks not_allowed)
			(vias allowed)
			(pads allowed)
			(copperpour not_allowed)
			(footprints allowed)
		)
		(placement
			(enabled no)
			(sheetname "")
		)
		(fill
			(thermal_gap 0.5)
			(thermal_bridge_width 0.5)
			(island_removal_mode 0)
		)
		(polygon
			(pts
				(arc
					(start 107.585002 -33.20034)
					(mid 107.099989 -32.714946)
					(end 106.614722 -33.200086)
				)
				(xy 106.614722 -33.659064) (xy 106.931714 -33.659064)
				(arc
					(start 106.936286 -33.65881)
					(mid 106.990066 -33.637199)
					(end 107.01401 -33.584388)
				)
				(arc
					(start 107.01401 -33.584388)
					(mid 107.099862 -32.806311)
					(end 107.185714 -33.584388)
				)
				(xy 107.18546 -33.58896) (xy 107.18546 -33.616646)
				(arc
					(start 107.182666 -33.61944)
					(mid 107.112601 -33.757401)
					(end 106.97464 -33.827466)
				)
				(xy 106.971846 -33.83026) (xy 106.94416 -33.83026) (xy 106.936286 -33.830514) (xy 106.931714 -33.83026)
				(xy 106.614722 -33.83026) (xy 106.614722 -33.96996) (xy 106.931968 -33.96996) (xy 106.93654 -33.96996)
				(xy 106.944414 -33.96996) (xy 106.9721 -33.96996)
				(arc
					(start 106.974894 -33.973008)
					(mid 107.112678 -34.042996)
					(end 107.182666 -34.18078)
				)
				(xy 107.18546 -34.183574) (xy 107.18546 -34.21126)
				(arc
					(start 107.185714 -34.215832)
					(mid 107.099862 -34.993909)
					(end 107.01401 -34.215832)
				)
				(arc
					(start 107.01401 -34.215832)
					(mid 106.990189 -34.163149)
					(end 106.93654 -34.141664)
				)
				(xy 106.931968 -34.141664) (xy 106.614722 -34.141664)
				(arc
					(start 106.614722 -34.600134)
					(mid 107.099862 -35.085274)
					(end 107.585002 -34.600134)
				)
			)
		)
	)
	(zone
		(layer "B.Cu")
		(hatch none 0.5)
		(connect_pads
			(clearance 0)
		)
		(min_thickness 0.25)
		(keepout
			(tracks allowed)
			(vias allowed)
			(pads allowed)
			(copperpour allowed)
			(footprints not_allowed)
		)
		(placement
			(enabled no)
			(sheetname "")
		)
		(fill
			(thermal_gap 0.5)
			(thermal_bridge_width 0.5)
			(island_removal_mode 0)
		)
		(polygon
			(pts
				(arc
					(start 160.250124 -153.999946)
					(mid 155.50007 -149.249892)
					(end 150.750016 -153.999946)
				)
				(arc
					(start 150.750016 -153.999946)
					(mid 155.50007 -158.75)
					(end 160.250124 -153.999946)
				)
			)
		)
	)
	(zone
		(net "GND")
		(layer "B.Cu")
		(hatch none 0.5)
		(connect_pads
			(clearance 0.5)
		)
		(min_thickness 0.25)
		(fill yes
			(thermal_gap 0.5)
			(thermal_bridge_width 0.5)
			(island_removal_mode 0)
		)
		(polygon
			(pts
				(xy 19.530822 -143.398494) (xy 19.422618 -143.506698) (xy 19.422618 -144.45234) (xy 19.240754 -144.634204)
				(xy 17.969484 -144.634204) (xy 17.760188 -144.8435) (xy 17.760188 -145.1102) (xy 17.455388 -145.415)
				(xy 17.0434 -145.415) (xy 16.891 -145.5674) (xy 16.891 -145.923) (xy 17.0434 -146.0754) (xy 17.54124 -146.0754)
				(xy 17.7038 -146.23796) (xy 17.7038 -146.812) (xy 17.78 -146.8882) (xy 18.2372 -146.8882) (xy 18.3134 -146.812)
				(xy 18.3134 -146.3548) (xy 18.5166 -146.1516) (xy 20.02155 -146.1516) (xy 20.521422 -145.651728)
				(xy 20.521422 -143.513556) (xy 20.40636 -143.398494)
			)
		)
		(polygon
			(pts
				(xy 20.281138 -143.987266) (xy 20.077938 -143.987266) (xy 20.077938 -144.190466) (xy 20.281138 -144.190466)
			)
		)
	)
	(zone
		(net "GND")
		(layer "B.Cu")
		(hatch none 0.5)
		(connect_pads
			(clearance 0.5)
		)
		(min_thickness 0.25)
		(fill yes
			(thermal_gap 0.5)
			(thermal_bridge_width 0.5)
			(island_removal_mode 0)
		)
		(polygon
			(pts
				(xy 198.198994 -130.54203) (xy 198.073518 -130.667506) (xy 198.073518 -132.116322) (xy 198.327518 -132.370322)
				(xy 204.845412 -132.370322) (xy 205.173072 -132.042662) (xy 205.173072 -130.861308) (xy 204.853794 -130.54203)
			)
		)
		(polygon
			(pts
				(xy 202.251818 -131.051808) (xy 202.048618 -131.051808) (xy 202.048618 -131.255008) (xy 202.251818 -131.255008)
			)
		)
		(polygon
			(pts
				(xy 201.642218 -131.051808) (xy 201.439018 -131.051808) (xy 201.439018 -131.255008) (xy 201.642218 -131.255008)
			)
		)
		(polygon
			(pts
				(xy 201.235818 -131.051808) (xy 201.032618 -131.051808) (xy 201.032618 -131.255008) (xy 201.235818 -131.255008)
			)
		)
		(polygon
			(pts
				(xy 200.626218 -131.051808) (xy 200.423018 -131.051808) (xy 200.423018 -131.255008) (xy 200.626218 -131.255008)
			)
		)
		(polygon
			(pts
				(xy 200.219818 -131.051808) (xy 200.016618 -131.051808) (xy 200.016618 -131.255008) (xy 200.219818 -131.255008)
			)
		)
		(polygon
			(pts
				(xy 199.610218 -131.051808) (xy 199.407018 -131.051808) (xy 199.407018 -131.255008) (xy 199.610218 -131.255008)
			)
		)
		(polygon
			(pts
				(xy 199.203818 -131.051808) (xy 199.000618 -131.051808) (xy 199.000618 -131.255008) (xy 199.203818 -131.255008)
			)
		)
	)
	(zone
		(layer "B.Cu")
		(hatch none 0.5)
		(connect_pads
			(clearance 0)
		)
		(min_thickness 0.25)
		(keepout
			(tracks not_allowed)
			(vias allowed)
			(pads allowed)
			(copperpour not_allowed)
			(footprints allowed)
		)
		(placement
			(enabled no)
			(sheetname "")
		)
		(fill
			(thermal_gap 0.5)
			(thermal_bridge_width 0.5)
			(island_removal_mode 0)
		)
		(polygon
			(pts
				(arc
					(start 83.250024 -40.049958)
					(mid 78.49997 -35.299904)
					(end 73.749916 -40.049958)
				)
				(arc
					(start 73.749916 -40.049958)
					(mid 78.49997 -44.800012)
					(end 83.250024 -40.049958)
				)
			)
		)
	)
	(zone
		(layer "B.Cu")
		(hatch none 0.5)
		(connect_pads
			(clearance 0)
		)
		(min_thickness 0.25)
		(keepout
			(tracks not_allowed)
			(vias allowed)
			(pads allowed)
			(copperpour not_allowed)
			(footprints allowed)
		)
		(placement
			(enabled no)
			(sheetname "")
		)
		(fill
			(thermal_gap 0.5)
			(thermal_bridge_width 0.5)
			(island_removal_mode 0)
		)
		(polygon
			(pts
				(arc
					(start 184.15 -51.250088)
					(mid 179.399946 -46.500034)
					(end 174.649892 -51.250088)
				)
				(arc
					(start 174.649892 -51.250088)
					(mid 179.399946 -56.000142)
					(end 184.15 -51.250088)
				)
			)
		)
	)
	(zone
		(net "P12V_STBY_VIN_PU1")
		(layer "B.Cu")
		(hatch none 0.5)
		(connect_pads
			(clearance 0.5)
		)
		(min_thickness 0.25)
		(fill yes
			(thermal_gap 0.5)
			(thermal_bridge_width 0.5)
			(island_removal_mode 0)
		)
		(polygon
			(pts
				(xy 222.563944 -50.444146) (xy 221.7293 -51.27879) (xy 221.7293 -55.3847) (xy 221.9452 -55.6006)
				(xy 225.5774 -55.6006) (xy 225.7806 -55.3974) (xy 225.7806 -52.280312) (xy 226.299268 -51.761644)
				(xy 226.299268 -50.613818) (xy 226.129596 -50.444146)
			)
		)
		(polygon
			(pts
				(xy 224.284286 -54.24551) (xy 224.081086 -54.24551) (xy 224.081086 -54.44871) (xy 224.284286 -54.44871)
			)
		)
	)
	(zone
		(layer "B.Cu")
		(hatch none 0.5)
		(connect_pads
			(clearance 0)
		)
		(min_thickness 0.25)
		(keepout
			(tracks not_allowed)
			(vias allowed)
			(pads allowed)
			(copperpour not_allowed)
			(footprints allowed)
		)
		(placement
			(enabled no)
			(sheetname "")
		)
		(fill
			(thermal_gap 0.5)
			(thermal_bridge_width 0.5)
			(island_removal_mode 0)
		)
		(polygon
			(pts
				(arc
					(start 45.200062 -169.999914)
					(mid 41.450006 -166.249858)
					(end 37.69995 -169.999914)
				)
				(arc
					(start 37.69995 -169.999914)
					(mid 41.450006 -173.74997)
					(end 45.200062 -169.999914)
				)
			)
		)
	)
	(zone
		(layer "B.Cu")
		(hatch none 0.5)
		(connect_pads
			(clearance 0)
		)
		(min_thickness 0.25)
		(keepout
			(tracks not_allowed)
			(vias allowed)
			(pads allowed)
			(copperpour not_allowed)
			(footprints allowed)
		)
		(placement
			(enabled no)
			(sheetname "")
		)
		(fill
			(thermal_gap 0.5)
			(thermal_bridge_width 0.5)
			(island_removal_mode 0)
		)
		(polygon
			(pts
				(arc
					(start 78.503018 -83.310222)
					(mid 78.122145 -82.928968)
					(end 77.741018 -83.309968)
				)
				(arc
					(start 77.741018 -84.198968)
					(mid 78.122018 -84.579968)
					(end 78.503018 -84.198968)
				)
				(xy 78.503018 -83.995768) (xy 78.44663 -83.995768)
				(arc
					(start 78.361286 -84.081112)
					(mid 77.933419 -84.387567)
					(end 78.239874 -83.9597)
				)
				(xy 78.37551 -83.824318) (xy 78.37551 -83.824064) (xy 78.503018 -83.824064) (xy 78.503018 -83.684364)
				(xy 78.375256 -83.684364)
				(arc
					(start 78.239874 -83.549236)
					(mid 77.933419 -83.121369)
					(end 78.361286 -83.427824)
				)
				(xy 78.446376 -83.513168) (xy 78.503018 -83.513168)
			)
		)
	)
	(zone
		(net "P12V_IOM")
		(layer "B.Cu")
		(hatch none 0.5)
		(connect_pads
			(clearance 0.5)
		)
		(min_thickness 0.25)
		(fill yes
			(thermal_gap 0.5)
			(thermal_bridge_width 0.5)
			(island_removal_mode 0)
		)
		(polygon
			(pts
				(xy 129.791968 -15.455392) (xy 129.437384 -15.809976) (xy 129.437384 -16.917162) (xy 129.277872 -17.076674)
				(xy 127.397002 -17.076674) (xy 127.13716 -16.816832) (xy 124.508768 -16.816832) (xy 124.1806 -17.145)
				(xy 124.1806 -19.7866) (xy 124.62764 -20.23364) (xy 131.66598 -20.23364) (xy 131.82346 -20.07616)
				(xy 131.82346 -18.428716) (xy 130.87604 -17.481296) (xy 130.87604 -15.777972) (xy 130.55346 -15.455392)
			)
		)
		(polygon
			(pts
				(xy 131.36626 -19.9136) (xy 131.16306 -19.9136) (xy 131.16306 -20.1168) (xy 131.36626 -20.1168)
			)
		)
		(polygon
			(pts
				(xy 131.36626 -19.3548) (xy 131.16306 -19.3548) (xy 131.16306 -19.558) (xy 131.36626 -19.558)
			)
		)
		(polygon
			(pts
				(xy 125.73 -17.272) (xy 125.5268 -17.272) (xy 125.5268 -17.4752) (xy 125.73 -17.4752)
			)
		)
		(polygon
			(pts
				(xy 125.1712 -17.272) (xy 124.968 -17.272) (xy 124.968 -17.4752) (xy 125.1712 -17.4752)
			)
		)
		(polygon
			(pts
				(xy 130.0988 -16.6878) (xy 129.8956 -16.6878) (xy 129.8956 -16.891) (xy 130.0988 -16.891)
			)
		)
		(polygon
			(pts
				(xy 130.0988 -16.129) (xy 129.8956 -16.129) (xy 129.8956 -16.3322) (xy 130.0988 -16.3322)
			)
		)
	)
	(zone
		(layer "B.Cu")
		(hatch none 0.5)
		(connect_pads
			(clearance 0)
		)
		(min_thickness 0.25)
		(keepout
			(tracks not_allowed)
			(vias allowed)
			(pads allowed)
			(copperpour not_allowed)
			(footprints allowed)
		)
		(placement
			(enabled no)
			(sheetname "")
		)
		(fill
			(thermal_gap 0.5)
			(thermal_bridge_width 0.5)
			(island_removal_mode 0)
		)
		(polygon
			(pts
				(arc
					(start 129.185162 -33.20034)
					(mid 128.700149 -32.714946)
					(end 128.214882 -33.200086)
				)
				(xy 128.214882 -33.659064) (xy 128.531874 -33.659064)
				(arc
					(start 128.536446 -33.65881)
					(mid 128.590226 -33.637199)
					(end 128.61417 -33.584388)
				)
				(arc
					(start 128.61417 -33.584388)
					(mid 128.700022 -32.806311)
					(end 128.785874 -33.584388)
				)
				(xy 128.78562 -33.58896) (xy 128.78562 -33.616646)
				(arc
					(start 128.782826 -33.61944)
					(mid 128.712761 -33.757401)
					(end 128.5748 -33.827466)
				)
				(xy 128.572006 -33.83026) (xy 128.54432 -33.83026) (xy 128.536446 -33.830514) (xy 128.531874 -33.83026)
				(xy 128.214882 -33.83026) (xy 128.214882 -33.96996) (xy 128.532128 -33.96996) (xy 128.5367 -33.96996)
				(xy 128.544574 -33.96996) (xy 128.57226 -33.96996)
				(arc
					(start 128.575054 -33.973008)
					(mid 128.712838 -34.042996)
					(end 128.782826 -34.18078)
				)
				(xy 128.78562 -34.183574) (xy 128.78562 -34.21126)
				(arc
					(start 128.785874 -34.215832)
					(mid 128.700022 -34.993909)
					(end 128.61417 -34.215832)
				)
				(arc
					(start 128.61417 -34.215832)
					(mid 128.590349 -34.163149)
					(end 128.5367 -34.141664)
				)
				(xy 128.532128 -34.141664) (xy 128.214882 -34.141664)
				(arc
					(start 128.214882 -34.600134)
					(mid 128.700022 -35.085274)
					(end 129.185162 -34.600134)
				)
			)
		)
	)
	(zone
		(net "GND")
		(layer "B.Cu")
		(hatch none 0.5)
		(connect_pads
			(clearance 0.5)
		)
		(min_thickness 0.25)
		(fill yes
			(thermal_gap 0.5)
			(thermal_bridge_width 0.5)
			(island_removal_mode 0)
		)
		(polygon
			(pts
				(xy 217.09888 -95.903288) (xy 216.746836 -96.255332) (xy 216.746836 -98.364548) (xy 217.073988 -98.6917)
				(xy 222.558102 -98.6917) (xy 222.83928 -98.410522) (xy 222.83928 -96.2406) (xy 222.501968 -95.903288)
			)
		)
	)
	(zone
		(layer "B.Cu")
		(hatch none 0.5)
		(connect_pads
			(clearance 0)
		)
		(min_thickness 0.25)
		(keepout
			(tracks not_allowed)
			(vias allowed)
			(pads allowed)
			(copperpour not_allowed)
			(footprints allowed)
		)
		(placement
			(enabled no)
			(sheetname "")
		)
		(fill
			(thermal_gap 0.5)
			(thermal_bridge_width 0.5)
			(island_removal_mode 0)
		)
		(polygon
			(pts
				(arc
					(start 209.14995 -21.249894)
					(mid 204.40015 -16.500094)
					(end 199.650096 -21.249894)
				)
				(arc
					(start 199.650096 -21.249894)
					(mid 204.40015 -25.999948)
					(end 209.14995 -21.249894)
				)
			)
		)
	)
	(zone
		(net "P3V3_M2")
		(layer "B.Cu")
		(hatch none 0.5)
		(connect_pads
			(clearance 0.5)
		)
		(min_thickness 0.25)
		(fill yes
			(thermal_gap 0.5)
			(thermal_bridge_width 0.5)
			(island_removal_mode 0)
		)
		(polygon
			(pts
				(xy 170.8404 -120.904) (xy 170.18 -121.5644) (xy 170.18 -128.759966) (xy 171.97578 -130.556) (xy 181.277006 -130.556)
				(xy 181.914038 -131.193032) (xy 188.42101 -131.193032) (xy 189.045342 -131.817364) (xy 189.045342 -133.093714)
				(xy 189.631574 -133.679946) (xy 194.48653 -133.679946) (xy 194.512438 -133.654038) (xy 196.749162 -133.654038)
				(xy 197.1548 -133.2484) (xy 198.5518 -133.2484) (xy 198.7296 -133.0706) (xy 198.7296 -131.9276)
				(xy 198.3232 -131.5212) (xy 198.3232 -130.302) (xy 198.39305 -130.23215) (xy 205.021434 -130.23215)
				(xy 205.223872 -130.434588) (xy 211.800948 -130.434588) (xy 213.741 -128.494536) (xy 213.741 -125.201172)
				(xy 213.603078 -125.06325) (xy 211.15655 -125.06325) (xy 209.8548 -126.365) (xy 202.52944 -126.365)
				(xy 199.296274 -123.131834) (xy 186.971686 -123.131834) (xy 181.647592 -128.455928) (xy 175.431196 -128.455928)
				(xy 174.8028 -127.827532) (xy 174.8028 -121.4374) (xy 174.2694 -120.904)
			)
		)
		(polygon
			(pts
				(xy 196.863462 -132.97535) (xy 196.660262 -132.97535) (xy 196.660262 -133.17855) (xy 196.863462 -133.17855)
			)
		)
		(polygon
			(pts
				(xy 196.253862 -132.97535) (xy 196.050662 -132.97535) (xy 196.050662 -133.17855) (xy 196.253862 -133.17855)
			)
		)
		(polygon
			(pts
				(xy 195.847462 -132.97535) (xy 195.644262 -132.97535) (xy 195.644262 -133.17855) (xy 195.847462 -133.17855)
			)
		)
		(polygon
			(pts
				(xy 195.237862 -132.97535) (xy 195.034662 -132.97535) (xy 195.034662 -133.17855) (xy 195.237862 -133.17855)
			)
		)
		(polygon
			(pts
				(xy 194.831462 -132.97535) (xy 194.628262 -132.97535) (xy 194.628262 -133.17855) (xy 194.831462 -133.17855)
			)
		)
		(polygon
			(pts
				(xy 194.221862 -132.97535) (xy 194.018662 -132.97535) (xy 194.018662 -133.17855) (xy 194.221862 -133.17855)
			)
		)
		(polygon
			(pts
				(xy 193.54165 -132.967984) (xy 193.33845 -132.967984) (xy 193.33845 -133.171184) (xy 193.54165 -133.171184)
			)
		)
		(polygon
			(pts
				(xy 192.93205 -132.967984) (xy 192.72885 -132.967984) (xy 192.72885 -133.171184) (xy 192.93205 -133.171184)
			)
		)
		(polygon
			(pts
				(xy 192.52565 -132.967984) (xy 192.32245 -132.967984) (xy 192.32245 -133.171184) (xy 192.52565 -133.171184)
			)
		)
		(polygon
			(pts
				(xy 191.91605 -132.967984) (xy 191.71285 -132.967984) (xy 191.71285 -133.171184) (xy 191.91605 -133.171184)
			)
		)
		(polygon
			(pts
				(xy 175.090836 -129.869184) (xy 174.887636 -129.869184) (xy 174.887636 -130.072384) (xy 175.090836 -130.072384)
			)
		)
		(polygon
			(pts
				(xy 176.604168 -129.860548) (xy 176.400968 -129.860548) (xy 176.400968 -130.063748) (xy 176.604168 -130.063748)
			)
		)
		(polygon
			(pts
				(xy 175.994568 -129.860548) (xy 175.791368 -129.860548) (xy 175.700436 -129.869184) (xy 175.497236 -129.869184)
				(xy 175.497236 -130.072384) (xy 175.700436 -130.072384) (xy 175.791368 -130.063748) (xy 175.994568 -130.063748)
			)
		)
		(polygon
			(pts
				(xy 174.776384 -129.856738) (xy 174.573184 -129.856738) (xy 174.573184 -130.059938) (xy 174.776384 -130.059938)
			)
		)
		(polygon
			(pts
				(xy 174.166784 -129.856738) (xy 173.963584 -129.856738) (xy 173.963584 -130.059938) (xy 174.166784 -130.059938)
			)
		)
		(polygon
			(pts
				(xy 202.251818 -129.527808) (xy 202.048618 -129.527808) (xy 202.048618 -129.731008) (xy 202.251818 -129.731008)
			)
		)
		(polygon
			(pts
				(xy 201.642218 -129.527808) (xy 201.439018 -129.527808) (xy 201.439018 -129.731008) (xy 201.642218 -129.731008)
			)
		)
		(polygon
			(pts
				(xy 201.235818 -129.527808) (xy 201.032618 -129.527808) (xy 201.032618 -129.731008) (xy 201.235818 -129.731008)
			)
		)
		(polygon
			(pts
				(xy 200.626218 -129.527808) (xy 200.423018 -129.527808) (xy 200.423018 -129.731008) (xy 200.626218 -129.731008)
			)
		)
		(polygon
			(pts
				(xy 200.219818 -129.527808) (xy 200.016618 -129.527808) (xy 200.016618 -129.731008) (xy 200.219818 -129.731008)
			)
		)
		(polygon
			(pts
				(xy 199.610218 -129.527808) (xy 199.407018 -129.527808) (xy 199.407018 -129.731008) (xy 199.610218 -129.731008)
			)
		)
		(polygon
			(pts
				(xy 199.203818 -129.527808) (xy 199.000618 -129.527808) (xy 199.000618 -129.731008) (xy 199.203818 -129.731008)
			)
		)
		(polygon
			(pts
				(xy 198.594218 -129.527808) (xy 198.391018 -129.527808) (xy 198.391018 -129.731008) (xy 198.594218 -129.731008)
			)
		)
		(polygon
			(pts
				(xy 174.2948 -127.256286) (xy 174.0916 -127.256286) (xy 174.0916 -127.459486) (xy 174.2948 -127.459486)
			)
		)
		(polygon
			(pts
				(xy 174.2948 -126.646686) (xy 174.0916 -126.646686) (xy 174.0916 -126.849886) (xy 174.2948 -126.849886)
			)
		)
		(polygon
			(pts
				(xy 174.2948 -126.316486) (xy 174.0916 -126.316486) (xy 174.0916 -126.519686) (xy 174.2948 -126.519686)
			)
		)
		(polygon
			(pts
				(xy 170.899328 -125.730508) (xy 170.696128 -125.730508) (xy 170.696128 -125.933708) (xy 170.899328 -125.933708)
			)
		)
		(polygon
			(pts
				(xy 174.2948 -125.706886) (xy 174.0916 -125.706886) (xy 174.0916 -125.910086) (xy 174.2948 -125.910086)
			)
		)
		(polygon
			(pts
				(xy 170.899328 -124.841508) (xy 170.696128 -124.841508) (xy 170.696128 -125.324108) (xy 170.899328 -125.324108)
			)
		)
		(polygon
			(pts
				(xy 170.899328 -124.231908) (xy 170.696128 -124.231908) (xy 170.696128 -124.435108) (xy 170.899328 -124.435108)
			)
		)
		(polygon
			(pts
				(xy 170.899328 -123.825508) (xy 170.696128 -123.825508) (xy 170.696128 -124.028708) (xy 170.899328 -124.028708)
			)
		)
		(polygon
			(pts
				(xy 170.899328 -123.215908) (xy 170.696128 -123.215908) (xy 170.696128 -123.419108) (xy 170.899328 -123.419108)
			)
		)
		(polygon
			(pts
				(xy 170.899328 -122.784108) (xy 170.696128 -122.784108) (xy 170.696128 -122.987308) (xy 170.899328 -122.987308)
			)
		)
		(polygon
			(pts
				(xy 170.899328 -122.174508) (xy 170.696128 -122.174508) (xy 170.696128 -122.377708) (xy 170.899328 -122.377708)
			)
		)
	)
	(zone
		(layer "B.Cu")
		(hatch none 0.5)
		(connect_pads
			(clearance 0)
		)
		(min_thickness 0.25)
		(keepout
			(tracks allowed)
			(vias allowed)
			(pads allowed)
			(copperpour allowed)
			(footprints allowed)
		)
		(placement
			(enabled no)
			(sheetname "")
		)
		(fill
			(thermal_gap 0.5)
			(thermal_bridge_width 0.5)
			(island_removal_mode 0)
		)
		(polygon
			(pts
				(xy 63.0174 -145.161) (xy 63.0174 -144.0688) (xy 64.389 -144.0688) (xy 64.389 -145.161)
			)
		)
	)
	(zone
		(layer "B.Cu")
		(hatch none 0.5)
		(connect_pads
			(clearance 0)
		)
		(min_thickness 0.25)
		(keepout
			(tracks not_allowed)
			(vias allowed)
			(pads allowed)
			(copperpour not_allowed)
			(footprints allowed)
		)
		(placement
			(enabled no)
			(sheetname "")
		)
		(fill
			(thermal_gap 0.5)
			(thermal_bridge_width 0.5)
			(island_removal_mode 0)
		)
		(polygon
			(pts
				(arc
					(start 97.249996 -187.999878)
					(mid 92.499942 -183.249824)
					(end 87.749888 -187.999878)
				)
				(arc
					(start 87.749888 -187.999878)
					(mid 92.499942 -192.749932)
					(end 97.249996 -187.999878)
				)
			)
		)
	)
	(zone
		(net "MPLLAV33")
		(layer "B.Cu")
		(hatch none 0.5)
		(connect_pads
			(clearance 0.5)
		)
		(min_thickness 0.25)
		(fill yes
			(thermal_gap 0.5)
			(thermal_bridge_width 0.5)
			(island_removal_mode 0)
		)
		(polygon
			(pts
				(xy 41.021 -139.954) (xy 40.767 -140.208) (xy 40.767 -141.3256) (xy 40.9194 -141.478) (xy 41.656 -141.478)
				(xy 41.783 -141.351) (xy 41.783 -140.208) (xy 41.529 -139.954)
			)
		)
	)
	(zone
		(layer "B.Cu")
		(hatch none 0.5)
		(connect_pads
			(clearance 0)
		)
		(min_thickness 0.25)
		(keepout
			(tracks not_allowed)
			(vias allowed)
			(pads allowed)
			(copperpour not_allowed)
			(footprints allowed)
		)
		(placement
			(enabled no)
			(sheetname "")
		)
		(fill
			(thermal_gap 0.5)
			(thermal_bridge_width 0.5)
			(island_removal_mode 0)
		)
		(polygon
			(pts
				(arc
					(start 77.664818 -73.709022)
					(mid 77.283945 -73.327768)
					(end 76.902818 -73.708768)
				)
				(arc
					(start 76.902818 -74.597768)
					(mid 77.283818 -74.978768)
					(end 77.664818 -74.597768)
				)
				(xy 77.664818 -74.394568) (xy 77.608176 -74.394568)
				(arc
					(start 77.523086 -74.479912)
					(mid 77.095219 -74.786367)
					(end 77.401674 -74.3585)
				)
				(xy 77.537056 -74.223372) (xy 77.664818 -74.223372) (xy 77.664818 -74.083672) (xy 77.53731 -74.083672)
				(xy 77.53731 -74.083418)
				(arc
					(start 77.401674 -73.948036)
					(mid 77.095219 -73.520169)
					(end 77.523086 -73.826624)
				)
				(xy 77.60843 -73.911968) (xy 77.664818 -73.911968)
			)
		)
	)
	(zone
		(net "AGND_CURRENT_MON")
		(layer "B.Cu")
		(hatch none 0.5)
		(connect_pads
			(clearance 0.5)
		)
		(min_thickness 0.25)
		(fill yes
			(thermal_gap 0.5)
			(thermal_bridge_width 0.5)
			(island_removal_mode 0)
		)
		(polygon
			(pts
				(xy 125.743208 -11.405362) (xy 124.554996 -12.593574) (xy 124.554996 -14.189964) (xy 124.579888 -14.189964)
				(xy 124.728478 -14.338554) (xy 130.161284 -14.338554) (xy 130.681222 -13.818616) (xy 130.681222 -13.08862)
				(xy 129.678684 -12.086082) (xy 128.614424 -12.086082) (xy 127.933704 -11.405362)
			)
		)
		(polygon
			(pts
				(xy 129.1844 -13.97) (xy 128.9812 -13.97) (xy 128.9812 -14.1732) (xy 129.1844 -14.1732)
			)
		)
		(polygon
			(pts
				(xy 128.3208 -13.97) (xy 128.1176 -13.97) (xy 128.1176 -14.1732) (xy 128.3208 -14.1732)
			)
		)
		(polygon
			(pts
				(xy 125.8824 -13.97) (xy 125.6792 -13.97) (xy 125.6792 -14.1732) (xy 125.8824 -14.1732)
			)
		)
		(polygon
			(pts
				(xy 125.0188 -13.97) (xy 124.8156 -13.97) (xy 124.8156 -14.1732) (xy 125.0188 -14.1732)
			)
		)
		(polygon
			(pts
				(xy 126.9111 -13.67282) (xy 126.7079 -13.67282) (xy 126.7079 -13.87602) (xy 126.9111 -13.87602)
			)
		)
		(polygon
			(pts
				(xy 126.3523 -13.67282) (xy 126.1491 -13.67282) (xy 126.1491 -13.87602) (xy 126.3523 -13.87602)
			)
		)
		(polygon
			(pts
				(xy 130.302 -13.5382) (xy 130.0988 -13.5382) (xy 130.0988 -13.7414) (xy 130.302 -13.7414)
			)
		)
		(polygon
			(pts
				(xy 129.7432 -13.5382) (xy 129.54 -13.5382) (xy 129.54 -13.7414) (xy 129.7432 -13.7414)
			)
		)
		(polygon
			(pts
				(xy 129.1844 -13.1064) (xy 128.9812 -13.1064) (xy 128.9812 -13.3096) (xy 129.1844 -13.3096)
			)
		)
		(polygon
			(pts
				(xy 128.3208 -13.1064) (xy 128.1176 -13.1064) (xy 128.1176 -13.3096) (xy 128.3208 -13.3096)
			)
		)
		(polygon
			(pts
				(xy 125.8824 -13.1064) (xy 125.6792 -13.1064) (xy 125.6792 -13.3096) (xy 125.8824 -13.3096)
			)
		)
		(polygon
			(pts
				(xy 125.0188 -13.1064) (xy 124.8156 -13.1064) (xy 124.8156 -13.3096) (xy 125.0188 -13.3096)
			)
		)
	)
	(zone
		(net "GND")
		(layer "B.Cu")
		(hatch none 0.5)
		(connect_pads
			(clearance 0.5)
		)
		(min_thickness 0.25)
		(fill yes
			(thermal_gap 0.5)
			(thermal_bridge_width 0.5)
			(island_removal_mode 0)
		)
		(polygon
			(pts
				(xy 44.330366 -146.986498) (xy 44.238418 -147.078446) (xy 44.238418 -149.427438) (xy 44.102782 -149.563074)
				(xy 42.724832 -149.563074) (xy 42.606722 -149.681184) (xy 42.606722 -149.897592) (xy 42.692066 -149.982936)
				(xy 44.815506 -149.982936) (xy 44.907454 -149.890988) (xy 44.907454 -147.03044) (xy 44.863512 -146.986498)
			)
		)
	)
	(zone
		(layer "B.Cu")
		(hatch none 0.5)
		(connect_pads
			(clearance 0)
		)
		(min_thickness 0.25)
		(keepout
			(tracks not_allowed)
			(vias allowed)
			(pads allowed)
			(copperpour not_allowed)
			(footprints allowed)
		)
		(placement
			(enabled no)
			(sheetname "")
		)
		(fill
			(thermal_gap 0.5)
			(thermal_bridge_width 0.5)
			(island_removal_mode 0)
		)
		(polygon
			(pts
				(arc
					(start 114.78514 -33.20034)
					(mid 114.300127 -32.714946)
					(end 113.81486 -33.200086)
				)
				(xy 113.81486 -33.659064) (xy 114.131852 -33.659064)
				(arc
					(start 114.136424 -33.65881)
					(mid 114.190204 -33.637199)
					(end 114.214148 -33.584388)
				)
				(arc
					(start 114.214148 -33.584388)
					(mid 114.3 -32.806311)
					(end 114.385852 -33.584388)
				)
				(xy 114.385852 -33.58896) (xy 114.385852 -33.616646)
				(arc
					(start 114.382804 -33.61944)
					(mid 114.312739 -33.757401)
					(end 114.174778 -33.827466)
				)
				(xy 114.171984 -33.83026) (xy 114.144298 -33.83026) (xy 114.136424 -33.830514) (xy 114.131852 -33.83026)
				(xy 113.81486 -33.83026) (xy 113.81486 -33.96996) (xy 114.132106 -33.96996) (xy 114.136678 -33.96996)
				(xy 114.144552 -33.96996) (xy 114.172238 -33.96996)
				(arc
					(start 114.175032 -33.973008)
					(mid 114.312816 -34.042996)
					(end 114.382804 -34.18078)
				)
				(xy 114.385852 -34.183574) (xy 114.385852 -34.21126)
				(arc
					(start 114.385852 -34.215832)
					(mid 114.3 -34.993909)
					(end 114.214148 -34.215832)
				)
				(arc
					(start 114.214148 -34.215832)
					(mid 114.190327 -34.163149)
					(end 114.136678 -34.141664)
				)
				(xy 114.132106 -34.141664) (xy 113.81486 -34.141664)
				(arc
					(start 113.81486 -34.600134)
					(mid 114.3 -35.085274)
					(end 114.78514 -34.600134)
				)
			)
		)
	)
	(zone
		(layer "B.Cu")
		(hatch none 0.5)
		(connect_pads
			(clearance 0)
		)
		(min_thickness 0.25)
		(keepout
			(tracks allowed)
			(vias allowed)
			(pads allowed)
			(copperpour allowed)
			(footprints not_allowed)
		)
		(placement
			(enabled no)
			(sheetname "")
		)
		(fill
			(thermal_gap 0.5)
			(thermal_bridge_width 0.5)
			(island_removal_mode 0)
		)
		(polygon
			(pts
				(arc
					(start 27.649932 -105.050082)
					(mid 22.900132 -100.300282)
					(end 18.150078 -105.050082)
				)
				(arc
					(start 18.150078 -105.050082)
					(mid 22.900132 -109.800136)
					(end 27.649932 -105.050082)
				)
			)
		)
	)
	(zone
		(layer "B.Cu")
		(hatch none 0.5)
		(connect_pads
			(clearance 0)
		)
		(min_thickness 0.25)
		(keepout
			(tracks not_allowed)
			(vias allowed)
			(pads allowed)
			(copperpour not_allowed)
			(footprints allowed)
		)
		(placement
			(enabled no)
			(sheetname "")
		)
		(fill
			(thermal_gap 0.5)
			(thermal_bridge_width 0.5)
			(island_removal_mode 0)
		)
		(polygon
			(pts
				(arc
					(start 127.16002 -34.85007)
					(mid 124.160026 -31.850076)
					(end 121.160032 -34.85007)
				)
				(arc
					(start 121.160032 -34.85007)
					(mid 124.160026 -37.850064)
					(end 127.16002 -34.85007)
				)
			)
		)
	)
	(zone
		(net "USB_CONN_GND")
		(layer "B.Cu")
		(hatch none 0.5)
		(connect_pads
			(clearance 0.5)
		)
		(min_thickness 0.25)
		(fill yes
			(thermal_gap 0.5)
			(thermal_bridge_width 0.5)
			(island_removal_mode 0)
		)
		(polygon
			(pts
				(xy 89.3699 -5.070094) (xy 84.709 -9.730994) (xy 84.709 -24.765) (xy 85.344 -25.4) (xy 92.456 -25.4)
				(xy 93.091 -24.765) (xy 93.091 -11.176) (xy 95.220536 -9.046464) (xy 95.220536 -5.23494) (xy 95.05569 -5.070094)
			)
		)
		(polygon
			(pts
				(xy 94.7674 -8.0518) (xy 94.5642 -8.0518) (xy 94.5642 -8.255) (xy 94.7674 -8.255)
			)
		)
		(polygon
			(pts
				(xy 94.7674 -7.493) (xy 94.5642 -7.493) (xy 94.5642 -7.6962) (xy 94.7674 -7.6962)
			)
		)
	)
	(zone
		(net "GND")
		(layer "B.Cu")
		(hatch none 0.5)
		(connect_pads
			(clearance 0.5)
		)
		(min_thickness 0.25)
		(fill yes
			(thermal_gap 0.5)
			(thermal_bridge_width 0.5)
			(island_removal_mode 0)
		)
		(polygon
			(pts
				(xy 12.38758 -165.942264) (xy 11.89101 -166.438834) (xy 11.89101 -170.540426) (xy 12.463018 -171.112434)
				(xy 18.667476 -171.112434) (xy 19.002248 -170.777662) (xy 24.214836 -170.777662) (xy 24.959564 -170.032934)
				(xy 24.959564 -166.425372) (xy 24.476456 -165.942264)
			)
		)
	)
	(zone
		(layer "B.Cu")
		(hatch none 0.5)
		(connect_pads
			(clearance 0)
		)
		(min_thickness 0.25)
		(keepout
			(tracks allowed)
			(vias allowed)
			(pads allowed)
			(copperpour allowed)
			(footprints not_allowed)
		)
		(placement
			(enabled no)
			(sheetname "")
		)
		(fill
			(thermal_gap 0.5)
			(thermal_bridge_width 0.5)
			(island_removal_mode 0)
		)
		(polygon
			(pts
				(arc
					(start 83.250024 -40.049958)
					(mid 78.49997 -35.299904)
					(end 73.749916 -40.049958)
				)
				(arc
					(start 73.749916 -40.049958)
					(mid 78.49997 -44.800012)
					(end 83.250024 -40.049958)
				)
			)
		)
	)
	(zone
		(net "P3V3_STBY")
		(layer "B.Cu")
		(hatch none 0.5)
		(connect_pads
			(clearance 0.5)
		)
		(min_thickness 0.25)
		(fill yes
			(thermal_gap 0.5)
			(thermal_bridge_width 0.5)
			(island_removal_mode 0)
		)
		(polygon
			(pts
				(xy 84.9122 -54.9148) (xy 84.6836 -55.1434) (xy 84.6836 -56.261) (xy 84.6074 -56.3372) (xy 83.1342 -56.3372)
				(xy 82.8548 -56.6166) (xy 82.8548 -60.579) (xy 82.9564 -60.6806) (xy 84.2518 -60.6806) (xy 84.5058 -60.4266)
				(xy 84.5058 -58.8264) (xy 84.7344 -58.5978) (xy 85.344 -58.5978) (xy 85.598 -58.3438) (xy 85.598 -55.1434)
				(xy 85.3694 -54.9148)
			)
		)
	)
	(zone
		(layer "B.Cu")
		(hatch none 0.5)
		(connect_pads
			(clearance 0)
		)
		(min_thickness 0.25)
		(keepout
			(tracks not_allowed)
			(vias allowed)
			(pads allowed)
			(copperpour not_allowed)
			(footprints allowed)
		)
		(placement
			(enabled no)
			(sheetname "")
		)
		(fill
			(thermal_gap 0.5)
			(thermal_bridge_width 0.5)
			(island_removal_mode 0)
		)
		(polygon
			(pts
				(arc
					(start 154.049984 -78.000098)
					(mid 149.29993 -73.250044)
					(end 144.549876 -78.000098)
				)
				(arc
					(start 144.549876 -78.000098)
					(mid 149.29993 -82.750152)
					(end 154.049984 -78.000098)
				)
			)
		)
	)
	(zone
		(net "GND")
		(layer "B.Cu")
		(hatch none 0.5)
		(connect_pads
			(clearance 0.5)
		)
		(min_thickness 0.25)
		(fill yes
			(thermal_gap 0.5)
			(thermal_bridge_width 0.5)
			(island_removal_mode 0)
		)
		(polygon
			(pts
				(arc
					(start 74.030078 -0.763016)
					(mid 73.862506 -0.832426)
					(end 73.793096 -0.999998)
				)
				(xy 73.793096 -36.016692) (xy 75.82408 -36.016692) (xy 75.82408 -2.794) (xy 232.206038 -2.794) (xy 232.206038 -183.340248)
				(xy 228.273356 -191.20612) (xy 217.794078 -191.20612)
				(arc
					(start 217.794078 -160.999932)
					(mid 216.682842 -158.31717)
					(end 214.00008 -157.205934)
				)
				(xy 151.026622 -157.205934) (xy 147.09394 -149.340062)
				(arc
					(start 147.09394 -47.999904)
					(mid 145.397362 -45.119087)
					(end 142.055342 -45.205904)
				)
				(xy 140.912088 -45.205904) (xy 140.912088 -47.236888)
				(arc
					(start 142.793466 -47.236888)
					(mid 144.202311 -46.802855)
					(end 145.062956 -47.999904)
				)
				(arc
					(start 145.062956 -149.763734)
					(mid 145.069351 -149.818161)
					(end 145.088102 -149.869652)
				)
				(arc
					(start 149.706076 -159.105854)
					(mid 149.793376 -159.201501)
					(end 149.917912 -159.236918)
				)
				(arc
					(start 214.00008 -159.236918)
					(mid 215.246719 -159.753293)
					(end 215.763094 -160.999932)
				)
				(arc
					(start 215.763094 -193.000122)
					(mid 215.832504 -193.167694)
					(end 216.000076 -193.237104)
				)
				(arc
					(start 229.382066 -193.237104)
					(mid 229.506557 -193.201614)
					(end 229.593902 -193.10604)
				)
				(arc
					(start 234.211876 -183.869838)
					(mid 234.230599 -183.818341)
					(end 234.237022 -183.76392)
				)
				(arc
					(start 234.237022 -0.999998)
					(mid 234.167612 -0.832426)
					(end 234.00004 -0.763016)
				)
			)
		)
	)
	(zone
		(net "P3V3_STBY")
		(layer "B.Cu")
		(hatch none 0.5)
		(connect_pads
			(clearance 0.5)
		)
		(min_thickness 0.25)
		(fill yes
			(thermal_gap 0.5)
			(thermal_bridge_width 0.5)
			(island_removal_mode 0)
		)
		(polygon
			(pts
				(xy 29.851604 -152.360122) (xy 29.693108 -152.518618) (xy 29.693108 -155.162758) (xy 29.82595 -155.2956)
				(xy 31.9024 -155.2956) (xy 31.9532 -155.2448) (xy 31.9532 -152.470612) (xy 31.84271 -152.360122)
			)
		)
		(polygon
			(pts
				(xy 31.5214 -154.686) (xy 31.3182 -154.686) (xy 31.3182 -154.8892) (xy 31.5214 -154.8892)
			)
		)
	)
	(zone
		(layer "B.Cu")
		(hatch none 0.5)
		(connect_pads
			(clearance 0)
		)
		(min_thickness 0.25)
		(keepout
			(tracks allowed)
			(vias allowed)
			(pads allowed)
			(copperpour allowed)
			(footprints allowed)
		)
		(placement
			(enabled no)
			(sheetname "")
		)
		(fill
			(thermal_gap 0.5)
			(thermal_bridge_width 0.5)
			(island_removal_mode 0)
		)
		(polygon
			(pts
				(xy 79.117698 -137.482834) (xy 80.922114 -137.482834) (xy 80.95869 -137.446258) (xy 80.95869 -137.05713)
				(xy 80.934306 -137.032746) (xy 79.121762 -137.032746) (xy 79.040736 -137.113772) (xy 79.040736 -137.405872)
			)
		)
	)
	(zone
		(net "GND")
		(layer "B.Cu")
		(hatch none 0.5)
		(connect_pads
			(clearance 0.5)
		)
		(min_thickness 0.25)
		(fill yes
			(thermal_gap 0.5)
			(thermal_bridge_width 0.5)
			(island_removal_mode 0)
		)
		(polygon
			(pts
				(xy 225.366072 -67.934332) (xy 225.133154 -68.16725) (xy 225.133154 -80.060038) (xy 225.893884 -80.820768)
				(xy 229.01402 -80.820768) (xy 229.802944 -80.031844) (xy 229.802944 -68.800726) (xy 228.93655 -67.934332)
			)
		)
		(polygon
			(pts
				(xy 225.853244 -68.71843) (xy 225.650044 -68.71843) (xy 225.650044 -68.92163) (xy 225.853244 -68.92163)
			)
		)
		(polygon
			(pts
				(xy 225.853244 -68.10883) (xy 225.650044 -68.10883) (xy 225.650044 -68.31203) (xy 225.853244 -68.31203)
			)
		)
	)
	(zone
		(net "P1V8_STBY")
		(layer "B.Cu")
		(hatch none 0.5)
		(connect_pads
			(clearance 0.5)
		)
		(min_thickness 0.25)
		(fill yes
			(thermal_gap 0.5)
			(thermal_bridge_width 0.5)
			(island_removal_mode 0)
		)
		(polygon
			(pts
				(xy 164.603938 -9.298178) (xy 164.222938 -9.679178) (xy 164.222938 -13.717778) (xy 164.502338 -13.997178)
				(xy 169.988738 -13.997178) (xy 170.699938 -13.285978) (xy 170.699938 -9.602978) (xy 170.395138 -9.298178)
			)
		)
	)
	(zone
		(net "P1V8_STBY")
		(layer "B.Cu")
		(hatch none 0.5)
		(connect_pads
			(clearance 0.5)
		)
		(min_thickness 0.25)
		(fill yes
			(thermal_gap 0.5)
			(thermal_bridge_width 0.5)
			(island_removal_mode 0)
		)
		(polygon
			(pts
				(xy 206.674212 -106.587798) (xy 206.667608 -106.594402) (xy 206.667608 -108.420154) (xy 206.620364 -108.467398)
				(xy 205.729586 -108.467398) (xy 205.552294 -108.290106) (xy 205.552294 -107.699302) (xy 205.29804 -107.445048)
				(xy 204.619098 -107.445048) (xy 204.530706 -107.53344) (xy 204.530706 -110.078774) (xy 205.15453 -110.702598)
				(xy 206.40675 -110.702598) (xy 206.435198 -110.674912) (xy 206.910432 -110.199678) (xy 206.910432 -108.563918)
				(xy 207.000856 -108.473494) (xy 207.000856 -106.601514) (xy 206.98714 -106.587798)
			)
		)
		(polygon
			(pts
				(xy 206.450184 -108.971334) (xy 206.246984 -108.971334) (xy 206.246984 -109.174534) (xy 206.450184 -109.174534)
			)
		)
		(polygon
			(pts
				(xy 205.33995 -107.95381) (xy 205.13675 -107.95381) (xy 205.13675 -108.15701) (xy 205.33995 -108.15701)
			)
		)
	)
	(zone
		(net "P3V3_STBY")
		(layer "B.Cu")
		(hatch none 0.5)
		(connect_pads
			(clearance 0.5)
		)
		(min_thickness 0.25)
		(fill yes
			(thermal_gap 0.5)
			(thermal_bridge_width 0.5)
			(island_removal_mode 0)
		)
		(polygon
			(pts
				(xy 39.2684 -129.921) (xy 39.2557 -129.9337) (xy 39.1541 -129.9337) (xy 39.0652 -130.0226) (xy 39.0652 -132.245608)
				(xy 39.147496 -132.327904) (xy 39.2938 -132.473954) (xy 39.865046 -133.0452) (xy 39.865046 -133.714998)
				(xy 39.939468 -133.78942) (xy 40.64762 -133.78942) (xy 41.275 -134.4168) (xy 42.8752 -134.4168)
				(xy 43.0784 -134.62) (xy 43.0784 -135.001) (xy 43.2816 -135.2042) (xy 43.7388 -135.2042) (xy 43.8658 -135.0772)
				(xy 43.8658 -133.477) (xy 43.7642 -133.3754) (xy 43.7642 -130.3782) (xy 43.5356 -130.1496) (xy 43.1292 -130.1496)
				(xy 43.0022 -130.2766) (xy 43.0022 -133.262624) (xy 42.7482 -133.516624) (xy 41.283382 -133.516624)
				(xy 40.649652 -132.883148) (xy 40.4114 -132.883148) (xy 40.132 -132.603748) (xy 40.132 -131.318)
				(xy 40.4368 -131.0132) (xy 40.4368 -130.0734) (xy 40.2844 -129.921)
			)
		)
		(polygon
			(pts
				(xy 43.3832 -133.9596) (xy 43.18 -133.9596) (xy 43.18 -134.1628) (xy 43.3832 -134.1628)
			)
		)
		(polygon
			(pts
				(xy 43.3832 -133.4008) (xy 43.18 -133.4008) (xy 43.18 -133.604) (xy 43.3832 -133.604)
			)
		)
		(polygon
			(pts
				(xy 39.672006 -131.905248) (xy 39.468806 -131.905248) (xy 39.468806 -132.108448) (xy 39.672006 -132.108448)
			)
		)
	)
	(zone
		(net "P3V3_STBY")
		(layer "B.Cu")
		(hatch none 0.5)
		(connect_pads
			(clearance 0.5)
		)
		(min_thickness 0.25)
		(fill yes
			(thermal_gap 0.5)
			(thermal_bridge_width 0.5)
			(island_removal_mode 0)
		)
		(polygon
			(pts
				(xy 88.4936 -158.2928) (xy 87.8586 -158.9278) (xy 87.8586 -160.909) (xy 88.1126 -161.163) (xy 90.3732 -161.163)
				(xy 90.678 -160.8582) (xy 90.678 -159.0802) (xy 89.8906 -158.2928)
			)
		)
		(polygon
			(pts
				(xy 90.4494 -160.02) (xy 90.2462 -160.02) (xy 90.2462 -160.2232) (xy 90.4494 -160.2232)
			)
		)
		(polygon
			(pts
				(xy 89.5858 -160.02) (xy 89.3826 -160.02) (xy 89.3826 -160.2232) (xy 89.5858 -160.2232)
			)
		)
		(polygon
			(pts
				(xy 89.2302 -160.02) (xy 89.027 -160.02) (xy 89.027 -160.2232) (xy 89.2302 -160.2232)
			)
		)
		(polygon
			(pts
				(xy 88.3666 -160.02) (xy 88.1634 -160.02) (xy 88.1634 -160.2232) (xy 88.3666 -160.2232)
			)
		)
	)
	(zone
		(layer "B.Cu")
		(hatch none 0.5)
		(connect_pads
			(clearance 0)
		)
		(min_thickness 0.25)
		(keepout
			(tracks not_allowed)
			(vias allowed)
			(pads allowed)
			(copperpour not_allowed)
			(footprints allowed)
		)
		(placement
			(enabled no)
			(sheetname "")
		)
		(fill
			(thermal_gap 0.5)
			(thermal_bridge_width 0.5)
			(island_removal_mode 0)
		)
		(polygon
			(pts
				(arc
					(start 227.24999 -120.000014)
					(mid 222.499936 -115.24996)
					(end 217.749882 -120.000014)
				)
				(arc
					(start 217.749882 -120.000014)
					(mid 222.499936 -124.750068)
					(end 227.24999 -120.000014)
				)
			)
		)
	)
	(zone
		(layer "B.Cu")
		(hatch none 0.5)
		(connect_pads
			(clearance 0)
		)
		(min_thickness 0.25)
		(keepout
			(tracks allowed)
			(vias allowed)
			(pads allowed)
			(copperpour allowed)
			(footprints not_allowed)
		)
		(placement
			(enabled no)
			(sheetname "")
		)
		(fill
			(thermal_gap 0.5)
			(thermal_bridge_width 0.5)
			(island_removal_mode 0)
		)
		(polygon
			(pts
				(arc
					(start 0.999998 0)
					(mid 0.292893 -0.292893)
					(end 0 -0.999998)
				)
				(arc
					(start 0 -183.76392)
					(mid 0.026764 -183.993728)
					(end 0.105664 -184.211214)
				)
				(arc
					(start 4.723638 -193.447162)
					(mid 4.843062 -193.631987)
					(end 4.99999 -193.786252)
				)
				(xy 4.99999 0)
			)
		)
	)
	(zone
		(layer "B.Cu")
		(hatch none 0.5)
		(connect_pads
			(clearance 0)
		)
		(min_thickness 0.25)
		(keepout
			(tracks allowed)
			(vias allowed)
			(pads allowed)
			(copperpour allowed)
			(footprints not_allowed)
		)
		(placement
			(enabled no)
			(sheetname "")
		)
		(fill
			(thermal_gap 0.5)
			(thermal_bridge_width 0.5)
			(island_removal_mode 0)
		)
		(polygon
			(pts
				(arc
					(start 87.749888 -187.999878)
					(mid 92.499942 -192.749932)
					(end 97.249996 -187.999878)
				)
				(arc
					(start 97.249996 -187.999878)
					(mid 92.499942 -183.249824)
					(end 87.749888 -187.999878)
				)
			)
		)
	)
	(zone
		(layer "B.Cu")
		(hatch none 0.5)
		(connect_pads
			(clearance 0)
		)
		(min_thickness 0.25)
		(keepout
			(tracks not_allowed)
			(vias allowed)
			(pads allowed)
			(copperpour not_allowed)
			(footprints allowed)
		)
		(placement
			(enabled no)
			(sheetname "")
		)
		(fill
			(thermal_gap 0.5)
			(thermal_bridge_width 0.5)
			(island_removal_mode 0)
		)
		(polygon
			(pts
				(arc
					(start 136.385046 -33.20034)
					(mid 135.900033 -32.714946)
					(end 135.414766 -33.200086)
				)
				(xy 135.414766 -33.659064) (xy 135.731758 -33.659064)
				(arc
					(start 135.73633 -33.65881)
					(mid 135.79011 -33.637199)
					(end 135.814054 -33.584388)
				)
				(arc
					(start 135.814054 -33.584388)
					(mid 135.899906 -32.806311)
					(end 135.985758 -33.584388)
				)
				(xy 135.985504 -33.58896) (xy 135.985504 -33.616646)
				(arc
					(start 135.98271 -33.61944)
					(mid 135.912645 -33.757401)
					(end 135.774684 -33.827466)
				)
				(xy 135.77189 -33.83026) (xy 135.744204 -33.83026) (xy 135.73633 -33.830514) (xy 135.731758 -33.83026)
				(xy 135.414766 -33.83026) (xy 135.414766 -33.96996) (xy 135.732012 -33.96996) (xy 135.736584 -33.96996)
				(xy 135.744458 -33.96996) (xy 135.772144 -33.96996)
				(arc
					(start 135.774938 -33.973008)
					(mid 135.912722 -34.042996)
					(end 135.98271 -34.18078)
				)
				(xy 135.985504 -34.183574) (xy 135.985504 -34.21126)
				(arc
					(start 135.985758 -34.215832)
					(mid 135.899906 -34.993909)
					(end 135.814054 -34.215832)
				)
				(arc
					(start 135.814054 -34.215832)
					(mid 135.790233 -34.163149)
					(end 135.736584 -34.141664)
				)
				(xy 135.732012 -34.141664) (xy 135.414766 -34.141664)
				(arc
					(start 135.414766 -34.600134)
					(mid 135.899906 -35.085274)
					(end 136.385046 -34.600134)
				)
			)
		)
	)
	(zone
		(net "GND")
		(layer "B.Cu")
		(hatch none 0.5)
		(connect_pads
			(clearance 0.5)
		)
		(min_thickness 0.25)
		(fill yes
			(thermal_gap 0.5)
			(thermal_bridge_width 0.5)
			(island_removal_mode 0)
		)
		(polygon
			(pts
				(xy 95.70085 -5.082794) (xy 95.5294 -5.254244) (xy 95.5294 -8.6614) (xy 95.758 -8.89) (xy 96.774 -8.89)
				(xy 97.917 -7.747) (xy 97.917 -5.318252) (xy 97.681542 -5.082794)
			)
		)
		(polygon
			(pts
				(xy 96.1898 -8.0518) (xy 95.9866 -8.0518) (xy 95.9866 -8.255) (xy 96.1898 -8.255)
			)
		)
		(polygon
			(pts
				(xy 96.1898 -7.493) (xy 95.9866 -7.493) (xy 95.9866 -7.6962) (xy 96.1898 -7.6962)
			)
		)
	)
	(zone
		(layer "B.Cu")
		(hatch none 0.5)
		(connect_pads
			(clearance 0)
		)
		(min_thickness 0.25)
		(keepout
			(tracks not_allowed)
			(vias allowed)
			(pads allowed)
			(copperpour not_allowed)
			(footprints allowed)
		)
		(placement
			(enabled no)
			(sheetname "")
		)
		(fill
			(thermal_gap 0.5)
			(thermal_bridge_width 0.5)
			(island_removal_mode 0)
		)
		(polygon
			(pts
				(arc
					(start 134.585202 -32.00019)
					(mid 134.100062 -31.51505)
					(end 133.614922 -32.00019)
				)
				(xy 133.614922 -32.45866) (xy 133.932168 -32.45866)
				(arc
					(start 133.93674 -32.45866)
					(mid 133.99034 -32.437124)
					(end 134.01421 -32.384492)
				)
				(arc
					(start 134.01421 -32.384492)
					(mid 134.100062 -31.606415)
					(end 134.185914 -32.384492)
				)
				(xy 134.18566 -32.389064) (xy 134.18566 -32.41675)
				(arc
					(start 134.182866 -32.419544)
					(mid 134.112878 -32.557328)
					(end 133.975094 -32.627316)
				)
				(xy 133.9723 -32.630364) (xy 133.944614 -32.630364) (xy 133.93674 -32.630364) (xy 133.932168 -32.630364)
				(xy 133.614922 -32.630364) (xy 133.614922 -32.770064) (xy 133.932168 -32.770064) (xy 133.93674 -32.76981)
				(xy 133.944614 -32.770064) (xy 133.9723 -32.770064)
				(arc
					(start 133.975094 -32.772858)
					(mid 134.112878 -32.842846)
					(end 134.182866 -32.98063)
				)
				(xy 134.18566 -32.983424) (xy 134.18566 -33.01111)
				(arc
					(start 134.185914 -33.015682)
					(mid 134.100062 -33.793759)
					(end 134.01421 -33.015682)
				)
				(arc
					(start 134.01421 -33.015682)
					(mid 133.990389 -32.962999)
					(end 133.93674 -32.941514)
				)
				(xy 133.932168 -32.94126) (xy 133.614922 -32.94126)
				(arc
					(start 133.614922 -33.39973)
					(mid 134.099935 -33.885124)
					(end 134.585202 -33.399984)
				)
			)
		)
	)
	(zone
		(layer "B.Cu")
		(hatch none 0.5)
		(connect_pads
			(clearance 0)
		)
		(min_thickness 0.25)
		(keepout
			(tracks allowed)
			(vias allowed)
			(pads allowed)
			(copperpour allowed)
			(footprints not_allowed)
		)
		(placement
			(enabled no)
			(sheetname "")
		)
		(fill
			(thermal_gap 0.5)
			(thermal_bridge_width 0.5)
			(island_removal_mode 0)
		)
		(polygon
			(pts
				(arc
					(start 150.750016 -153.999946)
					(mid 155.50007 -158.75)
					(end 160.250124 -153.999946)
				)
				(arc
					(start 160.250124 -153.999946)
					(mid 155.50007 -149.249892)
					(end 150.750016 -153.999946)
				)
			)
		)
	)
	(zone
		(layer "B.Cu")
		(hatch none 0.5)
		(connect_pads
			(clearance 0)
		)
		(min_thickness 0.25)
		(keepout
			(tracks allowed)
			(vias allowed)
			(pads allowed)
			(copperpour allowed)
			(footprints not_allowed)
		)
		(placement
			(enabled no)
			(sheetname "")
		)
		(fill
			(thermal_gap 0.5)
			(thermal_bridge_width 0.5)
			(island_removal_mode 0)
		)
		(polygon
			(pts
				(arc
					(start 184.15 -21.249894)
					(mid 179.399946 -16.49984)
					(end 174.649892 -21.249894)
				)
				(arc
					(start 174.649892 -21.249894)
					(mid 179.399946 -25.999948)
					(end 184.15 -21.249894)
				)
			)
		)
	)
	(zone
		(net "P1V8_STBY")
		(layer "B.Cu")
		(hatch none 0.5)
		(connect_pads
			(clearance 0.5)
		)
		(min_thickness 0.25)
		(fill yes
			(thermal_gap 0.5)
			(thermal_bridge_width 0.5)
			(island_removal_mode 0)
		)
		(polygon
			(pts
				(xy 19.3294 -171.0944) (xy 18.8722 -171.5516) (xy 18.8722 -173.482) (xy 18.879566 -173.921166) (xy 19.177 -174.2186)
				(xy 21.9456 -174.2186) (xy 22.0726 -174.0916) (xy 22.0726 -172.6946) (xy 22.5806 -172.1866) (xy 22.5806 -171.196)
				(xy 22.479 -171.0944)
			)
		)
		(polygon
			(pts
				(xy 21.5646 -173.2788) (xy 21.3614 -173.2788) (xy 21.3614 -173.482) (xy 21.5646 -173.482)
			)
		)
		(polygon
			(pts
				(xy 21.5646 -172.3644) (xy 21.3614 -172.3644) (xy 21.3614 -172.8724) (xy 21.5646 -172.8724)
			)
		)
		(polygon
			(pts
				(xy 22.4282 -171.5008) (xy 22.225 -171.5008) (xy 22.225 -171.704) (xy 22.4282 -171.704)
			)
		)
		(polygon
			(pts
				(xy 21.5646 -171.5008) (xy 21.3614 -171.5008) (xy 21.3614 -171.704) (xy 21.5646 -171.704)
			)
		)
	)
	(zone
		(layer "B.Cu")
		(hatch none 0.5)
		(connect_pads
			(clearance 0)
		)
		(min_thickness 0.25)
		(keepout
			(tracks allowed)
			(vias allowed)
			(pads allowed)
			(copperpour allowed)
			(footprints not_allowed)
		)
		(placement
			(enabled no)
			(sheetname "")
		)
		(fill
			(thermal_gap 0.5)
			(thermal_bridge_width 0.5)
			(island_removal_mode 0)
		)
		(polygon
			(pts
				(arc
					(start 154.049984 -78.000098)
					(mid 149.29993 -73.250044)
					(end 144.549876 -78.000098)
				)
				(arc
					(start 144.549876 -78.000098)
					(mid 149.29993 -82.750152)
					(end 154.049984 -78.000098)
				)
			)
		)
	)
	(zone
		(layer "B.Cu")
		(hatch none 0.5)
		(connect_pads
			(clearance 0)
		)
		(min_thickness 0.25)
		(keepout
			(tracks allowed)
			(vias allowed)
			(pads allowed)
			(copperpour allowed)
			(footprints not_allowed)
		)
		(placement
			(enabled no)
			(sheetname "")
		)
		(fill
			(thermal_gap 0.5)
			(thermal_bridge_width 0.5)
			(island_removal_mode 0)
		)
		(polygon
			(pts
				(arc
					(start 107.750102 -9.99998)
					(mid 103.000048 -5.249926)
					(end 98.249994 -9.99998)
				)
				(arc
					(start 98.249994 -9.99998)
					(mid 103.000048 -14.750034)
					(end 107.750102 -9.99998)
				)
			)
		)
	)
	(zone
		(net "GND")
		(layer "B.Cu")
		(hatch none 0.5)
		(connect_pads
			(clearance 0.5)
		)
		(min_thickness 0.25)
		(fill yes
			(thermal_gap 0.5)
			(thermal_bridge_width 0.5)
			(island_removal_mode 0)
		)
		(polygon
			(pts
				(xy 74.494644 -159.924242) (xy 74.0156 -160.403286) (xy 74.0156 -163.278312) (xy 74.567288 -163.83)
				(xy 79.29372 -163.83) (xy 79.302864 -163.820856) (xy 84.553044 -163.820856) (xy 85.4964 -162.8775)
				(xy 85.4964 -160.325562) (xy 85.09508 -159.924242)
			)
		)
	)
	(zone
		(layer "B.Cu")
		(hatch none 0.5)
		(connect_pads
			(clearance 0)
		)
		(min_thickness 0.25)
		(keepout
			(tracks not_allowed)
			(vias allowed)
			(pads allowed)
			(copperpour not_allowed)
			(footprints allowed)
		)
		(placement
			(enabled no)
			(sheetname "")
		)
		(fill
			(thermal_gap 0.5)
			(thermal_bridge_width 0.5)
			(island_removal_mode 0)
		)
		(polygon
			(pts
				(arc
					(start 17.249902 -187.999878)
					(mid 12.500102 -183.250078)
					(end 7.750048 -187.999878)
				)
				(arc
					(start 7.750048 -187.999878)
					(mid 12.500102 -192.749932)
					(end 17.249902 -187.999878)
				)
			)
		)
	)
	(zone
		(layer "B.Cu")
		(hatch none 0.5)
		(connect_pads
			(clearance 0)
		)
		(min_thickness 0.25)
		(keepout
			(tracks not_allowed)
			(vias allowed)
			(pads allowed)
			(copperpour not_allowed)
			(footprints allowed)
		)
		(placement
			(enabled no)
			(sheetname "")
		)
		(fill
			(thermal_gap 0.5)
			(thermal_bridge_width 0.5)
			(island_removal_mode 0)
		)
		(polygon
			(pts
				(arc
					(start 139.984988 -33.20034)
					(mid 139.499975 -32.714946)
					(end 139.014708 -33.200086)
				)
				(xy 139.014708 -33.659064) (xy 139.3317 -33.659064)
				(arc
					(start 139.336272 -33.65881)
					(mid 139.390052 -33.637199)
					(end 139.413996 -33.584388)
				)
				(arc
					(start 139.413996 -33.584388)
					(mid 139.499848 -32.806311)
					(end 139.5857 -33.584388)
				)
				(xy 139.5857 -33.58896) (xy 139.5857 -33.616646)
				(arc
					(start 139.582652 -33.61944)
					(mid 139.512587 -33.757401)
					(end 139.374626 -33.827466)
				)
				(xy 139.371832 -33.83026) (xy 139.344146 -33.83026) (xy 139.336272 -33.830514) (xy 139.3317 -33.83026)
				(xy 139.014708 -33.83026) (xy 139.014708 -33.96996) (xy 139.331954 -33.96996) (xy 139.336526 -33.96996)
				(xy 139.3444 -33.96996) (xy 139.372086 -33.96996)
				(arc
					(start 139.37488 -33.973008)
					(mid 139.512664 -34.042996)
					(end 139.582652 -34.18078)
				)
				(xy 139.5857 -34.183574) (xy 139.5857 -34.21126)
				(arc
					(start 139.5857 -34.215832)
					(mid 139.499848 -34.993909)
					(end 139.413996 -34.215832)
				)
				(arc
					(start 139.413996 -34.215832)
					(mid 139.390175 -34.163149)
					(end 139.336526 -34.141664)
				)
				(xy 139.331954 -34.141664) (xy 139.014708 -34.141664)
				(arc
					(start 139.014708 -34.600134)
					(mid 139.499848 -35.085274)
					(end 139.984988 -34.600134)
				)
			)
		)
	)
	(zone
		(layer "B.Cu")
		(hatch none 0.5)
		(connect_pads
			(clearance 0)
		)
		(min_thickness 0.25)
		(keepout
			(tracks not_allowed)
			(vias allowed)
			(pads allowed)
			(copperpour not_allowed)
			(footprints allowed)
		)
		(placement
			(enabled no)
			(sheetname "")
		)
		(fill
			(thermal_gap 0.5)
			(thermal_bridge_width 0.5)
			(island_removal_mode 0)
		)
		(polygon
			(pts
				(arc
					(start 83.300062 -105.050082)
					(mid 78.550008 -100.300028)
					(end 73.799954 -105.050082)
				)
				(arc
					(start 73.799954 -105.050082)
					(mid 78.550008 -109.800136)
					(end 83.300062 -105.050082)
				)
			)
		)
	)
	(zone
		(layer "B.Cu")
		(hatch none 0.5)
		(connect_pads
			(clearance 0)
		)
		(min_thickness 0.25)
		(keepout
			(tracks not_allowed)
			(vias allowed)
			(pads allowed)
			(copperpour not_allowed)
			(footprints allowed)
		)
		(placement
			(enabled no)
			(sheetname "")
		)
		(fill
			(thermal_gap 0.5)
			(thermal_bridge_width 0.5)
			(island_removal_mode 0)
		)
		(polygon
			(pts
				(arc
					(start 132.785104 -33.20034)
					(mid 132.300091 -32.714946)
					(end 131.814824 -33.200086)
				)
				(xy 131.814824 -33.659064) (xy 132.131816 -33.659064)
				(arc
					(start 132.136388 -33.65881)
					(mid 132.190168 -33.637199)
					(end 132.214112 -33.584388)
				)
				(arc
					(start 132.214112 -33.584388)
					(mid 132.299964 -32.806311)
					(end 132.385816 -33.584388)
				)
				(xy 132.385816 -33.58896) (xy 132.385816 -33.616646)
				(arc
					(start 132.382768 -33.61944)
					(mid 132.312703 -33.757401)
					(end 132.174742 -33.827466)
				)
				(xy 132.171948 -33.83026) (xy 132.144262 -33.83026) (xy 132.136388 -33.830514) (xy 132.131816 -33.83026)
				(xy 131.814824 -33.83026) (xy 131.814824 -33.96996) (xy 132.13207 -33.96996) (xy 132.136642 -33.96996)
				(xy 132.144516 -33.96996) (xy 132.172202 -33.96996)
				(arc
					(start 132.174996 -33.973008)
					(mid 132.31278 -34.042996)
					(end 132.382768 -34.18078)
				)
				(xy 132.385816 -34.183574) (xy 132.385816 -34.21126)
				(arc
					(start 132.385816 -34.215832)
					(mid 132.299964 -34.993909)
					(end 132.214112 -34.215832)
				)
				(arc
					(start 132.214112 -34.215832)
					(mid 132.190291 -34.163149)
					(end 132.136642 -34.141664)
				)
				(xy 132.13207 -34.141664) (xy 131.814824 -34.141664)
				(arc
					(start 131.814824 -34.600134)
					(mid 132.299964 -35.085274)
					(end 132.785104 -34.600134)
				)
			)
		)
	)
	(zone
		(layer "B.Cu")
		(hatch none 0.5)
		(connect_pads
			(clearance 0)
		)
		(min_thickness 0.25)
		(keepout
			(tracks allowed)
			(vias allowed)
			(pads allowed)
			(copperpour allowed)
			(footprints allowed)
		)
		(placement
			(enabled no)
			(sheetname "")
		)
		(fill
			(thermal_gap 0.5)
			(thermal_bridge_width 0.5)
			(island_removal_mode 0)
		)
		(polygon
			(pts
				(xy 127.414528 -34.80435) (xy 127.414528 -31.456376) (xy 142.239746 -31.456376) (xy 142.239746 -34.80435)
			)
		)
	)
	(zone
		(layer "B.Cu")
		(hatch none 0.5)
		(connect_pads
			(clearance 0)
		)
		(min_thickness 0.25)
		(keepout
			(tracks allowed)
			(vias allowed)
			(pads allowed)
			(copperpour allowed)
			(footprints not_allowed)
		)
		(placement
			(enabled no)
			(sheetname "")
		)
		(fill
			(thermal_gap 0.5)
			(thermal_bridge_width 0.5)
			(island_removal_mode 0)
		)
		(polygon
			(pts
				(arc
					(start 227.24999 -187.999878)
					(mid 222.499936 -183.249824)
					(end 217.749882 -187.999878)
				)
				(arc
					(start 217.749882 -187.999878)
					(mid 222.499936 -192.749932)
					(end 227.24999 -187.999878)
				)
			)
		)
	)
	(zone
		(net "P12V_STBY")
		(layer "B.Cu")
		(hatch none 0.5)
		(connect_pads
			(clearance 0.5)
		)
		(min_thickness 0.25)
		(fill yes
			(thermal_gap 0.5)
			(thermal_bridge_width 0.5)
			(island_removal_mode 0)
		)
		(polygon
			(pts
				(xy 222.25 -56.007) (xy 221.9706 -56.2864) (xy 221.9706 -60.6044) (xy 222.7326 -61.3664) (xy 228.2952 -61.3664)
				(xy 228.8032 -60.8584) (xy 228.8032 -56.7182) (xy 228.092 -56.007)
			)
		)
		(polygon
			(pts
				(xy 225.681286 -57.31891) (xy 225.478086 -57.31891) (xy 225.478086 -57.52211) (xy 225.681286 -57.52211)
			)
		)
		(polygon
			(pts
				(xy 224.284286 -57.31891) (xy 224.081086 -57.31891) (xy 224.081086 -57.52211) (xy 224.284286 -57.52211)
			)
		)
		(polygon
			(pts
				(xy 223.18726 -56.863742) (xy 222.98406 -56.863742) (xy 222.98406 -57.066942) (xy 223.18726 -57.066942)
			)
		)
		(polygon
			(pts
				(xy 222.32366 -56.863742) (xy 222.12046 -56.863742) (xy 222.12046 -57.066942) (xy 222.32366 -57.066942)
			)
		)
		(polygon
			(pts
				(xy 225.681286 -56.17591) (xy 225.478086 -56.17591) (xy 225.478086 -56.37911) (xy 225.681286 -56.37911)
			)
		)
		(polygon
			(pts
				(xy 224.284286 -56.17591) (xy 224.081086 -56.17591) (xy 224.081086 -56.37911) (xy 224.284286 -56.37911)
			)
		)
	)
	(zone
		(net "GND")
		(layer "B.Cu")
		(hatch none 0.5)
		(connect_pads
			(clearance 0.5)
		)
		(min_thickness 0.25)
		(fill yes
			(thermal_gap 0.5)
			(thermal_bridge_width 0.5)
			(island_removal_mode 0)
		)
		(polygon
			(pts
				(xy 62.773306 -157.7848) (xy 62.67196 -157.886146) (xy 62.67196 -159.092392) (xy 62.702186 -159.122618)
				(xy 63.07582 -159.122618) (xy 63.268098 -159.314896) (xy 63.268098 -160.26257) (xy 63.334392 -160.328864)
				(xy 64.410082 -160.328864) (xy 64.660018 -160.5788) (xy 65.1256 -160.5788) (xy 65.2272 -160.4772)
				(xy 65.2272 -158.7754) (xy 64.2366 -157.7848)
			)
		)
		(polygon
			(pts
				(xy 63.9826 -159.6136) (xy 63.7794 -159.6136) (xy 63.7794 -159.8168) (xy 63.9826 -159.8168)
			)
		)
	)
	(zone
		(layer "B.Cu")
		(hatch none 0.5)
		(connect_pads
			(clearance 0)
		)
		(min_thickness 0.25)
		(keepout
			(tracks not_allowed)
			(vias allowed)
			(pads allowed)
			(copperpour not_allowed)
			(footprints allowed)
		)
		(placement
			(enabled no)
			(sheetname "")
		)
		(fill
			(thermal_gap 0.5)
			(thermal_bridge_width 0.5)
			(island_removal_mode 0)
		)
		(polygon
			(pts
				(arc
					(start 77.736192 -67.312286)
					(mid 77.355319 -66.931032)
					(end 76.974192 -67.312032)
				)
				(xy 76.974192 -67.515232) (xy 77.03058 -67.515232)
				(arc
					(start 77.115924 -67.429888)
					(mid 77.543791 -67.123433)
					(end 77.237336 -67.5513)
				)
				(xy 77.1017 -67.686682) (xy 77.1017 -67.686936) (xy 76.974192 -67.686936) (xy 76.974192 -67.826636)
				(xy 77.101954 -67.826636)
				(arc
					(start 77.237336 -67.961764)
					(mid 77.543791 -68.389631)
					(end 77.115924 -68.083176)
				)
				(xy 77.030834 -67.997832) (xy 76.974192 -67.997832)
				(arc
					(start 76.974192 -68.201032)
					(mid 77.355192 -68.582032)
					(end 77.736192 -68.201032)
				)
			)
		)
	)
	(zone
		(layer "B.Cu")
		(hatch none 0.5)
		(connect_pads
			(clearance 0)
		)
		(min_thickness 0.25)
		(keepout
			(tracks not_allowed)
			(vias allowed)
			(pads allowed)
			(copperpour not_allowed)
			(footprints allowed)
		)
		(placement
			(enabled no)
			(sheetname "")
		)
		(fill
			(thermal_gap 0.5)
			(thermal_bridge_width 0.5)
			(island_removal_mode 0)
		)
		(polygon
			(pts
				(arc
					(start 27.649932 -105.050082)
					(mid 22.900132 -100.300282)
					(end 18.150078 -105.050082)
				)
				(arc
					(start 18.150078 -105.050082)
					(mid 22.900132 -109.800136)
					(end 27.649932 -105.050082)
				)
			)
		)
	)
	(zone
		(net "P3V3_STBY")
		(layer "B.Cu")
		(hatch none 0.5)
		(connect_pads
			(clearance 0.5)
		)
		(min_thickness 0.25)
		(fill yes
			(thermal_gap 0.5)
			(thermal_bridge_width 0.5)
			(island_removal_mode 0)
		)
		(polygon
			(pts
				(xy 51.17338 -145.52422) (xy 50.4444 -146.2532) (xy 49.1744 -146.2532) (xy 49.0728 -146.3548) (xy 49.0728 -146.7104)
				(xy 49.4919 -147.1295) (xy 50.1015 -147.1295) (xy 50.77714 -147.80514) (xy 50.77714 -148.43506)
				(xy 50.979324 -148.637244) (xy 51.886866 -148.637244) (xy 51.95062 -148.57349) (xy 51.95062 -147.806664)
				(xy 51.90109 -147.757134) (xy 51.506374 -147.757134) (xy 51.33086 -147.58162) (xy 51.33086 -146.431)
				(xy 51.56454 -146.19732) (xy 51.92776 -146.19732) (xy 52.02682 -146.09826) (xy 52.02682 -145.68424)
				(xy 52.01412 -145.68424) (xy 51.8541 -145.52422)
			)
		)
		(polygon
			(pts
				(xy 51.13782 -147.66036) (xy 50.93462 -147.66036) (xy 50.93462 -147.86356) (xy 51.13782 -147.86356)
			)
		)
		(polygon
			(pts
				(xy 50.62982 -147.00758) (xy 50.42662 -147.00758) (xy 50.42662 -147.21078) (xy 50.62982 -147.21078)
			)
		)
	)
	(zone
		(layer "B.Cu")
		(hatch none 0.5)
		(connect_pads
			(clearance 0)
		)
		(min_thickness 0.25)
		(keepout
			(tracks allowed)
			(vias allowed)
			(pads allowed)
			(copperpour allowed)
			(footprints not_allowed)
		)
		(placement
			(enabled no)
			(sheetname "")
		)
		(fill
			(thermal_gap 0.5)
			(thermal_bridge_width 0.5)
			(island_removal_mode 0)
		)
		(polygon
			(pts
				(arc
					(start 145.2499 -120.000014)
					(mid 149.999954 -124.750068)
					(end 154.750008 -120.000014)
				)
				(arc
					(start 154.750008 -120.000014)
					(mid 149.999954 -115.24996)
					(end 145.2499 -120.000014)
				)
			)
		)
	)
	(zone
		(net "GND")
		(layer "B.Cu")
		(hatch none 0.5)
		(connect_pads
			(clearance 0.5)
		)
		(min_thickness 0.25)
		(fill yes
			(thermal_gap 0.5)
			(thermal_bridge_width 0.5)
			(island_removal_mode 0)
		)
		(polygon
			(pts
				(xy 71.378064 -177.75428) (xy 70.66788 -178.464464) (xy 70.66788 -182.064152) (xy 71.222616 -182.618888)
				(xy 82.267298 -182.618888) (xy 83.08848 -181.797706) (xy 83.08848 -179.10048) (xy 81.74228 -177.75428)
			)
		)
	)
	(zone
		(layer "B.Cu")
		(hatch none 0.5)
		(connect_pads
			(clearance 0)
		)
		(min_thickness 0.25)
		(keepout
			(tracks not_allowed)
			(vias allowed)
			(pads allowed)
			(copperpour not_allowed)
			(footprints allowed)
		)
		(placement
			(enabled no)
			(sheetname "")
		)
		(fill
			(thermal_gap 0.5)
			(thermal_bridge_width 0.5)
			(island_removal_mode 0)
		)
		(polygon
			(pts
				(arc
					(start 78.503018 -89.711022)
					(mid 78.122145 -89.329768)
					(end 77.741018 -89.710768)
				)
				(arc
					(start 77.741018 -90.599768)
					(mid 78.122018 -90.980768)
					(end 78.503018 -90.599768)
				)
				(xy 78.503018 -90.396568) (xy 78.446376 -90.396568)
				(arc
					(start 78.361286 -90.481912)
					(mid 77.933419 -90.788367)
					(end 78.239874 -90.3605)
				)
				(xy 78.375256 -90.225372) (xy 78.503018 -90.225372) (xy 78.503018 -90.085672) (xy 78.37551 -90.085672)
				(xy 78.37551 -90.085418)
				(arc
					(start 78.239874 -89.950036)
					(mid 77.933419 -89.522169)
					(end 78.361286 -89.828624)
				)
				(xy 78.44663 -89.913968) (xy 78.503018 -89.913968)
			)
		)
	)
	(zone
		(layer "B.Cu")
		(hatch none 0.5)
		(connect_pads
			(clearance 0)
		)
		(min_thickness 0.25)
		(keepout
			(tracks not_allowed)
			(vias allowed)
			(pads allowed)
			(copperpour not_allowed)
			(footprints allowed)
		)
		(placement
			(enabled no)
			(sheetname "")
		)
		(fill
			(thermal_gap 0.5)
			(thermal_bridge_width 0.5)
			(island_removal_mode 0)
		)
		(polygon
			(pts
				(arc
					(start 118.385082 -33.20034)
					(mid 117.900069 -32.714946)
					(end 117.414802 -33.200086)
				)
				(xy 117.414802 -33.659064) (xy 117.731794 -33.659064)
				(arc
					(start 117.736366 -33.65881)
					(mid 117.790146 -33.637199)
					(end 117.81409 -33.584388)
				)
				(arc
					(start 117.81409 -33.584388)
					(mid 117.899942 -32.806311)
					(end 117.985794 -33.584388)
				)
				(xy 117.98554 -33.58896) (xy 117.98554 -33.616646)
				(arc
					(start 117.982746 -33.61944)
					(mid 117.912681 -33.757401)
					(end 117.77472 -33.827466)
				)
				(xy 117.771926 -33.83026) (xy 117.74424 -33.83026) (xy 117.736366 -33.830514) (xy 117.731794 -33.83026)
				(xy 117.414802 -33.83026) (xy 117.414802 -33.96996) (xy 117.732048 -33.96996) (xy 117.73662 -33.96996)
				(xy 117.744494 -33.96996) (xy 117.77218 -33.96996)
				(arc
					(start 117.774974 -33.973008)
					(mid 117.912758 -34.042996)
					(end 117.982746 -34.18078)
				)
				(xy 117.98554 -34.183574) (xy 117.98554 -34.21126)
				(arc
					(start 117.985794 -34.215832)
					(mid 117.899942 -34.993909)
					(end 117.81409 -34.215832)
				)
				(arc
					(start 117.81409 -34.215832)
					(mid 117.790269 -34.163149)
					(end 117.73662 -34.141664)
				)
				(xy 117.732048 -34.141664) (xy 117.414802 -34.141664)
				(arc
					(start 117.414802 -34.600134)
					(mid 117.899942 -35.085274)
					(end 118.385082 -34.600134)
				)
			)
		)
	)
	(zone
		(net "P3V3")
		(layer "B.Cu")
		(hatch none 0.5)
		(connect_pads
			(clearance 0.5)
		)
		(min_thickness 0.25)
		(fill yes
			(thermal_gap 0.5)
			(thermal_bridge_width 0.5)
			(island_removal_mode 0)
		)
		(polygon
			(pts
				(xy 84.0486 -47.9044) (xy 83.82 -48.133) (xy 83.82 -50.9524) (xy 82.6516 -52.1208) (xy 80.6704 -52.1208)
				(xy 77.9018 -54.8894) (xy 77.3176 -54.8894) (xy 77.216 -54.991) (xy 77.216 -56.9468) (xy 77.343 -57.0738)
				(xy 81.5848 -57.0738) (xy 81.7118 -56.9468) (xy 81.7118 -55.0926) (xy 81.5086 -54.8894) (xy 81.5086 -54.1274)
				(xy 81.8896 -53.7464) (xy 85.2932 -53.7464) (xy 86.1314 -52.9082) (xy 86.1314 -48.0822) (xy 85.9536 -47.9044)
			)
		)
	)
	(zone
		(net "P3V3_STBY")
		(layer "B.Cu")
		(hatch none 0.5)
		(connect_pads
			(clearance 0.5)
		)
		(min_thickness 0.25)
		(fill yes
			(thermal_gap 0.5)
			(thermal_bridge_width 0.5)
			(island_removal_mode 0)
		)
		(polygon
			(pts
				(xy 32.1564 -127.6604) (xy 32.0548 -127.762) (xy 32.0548 -129.159) (xy 29.811218 -131.402582) (xy 29.811218 -132.842508)
				(xy 30.163008 -133.194298) (xy 30.163008 -134.652512) (xy 30.793182 -135.282686) (xy 31.604712 -135.282686)
				(xy 31.987744 -135.665718) (xy 31.987744 -136.870948) (xy 34.223452 -139.106402) (xy 34.384488 -139.267438)
				(xy 35.864038 -139.267438) (xy 36.1188 -139.5222) (xy 36.1188 -139.930124) (xy 36.281868 -140.093192)
				(xy 39.307008 -140.093192) (xy 39.5478 -139.8524) (xy 39.5478 -138.9634) (xy 39.482268 -138.897868)
				(xy 37.95141 -138.897868) (xy 36.45662 -137.403078) (xy 36.45662 -135.46582) (xy 36.02355 -135.03275)
				(xy 36.02355 -132.40385) (xy 36.6776 -131.7498) (xy 37.4142 -131.7498) (xy 37.6174 -131.5466) (xy 37.6174 -128.905)
				(xy 37.5666 -128.8542) (xy 35.162236 -128.8542) (xy 34.752534 -128.444498) (xy 34.752534 -127.703072)
				(xy 34.709862 -127.6604)
			)
		)
		(polygon
			(pts
				(xy 38.65753 -139.056364) (xy 38.45433 -139.056364) (xy 38.45433 -139.259564) (xy 38.65753 -139.259564)
			)
		)
		(polygon
			(pts
				(xy 38.33876 -139.04849) (xy 38.13556 -139.04849) (xy 38.13556 -139.25169) (xy 38.33876 -139.25169)
			)
		)
		(polygon
			(pts
				(xy 37.47516 -139.04849) (xy 37.27196 -139.04849) (xy 37.27196 -139.25169) (xy 37.47516 -139.25169)
			)
		)
		(polygon
			(pts
				(xy 37.118798 -139.036044) (xy 36.915598 -139.036044) (xy 36.915598 -139.239244) (xy 37.118798 -139.239244)
			)
		)
		(polygon
			(pts
				(xy 36.255198 -139.036044) (xy 36.051998 -139.036044) (xy 36.051998 -139.239244) (xy 36.255198 -139.239244)
			)
		)
		(polygon
			(pts
				(xy 37.0586 -131.0132) (xy 36.8554 -131.0132) (xy 36.8554 -131.2164) (xy 37.0586 -131.2164)
			)
		)
		(polygon
			(pts
				(xy 37.186362 -129.562606) (xy 36.983162 -129.562606) (xy 36.983162 -129.765806) (xy 37.186362 -129.765806)
			)
		)
		(polygon
			(pts
				(xy 37.186362 -129.003806) (xy 36.983162 -129.003806) (xy 36.983162 -129.207006) (xy 37.186362 -129.207006)
			)
		)
		(polygon
			(pts
				(xy 32.766 -128.3716) (xy 32.5628 -128.3716) (xy 32.5628 -128.5748) (xy 32.766 -128.5748)
			)
		)
	)
	(zone
		(layer "B.Cu")
		(hatch none 0.5)
		(connect_pads
			(clearance 0)
		)
		(min_thickness 0.25)
		(keepout
			(tracks allowed)
			(vias allowed)
			(pads allowed)
			(copperpour allowed)
			(footprints not_allowed)
		)
		(placement
			(enabled no)
			(sheetname "")
		)
		(fill
			(thermal_gap 0.5)
			(thermal_bridge_width 0.5)
			(island_removal_mode 0)
		)
		(polygon
			(pts
				(arc
					(start 174.649892 -51.250088)
					(mid 179.399946 -56.000142)
					(end 184.15 -51.250088)
				)
				(arc
					(start 184.15 -51.250088)
					(mid 179.399946 -46.500034)
					(end 174.649892 -51.250088)
				)
			)
		)
	)
	(zone
		(layer "B.Cu")
		(hatch none 0.5)
		(connect_pads
			(clearance 0)
		)
		(min_thickness 0.25)
		(keepout
			(tracks allowed)
			(vias allowed)
			(pads allowed)
			(copperpour allowed)
			(footprints not_allowed)
		)
		(placement
			(enabled no)
			(sheetname "")
		)
		(fill
			(thermal_gap 0.5)
			(thermal_bridge_width 0.5)
			(island_removal_mode 0)
		)
		(polygon
			(pts
				(arc
					(start 17.249902 -187.999878)
					(mid 12.500102 -183.250078)
					(end 7.750048 -187.999878)
				)
				(arc
					(start 7.750048 -187.999878)
					(mid 12.500102 -192.749932)
					(end 17.249902 -187.999878)
				)
			)
		)
	)
	(zone
		(layer "B.Cu")
		(hatch none 0.5)
		(connect_pads
			(clearance 0)
		)
		(min_thickness 0.25)
		(keepout
			(tracks not_allowed)
			(vias allowed)
			(pads allowed)
			(copperpour not_allowed)
			(footprints allowed)
		)
		(placement
			(enabled no)
			(sheetname "")
		)
		(fill
			(thermal_gap 0.5)
			(thermal_bridge_width 0.5)
			(island_removal_mode 0)
		)
		(polygon
			(pts
				(arc
					(start 84.749894 -120.000014)
					(mid 80.000094 -115.250214)
					(end 75.25004 -120.000014)
				)
				(arc
					(start 75.25004 -120.000014)
					(mid 80.000094 -124.750068)
					(end 84.749894 -120.000014)
				)
			)
		)
	)
	(zone
		(layer "B.Cu")
		(hatch none 0.5)
		(connect_pads
			(clearance 0)
		)
		(min_thickness 0.25)
		(keepout
			(tracks allowed)
			(vias allowed)
			(pads allowed)
			(copperpour allowed)
			(footprints allowed)
		)
		(placement
			(enabled no)
			(sheetname "")
		)
		(fill
			(thermal_gap 0.5)
			(thermal_bridge_width 0.5)
			(island_removal_mode 0)
		)
		(polygon
			(pts
				(xy 105.969816 -34.609278) (xy 105.969816 -31.261304) (xy 120.795034 -31.261304) (xy 120.795034 -34.609278)
			)
		)
	)
	(zone
		(layer "B.Cu")
		(hatch none 0.5)
		(connect_pads
			(clearance 0)
		)
		(min_thickness 0.25)
		(keepout
			(tracks not_allowed)
			(vias allowed)
			(pads allowed)
			(copperpour not_allowed)
			(footprints allowed)
		)
		(placement
			(enabled no)
			(sheetname "")
		)
		(fill
			(thermal_gap 0.5)
			(thermal_bridge_width 0.5)
			(island_removal_mode 0)
		)
		(polygon
			(pts
				(arc
					(start 112.985042 -32.00019)
					(mid 112.499902 -31.51505)
					(end 112.014762 -32.00019)
				)
				(xy 112.014762 -32.45866) (xy 112.332008 -32.45866)
				(arc
					(start 112.33658 -32.45866)
					(mid 112.39018 -32.437124)
					(end 112.41405 -32.384492)
				)
				(arc
					(start 112.41405 -32.384492)
					(mid 112.499902 -31.606415)
					(end 112.585754 -32.384492)
				)
				(xy 112.5855 -32.389064) (xy 112.5855 -32.41675)
				(arc
					(start 112.582706 -32.419544)
					(mid 112.512718 -32.557328)
					(end 112.374934 -32.627316)
				)
				(xy 112.37214 -32.630364) (xy 112.344454 -32.630364) (xy 112.33658 -32.630364) (xy 112.332008 -32.630364)
				(xy 112.014762 -32.630364) (xy 112.014762 -32.770064) (xy 112.332008 -32.770064) (xy 112.33658 -32.76981)
				(xy 112.344454 -32.770064) (xy 112.37214 -32.770064)
				(arc
					(start 112.374934 -32.772858)
					(mid 112.512718 -32.842846)
					(end 112.582706 -32.98063)
				)
				(xy 112.5855 -32.983424) (xy 112.5855 -33.01111)
				(arc
					(start 112.585754 -33.015682)
					(mid 112.499902 -33.793759)
					(end 112.41405 -33.015682)
				)
				(arc
					(start 112.41405 -33.015682)
					(mid 112.390229 -32.962999)
					(end 112.33658 -32.941514)
				)
				(xy 112.332008 -32.94126) (xy 112.014762 -32.94126)
				(arc
					(start 112.014762 -33.39973)
					(mid 112.499775 -33.885124)
					(end 112.985042 -33.399984)
				)
			)
		)
	)
	(zone
		(layer "B.Cu")
		(hatch none 0.5)
		(connect_pads
			(clearance 0)
		)
		(min_thickness 0.25)
		(keepout
			(tracks allowed)
			(vias allowed)
			(pads allowed)
			(copperpour allowed)
			(footprints not_allowed)
		)
		(placement
			(enabled no)
			(sheetname "")
		)
		(fill
			(thermal_gap 0.5)
			(thermal_bridge_width 0.5)
			(island_removal_mode 0)
		)
		(polygon
			(pts
				(arc
					(start 184.15 -51.250088)
					(mid 179.399946 -46.500034)
					(end 174.649892 -51.250088)
				)
				(arc
					(start 174.649892 -51.250088)
					(mid 179.399946 -56.000142)
					(end 184.15 -51.250088)
				)
			)
		)
	)
	(zone
		(net "P2V5_STBY")
		(layer "B.Cu")
		(hatch none 0.5)
		(connect_pads
			(clearance 0.5)
		)
		(min_thickness 0.25)
		(fill yes
			(thermal_gap 0.5)
			(thermal_bridge_width 0.5)
			(island_removal_mode 0)
		)
		(polygon
			(pts
				(xy 36.9316 -164.2872) (xy 35.122104 -166.096696) (xy 30.998922 -166.096696) (xy 30.672786 -166.422832)
				(xy 30.672786 -168.162986) (xy 30.8356 -168.3258) (xy 34.961322 -168.3258) (xy 35.3314 -167.955722)
				(xy 37.846 -167.955722) (xy 39.558722 -166.243) (xy 43.845988 -166.243) (xy 48.085248 -170.48226)
				(xy 61.835792 -170.48226) (xy 62.568836 -169.749216) (xy 64.456564 -169.749216) (xy 66.675 -167.53078)
				(xy 68.120514 -167.53078) (xy 72.52843 -171.938696) (xy 77.371702 -171.938696) (xy 77.6986 -171.611798)
				(xy 77.6986 -170.2816) (xy 77.4954 -170.0784) (xy 74.582528 -170.0784) (xy 70.290182 -165.786054)
				(xy 65.063878 -165.786054) (xy 64.036448 -166.813484) (xy 64.036448 -166.894764) (xy 63.107062 -167.82415)
				(xy 47.91075 -167.82415) (xy 44.3738 -164.2872)
			)
		)
	)
	(zone
		(layer "B.Cu")
		(hatch none 0.5)
		(connect_pads
			(clearance 0)
		)
		(min_thickness 0.25)
		(keepout
			(tracks allowed)
			(vias allowed)
			(pads allowed)
			(copperpour allowed)
			(footprints not_allowed)
		)
		(placement
			(enabled no)
			(sheetname "")
		)
		(fill
			(thermal_gap 0.5)
			(thermal_bridge_width 0.5)
			(island_removal_mode 0)
		)
		(polygon
			(pts
				(arc
					(start 27.55011 -60.550044)
					(mid 22.800056 -55.79999)
					(end 18.050002 -60.550044)
				)
				(arc
					(start 18.050002 -60.550044)
					(mid 22.800056 -65.300098)
					(end 27.55011 -60.550044)
				)
			)
		)
	)
	(zone
		(layer "B.Cu")
		(hatch none 0.5)
		(connect_pads
			(clearance 0)
		)
		(min_thickness 0.25)
		(keepout
			(tracks not_allowed)
			(vias allowed)
			(pads allowed)
			(copperpour not_allowed)
			(footprints allowed)
		)
		(placement
			(enabled no)
			(sheetname "")
		)
		(fill
			(thermal_gap 0.5)
			(thermal_bridge_width 0.5)
			(island_removal_mode 0)
		)
		(polygon
			(pts
				(arc
					(start 160.250124 -153.999946)
					(mid 155.50007 -149.249892)
					(end 150.750016 -153.999946)
				)
				(arc
					(start 150.750016 -153.999946)
					(mid 155.50007 -158.75)
					(end 160.250124 -153.999946)
				)
			)
		)
	)
	(zone
		(layer "B.Cu")
		(hatch none 0.5)
		(connect_pads
			(clearance 0)
		)
		(min_thickness 0.25)
		(keepout
			(tracks allowed)
			(vias allowed)
			(pads allowed)
			(copperpour allowed)
			(footprints not_allowed)
		)
		(placement
			(enabled no)
			(sheetname "")
		)
		(fill
			(thermal_gap 0.5)
			(thermal_bridge_width 0.5)
			(island_removal_mode 0)
		)
		(polygon
			(pts
				(arc
					(start 230.2764 -193.447162)
					(mid 230.156976 -193.631987)
					(end 230.000048 -193.786252)
				)
				(xy 230.000048 0)
				(arc
					(start 234.00004 0)
					(mid 234.707145 -0.292893)
					(end 235.000038 -0.999998)
				)
				(arc
					(start 235.000038 -183.76392)
					(mid 234.973274 -183.993728)
					(end 234.894374 -184.211214)
				)
			)
		)
	)
	(zone
		(net "P1V2_STBY")
		(layer "B.Cu")
		(hatch none 0.5)
		(connect_pads
			(clearance 0.5)
		)
		(min_thickness 0.25)
		(fill yes
			(thermal_gap 0.5)
			(thermal_bridge_width 0.5)
			(island_removal_mode 0)
		)
		(polygon
			(pts
				(xy 30.02407 -142.180056) (xy 28.236418 -143.967708) (xy 22.640036 -143.967708) (xy 22.565106 -144.042638)
				(xy 22.565106 -144.36725) (xy 22.407118 -144.525238) (xy 21.574506 -144.525238) (xy 21.51634 -144.467072)
				(xy 21.51634 -144.025874) (xy 21.408136 -143.91767) (xy 20.955 -143.91767) (xy 20.91055 -143.96212)
				(xy 20.91055 -144.851374) (xy 21.448776 -145.3896) (xy 23.088092 -145.3896) (xy 23.532846 -145.834354)
				(xy 25.895554 -145.834354) (xy 26.041604 -145.980404) (xy 26.041604 -146.919188) (xy 25.828498 -147.132294)
				(xy 23.465536 -147.132294) (xy 23.324058 -147.273772) (xy 23.324058 -149.41296) (xy 23.330662 -149.419564)
				(xy 23.330662 -151.774144) (xy 23.547578 -151.99106) (xy 26.007314 -151.99106) (xy 26.473912 -151.524462)
				(xy 26.473912 -151.52243) (xy 28.641802 -149.35454) (xy 30.8483 -149.35454) (xy 34.36112 -145.84172)
				(xy 37.756846 -145.84172) (xy 38.24859 -145.349976) (xy 38.24859 -144.530826) (xy 38.355524 -144.423892)
				(xy 39.021766 -144.423892) (xy 39.0906 -144.355058) (xy 39.0906 -143.3576) (xy 38.989 -143.256)
				(xy 33.512506 -143.256) (xy 32.436562 -142.180056)
			)
		)
		(polygon
			(pts
				(xy 26.75382 -146.622008) (xy 26.55062 -146.622008) (xy 26.55062 -146.825208) (xy 26.75382 -146.825208)
			)
		)
		(polygon
			(pts
				(xy 26.75382 -146.012408) (xy 26.55062 -146.012408) (xy 26.55062 -146.215608) (xy 26.75382 -146.215608)
			)
		)
		(polygon
			(pts
				(xy 24.863298 -145.109946) (xy 24.660098 -145.109946) (xy 24.660098 -145.313146) (xy 24.863298 -145.313146)
			)
		)
		(polygon
			(pts
				(xy 24.253698 -145.109946) (xy 24.050498 -145.109946) (xy 24.050498 -145.313146) (xy 24.253698 -145.313146)
			)
		)
		(polygon
			(pts
				(xy 37.570664 -145.06067) (xy 37.367464 -145.06067) (xy 37.367464 -145.26387) (xy 37.570664 -145.26387)
			)
		)
		(polygon
			(pts
				(xy 23.99538 -144.47901) (xy 23.79218 -144.47901) (xy 23.79218 -144.68221) (xy 23.99538 -144.68221)
			)
		)
		(polygon
			(pts
				(xy 23.38578 -144.47901) (xy 23.18258 -144.47901) (xy 23.18258 -144.68221) (xy 23.38578 -144.68221)
			)
		)
		(polygon
			(pts
				(xy 24.463502 -144.471644) (xy 24.260302 -144.471644) (xy 24.260302 -144.674844) (xy 24.463502 -144.674844)
			)
		)
		(polygon
			(pts
				(xy 25.963626 -144.47139) (xy 25.760426 -144.47139) (xy 25.760426 -144.67459) (xy 25.963626 -144.67459)
			)
		)
		(polygon
			(pts
				(xy 25.354026 -144.47139) (xy 25.150826 -144.47139) (xy 25.073102 -144.471644) (xy 24.869902 -144.471644)
				(xy 24.869902 -144.674844) (xy 25.073102 -144.674844) (xy 25.150826 -144.67459) (xy 25.354026 -144.67459)
			)
		)
		(polygon
			(pts
				(xy 37.570664 -144.45107) (xy 37.367464 -144.45107) (xy 37.367464 -144.65427) (xy 37.570664 -144.65427)
			)
		)
		(polygon
			(pts
				(xy 36.572698 -144.117314) (xy 36.369498 -144.117314) (xy 36.369498 -144.320514) (xy 36.572698 -144.320514)
			)
		)
		(polygon
			(pts
				(xy 35.709098 -144.117314) (xy 35.505898 -144.117314) (xy 35.505898 -144.320514) (xy 35.709098 -144.320514)
			)
		)
		(polygon
			(pts
				(xy 38.952678 -144.100042) (xy 38.749478 -144.100042) (xy 38.749478 -144.303242) (xy 38.952678 -144.303242)
			)
		)
		(polygon
			(pts
				(xy 38.089078 -144.100042) (xy 37.885878 -144.100042) (xy 37.885878 -144.303242) (xy 38.089078 -144.303242)
			)
		)
		(polygon
			(pts
				(xy 37.761418 -144.091914) (xy 37.558218 -144.091914) (xy 37.558218 -144.295114) (xy 37.761418 -144.295114)
			)
		)
		(polygon
			(pts
				(xy 36.897818 -144.091914) (xy 36.694618 -144.091914) (xy 36.694618 -144.295114) (xy 36.897818 -144.295114)
			)
		)
	)
	(zone
		(net "GND")
		(layer "B.Cu")
		(hatch none 0.5)
		(connect_pads
			(clearance 0.5)
		)
		(min_thickness 0.25)
		(fill yes
			(thermal_gap 0.5)
			(thermal_bridge_width 0.5)
			(island_removal_mode 0)
		)
		(polygon
			(pts
				(xy 10.043922 -126.387352) (xy 6.99135 -129.439924) (xy 6.99135 -146.554444) (xy 10.689844 -150.252938)
				(xy 12.45108 -150.252938) (xy 12.942062 -149.761956) (xy 12.942062 -145.994882) (xy 13.181076 -145.755868)
				(xy 13.181076 -145.32483) (xy 13.172186 -145.32483) (xy 13.172186 -144.964912) (xy 13.040106 -144.832832)
				(xy 11.40968 -144.832832) (xy 11.226292 -144.649444) (xy 11.226292 -143.775938) (xy 10.668254 -143.2179)
				(xy 10.214102 -143.2179) (xy 10.036556 -143.040354) (xy 10.036556 -131.230878) (xy 12.337034 -128.9304)
				(xy 25.1206 -128.9304) (xy 25.4762 -129.286) (xy 25.4762 -129.308098) (xy 26.3398 -130.171698) (xy 26.3398 -141.544294)
				(xy 26.08961 -141.794484) (xy 25.755092 -141.794484) (xy 25.508712 -142.040864) (xy 25.508712 -142.675102)
				(xy 25.312624 -142.87119) (xy 24.580088 -142.87119) (xy 24.51735 -142.808452) (xy 23.433278 -142.808452)
				(xy 23.320248 -142.921482) (xy 22.695916 -142.921482) (xy 22.583648 -143.03375) (xy 22.583648 -143.537432)
				(xy 22.720554 -143.674338) (xy 27.833828 -143.674338) (xy 29.742638 -141.765528) (xy 32.72282 -141.765528)
				(xy 33.785556 -142.828264) (xy 38.78199 -142.828264) (xy 38.873938 -142.736316) (xy 39.141908 -142.736316)
				(xy 39.175436 -142.769844) (xy 40.132 -142.769844) (xy 40.132 -140.914628) (xy 39.577772 -140.3604)
				(xy 35.959796 -140.3604) (xy 35.803332 -140.203936) (xy 35.803332 -139.689332) (xy 35.7886 -139.6746)
				(xy 33.095946 -139.6746) (xy 31.766256 -138.34491) (xy 31.766256 -137.328656) (xy 29.8704 -135.4328)
				(xy 29.8704 -133.3246) (xy 29.464 -132.9182) (xy 29.464 -128.0922) (xy 27.759152 -126.387352)
			)
		)
		(polygon
			(pts
				(xy 12.1793 -147.7137) (xy 11.9761 -147.7137) (xy 11.9761 -147.9169) (xy 12.1793 -147.9169)
			)
		)
		(polygon
			(pts
				(xy 12.1793 -146.8501) (xy 11.9761 -146.8501) (xy 11.9761 -147.0533) (xy 12.1793 -147.0533)
			)
		)
		(polygon
			(pts
				(xy 12.714224 -145.41373) (xy 12.511024 -145.41373) (xy 12.511024 -145.61693) (xy 12.714224 -145.61693)
			)
		)
		(polygon
			(pts
				(xy 10.304272 -144.428464) (xy 10.101072 -144.428464) (xy 10.101072 -144.631664) (xy 10.304272 -144.631664)
			)
		)
		(polygon
			(pts
				(xy 10.304272 -143.564864) (xy 10.101072 -143.564864) (xy 10.101072 -143.768064) (xy 10.304272 -143.768064)
			)
		)
		(polygon
			(pts
				(xy 23.99538 -142.95501) (xy 23.79218 -142.95501) (xy 23.79218 -143.15821) (xy 23.99538 -143.15821)
			)
		)
		(polygon
			(pts
				(xy 24.463502 -142.947644) (xy 24.260302 -142.947644) (xy 24.260302 -143.150844) (xy 24.463502 -143.150844)
			)
		)
		(polygon
			(pts
				(xy 25.963626 -142.94739) (xy 25.760426 -142.94739) (xy 25.760426 -143.15059) (xy 25.963626 -143.15059)
			)
		)
		(polygon
			(pts
				(xy 9.5758 -142.6464) (xy 9.3726 -142.6464) (xy 9.3726 -142.8496) (xy 9.5758 -142.8496)
			)
		)
		(polygon
			(pts
				(xy 26.155904 -142.459964) (xy 25.952704 -142.459964) (xy 25.952704 -142.663164) (xy 26.155904 -142.663164)
			)
		)
		(polygon
			(pts
				(xy 9.5758 -142.0876) (xy 9.3726 -142.0876) (xy 9.3726 -142.2908) (xy 9.5758 -142.2908)
			)
		)
		(polygon
			(pts
				(xy 39.573454 -142.079218) (xy 39.370254 -142.079218) (xy 39.370254 -142.282418) (xy 39.573454 -142.282418)
			)
		)
		(polygon
			(pts
				(xy 26.155904 -141.901164) (xy 25.952704 -141.901164) (xy 25.952704 -142.104364) (xy 26.155904 -142.104364)
			)
		)
		(polygon
			(pts
				(xy 36.572698 -141.831314) (xy 36.369498 -141.831314) (xy 36.369498 -142.034514) (xy 36.572698 -142.034514)
			)
		)
		(polygon
			(pts
				(xy 35.709098 -141.831314) (xy 35.505898 -141.831314) (xy 35.505898 -142.034514) (xy 35.709098 -142.034514)
			)
		)
		(polygon
			(pts
				(xy 38.952678 -141.814042) (xy 38.749478 -141.814042) (xy 38.749478 -142.017242) (xy 38.952678 -142.017242)
			)
		)
		(polygon
			(pts
				(xy 38.089078 -141.814042) (xy 37.885878 -141.814042) (xy 37.885878 -142.017242) (xy 38.089078 -142.017242)
			)
		)
		(polygon
			(pts
				(xy 37.761418 -141.805914) (xy 37.558218 -141.805914) (xy 37.558218 -142.009114) (xy 37.761418 -142.009114)
			)
		)
		(polygon
			(pts
				(xy 36.897818 -141.805914) (xy 36.694618 -141.805914) (xy 36.694618 -142.009114) (xy 36.897818 -142.009114)
			)
		)
		(polygon
			(pts
				(xy 39.52113 -141.342364) (xy 39.31793 -141.342364) (xy 39.31793 -141.545564) (xy 39.52113 -141.545564)
			)
		)
		(polygon
			(pts
				(xy 38.65753 -141.342364) (xy 38.45433 -141.342364) (xy 38.45433 -141.545564) (xy 38.65753 -141.545564)
			)
		)
		(polygon
			(pts
				(xy 38.33876 -141.33449) (xy 38.13556 -141.33449) (xy 38.13556 -141.53769) (xy 38.33876 -141.53769)
			)
		)
		(polygon
			(pts
				(xy 37.47516 -141.33449) (xy 37.27196 -141.33449) (xy 37.27196 -141.53769) (xy 37.47516 -141.53769)
			)
		)
		(polygon
			(pts
				(xy 37.118798 -141.322044) (xy 36.915598 -141.322044) (xy 36.915598 -141.525244) (xy 37.118798 -141.525244)
			)
		)
		(polygon
			(pts
				(xy 36.255198 -141.322044) (xy 36.051998 -141.322044) (xy 36.051998 -141.525244) (xy 36.255198 -141.525244)
			)
		)
		(polygon
			(pts
				(xy 9.59739 -141.186662) (xy 9.39419 -141.186662) (xy 9.39419 -141.389862) (xy 9.59739 -141.389862)
			)
		)
		(polygon
			(pts
				(xy 9.59739 -140.627862) (xy 9.39419 -140.627862) (xy 9.39419 -140.831062) (xy 9.59739 -140.831062)
			)
		)
		(polygon
			(pts
				(xy 39.52113 -140.478764) (xy 39.31793 -140.478764) (xy 39.31793 -140.681964) (xy 39.52113 -140.681964)
			)
		)
		(polygon
			(pts
				(xy 38.65753 -140.478764) (xy 38.45433 -140.478764) (xy 38.45433 -140.681964) (xy 38.65753 -140.681964)
			)
		)
		(polygon
			(pts
				(xy 38.33876 -140.47089) (xy 38.13556 -140.47089) (xy 38.13556 -140.67409) (xy 38.33876 -140.67409)
			)
		)
		(polygon
			(pts
				(xy 37.47516 -140.47089) (xy 37.27196 -140.47089) (xy 37.27196 -140.67409) (xy 37.47516 -140.67409)
			)
		)
		(polygon
			(pts
				(xy 9.601962 -139.752832) (xy 9.398762 -139.752832) (xy 9.398762 -139.956032) (xy 9.601962 -139.956032)
			)
		)
		(polygon
			(pts
				(xy 9.601962 -139.194032) (xy 9.398762 -139.194032) (xy 9.398762 -139.397232) (xy 9.601962 -139.397232)
			)
		)
		(polygon
			(pts
				(xy 9.590532 -138.323574) (xy 9.387332 -138.323574) (xy 9.387332 -138.526774) (xy 9.590532 -138.526774)
			)
		)
		(polygon
			(pts
				(xy 9.590532 -137.764774) (xy 9.387332 -137.764774) (xy 9.387332 -137.967974) (xy 9.590532 -137.967974)
			)
		)
		(polygon
			(pts
				(xy 9.565132 -136.894316) (xy 9.361932 -136.894316) (xy 9.361932 -137.097516) (xy 9.565132 -137.097516)
			)
		)
		(polygon
			(pts
				(xy 27.323796 -136.429496) (xy 27.120596 -136.429496) (xy 27.120596 -136.632696) (xy 27.323796 -136.632696)
			)
		)
		(polygon
			(pts
				(xy 9.565132 -136.335516) (xy 9.361932 -136.335516) (xy 9.361932 -136.538716) (xy 9.565132 -136.538716)
			)
		)
		(polygon
			(pts
				(xy 27.323796 -135.565896) (xy 27.120596 -135.565896) (xy 27.120596 -135.769096) (xy 27.323796 -135.769096)
			)
		)
		(polygon
			(pts
				(xy 9.59231 -135.467852) (xy 9.38911 -135.467852) (xy 9.38911 -135.671052) (xy 9.59231 -135.671052)
			)
		)
		(polygon
			(pts
				(xy 9.59231 -134.909052) (xy 9.38911 -134.909052) (xy 9.38911 -135.112252) (xy 9.59231 -135.112252)
			)
		)
		(polygon
			(pts
				(xy 9.59485 -134.03453) (xy 9.39165 -134.03453) (xy 9.39165 -134.23773) (xy 9.59485 -134.23773)
			)
		)
		(polygon
			(pts
				(xy 9.59485 -133.47573) (xy 9.39165 -133.47573) (xy 9.39165 -133.67893) (xy 9.59485 -133.67893)
			)
		)
		(polygon
			(pts
				(xy 9.583928 -132.580634) (xy 9.380728 -132.580634) (xy 9.380728 -132.783834) (xy 9.583928 -132.783834)
			)
		)
		(polygon
			(pts
				(xy 9.583928 -132.021834) (xy 9.380728 -132.021834) (xy 9.380728 -132.225034) (xy 9.583928 -132.225034)
			)
		)
		(polygon
			(pts
				(xy 25.2476 -128.2954) (xy 25.0444 -128.2954) (xy 25.0444 -128.4986) (xy 25.2476 -128.4986)
			)
		)
		(polygon
			(pts
				(xy 24.6888 -128.2954) (xy 24.4856 -128.2954) (xy 24.4856 -128.4986) (xy 24.6888 -128.4986)
			)
		)
		(polygon
			(pts
				(xy 23.818342 -128.2954) (xy 23.615142 -128.2954) (xy 23.615142 -128.4986) (xy 23.818342 -128.4986)
			)
		)
		(polygon
			(pts
				(xy 23.259542 -128.2954) (xy 23.056342 -128.2954) (xy 23.056342 -128.4986) (xy 23.259542 -128.4986)
			)
		)
		(polygon
			(pts
				(xy 22.395942 -128.2954) (xy 22.192742 -128.2954) (xy 22.192742 -128.4986) (xy 22.395942 -128.4986)
			)
		)
		(polygon
			(pts
				(xy 21.837142 -128.2954) (xy 21.633942 -128.2954) (xy 21.633942 -128.4986) (xy 21.837142 -128.4986)
			)
		)
		(polygon
			(pts
				(xy 19.525742 -128.264666) (xy 19.322542 -128.264666) (xy 19.322542 -128.467866) (xy 19.525742 -128.467866)
			)
		)
		(polygon
			(pts
				(xy 18.966942 -128.264666) (xy 18.763742 -128.264666) (xy 18.763742 -128.467866) (xy 18.966942 -128.467866)
			)
		)
		(polygon
			(pts
				(xy 16.700754 -128.264158) (xy 16.497554 -128.264158) (xy 16.497554 -128.467358) (xy 16.700754 -128.467358)
			)
		)
		(polygon
			(pts
				(xy 16.141954 -128.264158) (xy 15.938754 -128.264158) (xy 15.938754 -128.467358) (xy 16.141954 -128.467358)
			)
		)
		(polygon
			(pts
				(xy 20.972272 -128.261364) (xy 20.769072 -128.261364) (xy 20.769072 -128.464564) (xy 20.972272 -128.464564)
			)
		)
		(polygon
			(pts
				(xy 20.413472 -128.261364) (xy 20.210272 -128.261364) (xy 20.210272 -128.464564) (xy 20.413472 -128.464564)
			)
		)
		(polygon
			(pts
				(xy 18.130012 -128.238758) (xy 17.926812 -128.238758) (xy 17.926812 -128.441958) (xy 18.130012 -128.441958)
			)
		)
		(polygon
			(pts
				(xy 17.571212 -128.238758) (xy 17.368012 -128.238758) (xy 17.368012 -128.441958) (xy 17.571212 -128.441958)
			)
		)
	)
	(zone
		(net "GND")
		(layer "B.Cu")
		(hatch none 0.5)
		(connect_pads
			(clearance 0.5)
		)
		(min_thickness 0.25)
		(fill yes
			(thermal_gap 0.5)
			(thermal_bridge_width 0.5)
			(island_removal_mode 0)
		)
		(polygon
			(pts
				(xy 168.339008 -122.163078) (xy 168.099486 -122.4026) (xy 168.099486 -125.748796) (xy 168.386252 -126.035562)
				(xy 169.714164 -126.035562) (xy 169.8752 -125.874526) (xy 169.8752 -122.317764) (xy 169.720514 -122.163078)
			)
		)
		(polygon
			(pts
				(xy 169.375328 -125.730508) (xy 169.172128 -125.730508) (xy 169.172128 -125.933708) (xy 169.375328 -125.933708)
			)
		)
		(polygon
			(pts
				(xy 169.375328 -124.841508) (xy 169.172128 -124.841508) (xy 169.172128 -125.324108) (xy 169.375328 -125.324108)
			)
		)
		(polygon
			(pts
				(xy 169.375328 -124.231908) (xy 169.172128 -124.231908) (xy 169.172128 -124.435108) (xy 169.375328 -124.435108)
			)
		)
		(polygon
			(pts
				(xy 169.375328 -123.825508) (xy 169.172128 -123.825508) (xy 169.172128 -124.028708) (xy 169.375328 -124.028708)
			)
		)
		(polygon
			(pts
				(xy 169.375328 -123.215908) (xy 169.172128 -123.215908) (xy 169.172128 -123.419108) (xy 169.375328 -123.419108)
			)
		)
		(polygon
			(pts
				(xy 169.375328 -122.784108) (xy 169.172128 -122.784108) (xy 169.172128 -122.987308) (xy 169.375328 -122.987308)
			)
		)
	)
	(zone
		(layer "B.Cu")
		(hatch none 0.5)
		(connect_pads
			(clearance 0)
		)
		(min_thickness 0.25)
		(keepout
			(tracks allowed)
			(vias allowed)
			(pads allowed)
			(copperpour allowed)
			(footprints not_allowed)
		)
		(placement
			(enabled no)
			(sheetname "")
		)
		(fill
			(thermal_gap 0.5)
			(thermal_bridge_width 0.5)
			(island_removal_mode 0)
		)
		(polygon
			(pts
				(arc
					(start 18.150078 -105.050082)
					(mid 22.900132 -109.800136)
					(end 27.649932 -105.050082)
				)
				(arc
					(start 27.649932 -105.050082)
					(mid 22.900132 -100.300282)
					(end 18.150078 -105.050082)
				)
			)
		)
	)
	(zone
		(layer "B.Cu")
		(hatch none 0.5)
		(connect_pads
			(clearance 0)
		)
		(min_thickness 0.25)
		(keepout
			(tracks not_allowed)
			(vias allowed)
			(pads allowed)
			(copperpour not_allowed)
			(footprints allowed)
		)
		(placement
			(enabled no)
			(sheetname "")
		)
		(fill
			(thermal_gap 0.5)
			(thermal_bridge_width 0.5)
			(island_removal_mode 0)
		)
		(polygon
			(pts
				(arc
					(start 130.985006 -32.00019)
					(mid 130.499866 -31.51505)
					(end 130.014726 -32.00019)
				)
				(xy 130.014726 -32.45866) (xy 130.331972 -32.45866)
				(arc
					(start 130.336544 -32.45866)
					(mid 130.390144 -32.437124)
					(end 130.414014 -32.384492)
				)
				(arc
					(start 130.414014 -32.384492)
					(mid 130.499866 -31.606415)
					(end 130.585718 -32.384492)
				)
				(xy 130.585464 -32.389064) (xy 130.585464 -32.41675)
				(arc
					(start 130.58267 -32.419544)
					(mid 130.512682 -32.557328)
					(end 130.374898 -32.627316)
				)
				(xy 130.372104 -32.630364) (xy 130.344418 -32.630364) (xy 130.336544 -32.630364) (xy 130.331972 -32.630364)
				(xy 130.014726 -32.630364) (xy 130.014726 -32.770064) (xy 130.331972 -32.770064) (xy 130.336544 -32.76981)
				(xy 130.344418 -32.770064) (xy 130.372104 -32.770064)
				(arc
					(start 130.374898 -32.772858)
					(mid 130.512682 -32.842846)
					(end 130.58267 -32.98063)
				)
				(xy 130.585464 -32.983424) (xy 130.585464 -33.01111)
				(arc
					(start 130.585718 -33.015682)
					(mid 130.499866 -33.793759)
					(end 130.414014 -33.015682)
				)
				(arc
					(start 130.414014 -33.015682)
					(mid 130.390193 -32.962999)
					(end 130.336544 -32.941514)
				)
				(xy 130.331972 -32.94126) (xy 130.014726 -32.94126)
				(arc
					(start 130.014726 -33.39973)
					(mid 130.499739 -33.885124)
					(end 130.985006 -33.399984)
				)
			)
		)
	)
	(zone
		(layer "B.Cu")
		(hatch none 0.5)
		(connect_pads
			(clearance 0)
		)
		(min_thickness 0.25)
		(keepout
			(tracks allowed)
			(vias allowed)
			(pads allowed)
			(copperpour allowed)
			(footprints not_allowed)
		)
		(placement
			(enabled no)
			(sheetname "")
		)
		(fill
			(thermal_gap 0.5)
			(thermal_bridge_width 0.5)
			(island_removal_mode 0)
		)
		(polygon
			(pts
				(arc
					(start 75.25004 -120.000014)
					(mid 80.000094 -124.750068)
					(end 84.749894 -120.000014)
				)
				(arc
					(start 84.749894 -120.000014)
					(mid 80.000094 -115.250214)
					(end 75.25004 -120.000014)
				)
			)
		)
	)
	(zone
		(layer "B.Cu")
		(hatch none 0.5)
		(connect_pads
			(clearance 0)
		)
		(min_thickness 0.25)
		(keepout
			(tracks not_allowed)
			(vias allowed)
			(pads allowed)
			(copperpour not_allowed)
			(footprints allowed)
		)
		(placement
			(enabled no)
			(sheetname "")
		)
		(fill
			(thermal_gap 0.5)
			(thermal_bridge_width 0.5)
			(island_removal_mode 0)
		)
		(polygon
			(pts
				(arc
					(start 78.503018 -70.508622)
					(mid 78.122145 -70.127368)
					(end 77.741018 -70.508368)
				)
				(arc
					(start 77.741018 -71.397368)
					(mid 78.122018 -71.778368)
					(end 78.503018 -71.397368)
				)
				(xy 78.503018 -71.194168) (xy 78.44663 -71.194168)
				(arc
					(start 78.361286 -71.279512)
					(mid 77.933419 -71.585967)
					(end 78.239874 -71.1581)
				)
				(xy 78.37551 -71.022718) (xy 78.37551 -71.022464) (xy 78.503018 -71.022464) (xy 78.503018 -70.882764)
				(xy 78.375256 -70.882764)
				(arc
					(start 78.239874 -70.747636)
					(mid 77.933419 -70.319769)
					(end 78.361286 -70.626224)
				)
				(xy 78.446376 -70.711568) (xy 78.503018 -70.711568)
			)
		)
	)
	(zone
		(layer "B.Cu")
		(hatch none 0.5)
		(connect_pads
			(clearance 0)
		)
		(min_thickness 0.25)
		(keepout
			(tracks allowed)
			(vias allowed)
			(pads allowed)
			(copperpour allowed)
			(footprints not_allowed)
		)
		(placement
			(enabled no)
			(sheetname "")
		)
		(fill
			(thermal_gap 0.5)
			(thermal_bridge_width 0.5)
			(island_removal_mode 0)
		)
		(polygon
			(pts
				(arc
					(start 144.549876 -78.000098)
					(mid 149.29993 -82.750152)
					(end 154.049984 -78.000098)
				)
				(arc
					(start 154.049984 -78.000098)
					(mid 149.29993 -73.250044)
					(end 144.549876 -78.000098)
				)
			)
		)
	)
	(zone
		(layer "B.Cu")
		(hatch none 0.5)
		(connect_pads
			(clearance 0)
		)
		(min_thickness 0.25)
		(keepout
			(tracks allowed)
			(vias allowed)
			(pads allowed)
			(copperpour allowed)
			(footprints not_allowed)
		)
		(placement
			(enabled no)
			(sheetname "")
		)
		(fill
			(thermal_gap 0.5)
			(thermal_bridge_width 0.5)
			(island_removal_mode 0)
		)
		(polygon
			(pts
				(arc
					(start 209.14995 -21.249894)
					(mid 204.40015 -16.500094)
					(end 199.650096 -21.249894)
				)
				(arc
					(start 199.650096 -21.249894)
					(mid 204.40015 -25.999948)
					(end 209.14995 -21.249894)
				)
			)
		)
	)
	(zone
		(net "GND")
		(layer "B.Cu")
		(hatch none 0.5)
		(connect_pads
			(clearance 0.5)
		)
		(min_thickness 0.25)
		(fill yes
			(thermal_gap 0.5)
			(thermal_bridge_width 0.5)
			(island_removal_mode 0)
		)
		(polygon
			(pts
				(xy 165.746938 -5.869178) (xy 165.492938 -6.123178) (xy 165.492938 -8.663178) (xy 165.823138 -8.993378)
				(xy 170.318938 -8.993378) (xy 170.420538 -8.891778) (xy 170.420538 -6.046978) (xy 170.242738 -5.869178)
			)
		)
	)
	(zone
		(layer "B.Cu")
		(hatch none 0.5)
		(connect_pads
			(clearance 0)
		)
		(min_thickness 0.25)
		(keepout
			(tracks allowed)
			(vias allowed)
			(pads allowed)
			(copperpour allowed)
			(footprints not_allowed)
		)
		(placement
			(enabled no)
			(sheetname "")
		)
		(fill
			(thermal_gap 0.5)
			(thermal_bridge_width 0.5)
			(island_removal_mode 0)
		)
		(polygon
			(pts
				(arc
					(start 229.382066 -194.00012)
					(mid 229.709045 -193.945151)
					(end 230.000048 -193.786252)
				)
				(xy 230.000048 0)
				(arc
					(start 74.030078 0)
					(mid 73.322973 -0.292893)
					(end 73.03008 -0.999998)
				)
				(arc
					(start 73.03008 -109.050074)
					(mid 72.737187 -109.757179)
					(end 72.030082 -110.050072)
				)
				(arc
					(start 31.530036 -110.050072)
					(mid 30.822931 -109.757179)
					(end 30.530038 -109.050074)
				)
				(arc
					(start 30.530038 -0.999998)
					(mid 30.237145 -0.292893)
					(end 29.53004 0)
				)
				(xy 4.99999 0)
				(arc
					(start 4.99999 -193.786252)
					(mid 5.291008 -193.945107)
					(end 5.617972 -194.00012)
				)
				(arc
					(start 98.081846 -194.00012)
					(mid 98.607673 -193.850711)
					(end 98.976434 -193.447162)
				)
				(arc
					(start 103.594408 -184.211214)
					(mid 103.673264 -183.993717)
					(end 103.700072 -183.76392)
				)
				(arc
					(start 103.700072 -47.999904)
					(mid 104.200198 -47.499778)
					(end 104.70007 -47.999904)
				)
				(arc
					(start 143.299942 -47.999904)
					(mid 143.800068 -47.499778)
					(end 144.29994 -47.999904)
				)
				(arc
					(start 144.29994 -149.763988)
					(mid 144.326733 -149.993665)
					(end 144.405604 -150.211028)
				)
				(arc
					(start 149.023578 -159.44723)
					(mid 149.392254 -159.850576)
					(end 149.917912 -159.999934)
				)
				(arc
					(start 214.00008 -159.999934)
					(mid 214.707185 -160.292827)
					(end 215.000078 -160.999932)
				)
				(arc
					(start 215.000078 -193.000122)
					(mid 215.292971 -193.707227)
					(end 216.000076 -194.00012)
				)
			)
		)
	)
	(zone
		(layer "B.Cu")
		(hatch none 0.5)
		(connect_pads
			(clearance 0)
		)
		(min_thickness 0.25)
		(keepout
			(tracks allowed)
			(vias allowed)
			(pads allowed)
			(copperpour allowed)
			(footprints not_allowed)
		)
		(placement
			(enabled no)
			(sheetname "")
		)
		(fill
			(thermal_gap 0.5)
			(thermal_bridge_width 0.5)
			(island_removal_mode 0)
		)
		(polygon
			(pts
				(arc
					(start 121.160032 -34.85007)
					(mid 124.160026 -37.850064)
					(end 127.16002 -34.85007)
				)
				(arc
					(start 127.16002 -34.85007)
					(mid 124.160026 -31.850076)
					(end 121.160032 -34.85007)
				)
			)
		)
	)
	(zone
		(net "GND")
		(layer "B.Cu")
		(hatch none 0.5)
		(connect_pads
			(clearance 0.5)
		)
		(min_thickness 0.25)
		(fill yes
			(thermal_gap 0.5)
			(thermal_bridge_width 0.5)
			(island_removal_mode 0)
		)
		(polygon
			(pts
				(xy 33.654746 -152.247854) (xy 33.401 -152.5016) (xy 32.372046 -152.5016) (xy 32.3088 -152.564846)
				(xy 32.3088 -153.641806) (xy 33.124394 -154.4574) (xy 35.74288 -154.4574) (xy 36.57981 -153.62047)
				(xy 36.57981 -152.31237) (xy 36.515294 -152.247854)
			)
		)
		(polygon
			(pts
				(xy 33.3248 -153.2636) (xy 33.1216 -153.2636) (xy 33.1216 -153.4668) (xy 33.3248 -153.4668)
			)
		)
		(polygon
			(pts
				(xy 36.395406 -153.069798) (xy 36.192206 -153.069798) (xy 36.192206 -153.272998) (xy 36.395406 -153.272998)
			)
		)
		(polygon
			(pts
				(xy 35.531806 -153.069798) (xy 35.328606 -153.069798) (xy 35.328606 -153.272998) (xy 35.531806 -153.272998)
			)
		)
		(polygon
			(pts
				(xy 35.2298 -152.7556) (xy 35.0266 -152.7556) (xy 35.0266 -152.9588) (xy 35.2298 -152.9588)
			)
		)
		(polygon
			(pts
				(xy 34.6202 -152.7556) (xy 34.1376 -152.7556) (xy 34.1376 -152.9588) (xy 34.6202 -152.9588)
			)
		)
		(polygon
			(pts
				(xy 33.7312 -152.7556) (xy 33.528 -152.7556) (xy 33.528 -152.9588) (xy 33.7312 -152.9588)
			)
		)
	)
	(zone
		(layer "B.Cu")
		(hatch none 0.5)
		(connect_pads
			(clearance 0)
		)
		(min_thickness 0.25)
		(keepout
			(tracks not_allowed)
			(vias allowed)
			(pads allowed)
			(copperpour not_allowed)
			(footprints allowed)
		)
		(placement
			(enabled no)
			(sheetname "")
		)
		(fill
			(thermal_gap 0.5)
			(thermal_bridge_width 0.5)
			(island_removal_mode 0)
		)
		(polygon
			(pts
				(arc
					(start 116.584984 -32.00019)
					(mid 116.099844 -31.51505)
					(end 115.614704 -32.00019)
				)
				(xy 115.614704 -32.45866) (xy 115.93195 -32.45866)
				(arc
					(start 115.936522 -32.45866)
					(mid 115.990122 -32.437124)
					(end 116.013992 -32.384492)
				)
				(arc
					(start 116.013992 -32.384492)
					(mid 116.099844 -31.606415)
					(end 116.185696 -32.384492)
				)
				(xy 116.185696 -32.389064) (xy 116.185696 -32.41675)
				(arc
					(start 116.182648 -32.419544)
					(mid 116.11266 -32.557328)
					(end 115.974876 -32.627316)
				)
				(xy 115.972082 -32.630364) (xy 115.944396 -32.630364) (xy 115.936522 -32.630364) (xy 115.93195 -32.630364)
				(xy 115.614704 -32.630364) (xy 115.614704 -32.770064) (xy 115.93195 -32.770064) (xy 115.936522 -32.76981)
				(xy 115.944396 -32.770064) (xy 115.972082 -32.770064)
				(arc
					(start 115.974876 -32.772858)
					(mid 116.11266 -32.842846)
					(end 116.182648 -32.98063)
				)
				(xy 116.185696 -32.983424) (xy 116.185696 -33.01111)
				(arc
					(start 116.185696 -33.015682)
					(mid 116.099844 -33.793759)
					(end 116.013992 -33.015682)
				)
				(arc
					(start 116.013992 -33.015682)
					(mid 115.990171 -32.962999)
					(end 115.936522 -32.941514)
				)
				(xy 115.93195 -32.94126) (xy 115.614704 -32.94126)
				(arc
					(start 115.614704 -33.39973)
					(mid 116.099717 -33.885124)
					(end 116.584984 -33.399984)
				)
			)
		)
	)
	(zone
		(layer "B.Cu")
		(hatch none 0.5)
		(connect_pads
			(clearance 0)
		)
		(min_thickness 0.25)
		(keepout
			(tracks allowed)
			(vias allowed)
			(pads allowed)
			(copperpour allowed)
			(footprints not_allowed)
		)
		(placement
			(enabled no)
			(sheetname "")
		)
		(fill
			(thermal_gap 0.5)
			(thermal_bridge_width 0.5)
			(island_removal_mode 0)
		)
		(polygon
			(pts
				(arc
					(start 217.749882 -153.999946)
					(mid 222.499936 -158.75)
					(end 227.24999 -153.999946)
				)
				(arc
					(start 227.24999 -153.999946)
					(mid 222.499936 -149.249892)
					(end 217.749882 -153.999946)
				)
			)
		)
	)
	(zone
		(layer "B.Cu")
		(hatch none 0.5)
		(connect_pads
			(clearance 0)
		)
		(min_thickness 0.25)
		(keepout
			(tracks allowed)
			(vias allowed)
			(pads allowed)
			(copperpour allowed)
			(footprints not_allowed)
		)
		(placement
			(enabled no)
			(sheetname "")
		)
		(fill
			(thermal_gap 0.5)
			(thermal_bridge_width 0.5)
			(island_removal_mode 0)
		)
		(polygon
			(pts
				(arc
					(start 18.050002 -60.550044)
					(mid 22.800056 -65.300098)
					(end 27.55011 -60.550044)
				)
				(arc
					(start 27.55011 -60.550044)
					(mid 22.800056 -55.79999)
					(end 18.050002 -60.550044)
				)
			)
		)
	)
	(zone
		(net "GND")
		(layer "B.Cu")
		(hatch none 0.5)
		(connect_pads
			(clearance 0.5)
		)
		(min_thickness 0.25)
		(fill yes
			(thermal_gap 0.5)
			(thermal_bridge_width 0.5)
			(island_removal_mode 0)
		)
		(polygon
			(pts
				(arc
					(start 0.999998 -0.763016)
					(mid 0.832426 -0.832426)
					(end 0.763016 -0.999998)
				)
				(arc
					(start 0.763016 -183.76392)
					(mid 0.769411 -183.818347)
					(end 0.788162 -183.869838)
				)
				(arc
					(start 5.406136 -193.10604)
					(mid 5.493436 -193.201687)
					(end 5.617972 -193.237104)
				)
				(arc
					(start 98.0821 -193.237104)
					(mid 98.206591 -193.201614)
					(end 98.293936 -193.10604)
				)
				(arc
					(start 102.91191 -183.869838)
					(mid 102.930633 -183.818341)
					(end 102.937056 -183.76392)
				)
				(xy 102.937056 -183.403748) (xy 100.874322 -183.403748) (xy 96.97339 -191.20612) (xy 6.726682 -191.20612)
				(xy 2.82575 -183.403748) (xy 2.767584 -183.403748) (xy 2.7305 -183.366664) (xy 2.7305 -183.313832)
				(xy 2.767584 -183.276748) (xy 2.794 -183.276748) (xy 2.794 -2.794) (xy 27.736038 -2.794) (xy 27.736038 -108.8644)
				(xy 27.7368 -108.8644) (xy 27.743658 -108.871258) (xy 29.767022 -108.871258)
				(arc
					(start 29.767022 -0.999998)
					(mid 29.697612 -0.832426)
					(end 29.53004 -0.763016)
				)
			)
		)
	)
	(zone
		(net "P5V_STBY")
		(layer "B.Cu")
		(hatch none 0.5)
		(connect_pads
			(clearance 0.5)
		)
		(min_thickness 0.25)
		(fill yes
			(thermal_gap 0.5)
			(thermal_bridge_width 0.5)
			(island_removal_mode 0)
		)
		(polygon
			(pts
				(xy 81.915 -45.5676) (xy 81.8388 -45.6438) (xy 81.8388 -49.53) (xy 81.661 -49.7078) (xy 81.2546 -49.7078)
				(xy 81.1022 -49.8602) (xy 81.1022 -51.6382) (xy 81.28 -51.816) (xy 82.4992 -51.816) (xy 83.5152 -50.8)
				(xy 83.5152 -45.6438) (xy 83.439 -45.5676)
			)
		)
	)
	(zone
		(layers "B.Cu" "In2.Cu")
		(hatch none 0.5)
		(connect_pads
			(clearance 0)
		)
		(min_thickness 0.25)
		(keepout
			(tracks not_allowed)
			(vias allowed)
			(pads allowed)
			(copperpour not_allowed)
			(footprints allowed)
		)
		(placement
			(enabled no)
			(sheetname "")
		)
		(fill yes
			(thermal_gap 0.5)
			(thermal_bridge_width 0.5)
			(island_removal_mode 0)
		)
		(polygon
			(pts
				(arc
					(start 85.367622 -78.507336)
					(mid 84.986622 -78.126336)
					(end 84.605622 -78.507336)
				)
				(arc
					(start 84.605622 -79.396336)
					(mid 84.985352 -79.777334)
					(end 85.367622 -79.398876)
				)
				(arc
					(start 85.253322 -79.398876)
					(mid 84.986622 -79.663048)
					(end 84.719922 -79.398876)
				)
				(arc
					(start 84.719922 -79.396336)
					(mid 84.986622 -79.129636)
					(end 85.253322 -79.396336)
				)
				(xy 85.367622 -79.396336) (xy 85.367622 -78.509876)
				(arc
					(start 85.253322 -78.509876)
					(mid 84.986622 -78.774048)
					(end 84.719922 -78.509876)
				)
				(arc
					(start 84.719922 -78.507336)
					(mid 84.986622 -78.240636)
					(end 85.253322 -78.507336)
				)
			)
		)
	)
	(zone
		(layers "B.Cu" "In2.Cu")
		(hatch none 0.5)
		(connect_pads
			(clearance 0)
		)
		(min_thickness 0.25)
		(keepout
			(tracks not_allowed)
			(vias allowed)
			(pads allowed)
			(copperpour not_allowed)
			(footprints allowed)
		)
		(placement
			(enabled no)
			(sheetname "")
		)
		(fill yes
			(thermal_gap 0.5)
			(thermal_bridge_width 0.5)
			(island_removal_mode 0)
		)
		(polygon
			(pts
				(arc
					(start 83.739228 -75.305158)
					(mid 83.358228 -74.924158)
					(end 82.977228 -75.305158)
				)
				(arc
					(start 82.977228 -76.194158)
					(mid 83.356958 -76.575156)
					(end 83.739228 -76.196698)
				)
				(arc
					(start 83.624928 -76.196698)
					(mid 83.358228 -76.46087)
					(end 83.091528 -76.196698)
				)
				(arc
					(start 83.091528 -76.194158)
					(mid 83.358228 -75.927458)
					(end 83.624928 -76.194158)
				)
				(xy 83.739228 -76.194158) (xy 83.739228 -75.307698)
				(arc
					(start 83.624928 -75.307698)
					(mid 83.358228 -75.57187)
					(end 83.091528 -75.307698)
				)
				(arc
					(start 83.091528 -75.305158)
					(mid 83.358228 -75.038458)
					(end 83.624928 -75.305158)
				)
			)
		)
	)
	(zone
		(layers "B.Cu" "In2.Cu")
		(hatch none 0.5)
		(connect_pads
			(clearance 0)
		)
		(min_thickness 0.25)
		(keepout
			(tracks not_allowed)
			(vias allowed)
			(pads allowed)
			(copperpour not_allowed)
			(footprints allowed)
		)
		(placement
			(enabled no)
			(sheetname "")
		)
		(fill yes
			(thermal_gap 0.5)
			(thermal_bridge_width 0.5)
			(island_removal_mode 0)
		)
		(polygon
			(pts
				(arc
					(start 85.244178 -72.098916)
					(mid 84.863178 -71.717916)
					(end 84.482178 -72.098916)
				)
				(arc
					(start 84.482178 -72.987916)
					(mid 84.861908 -73.368914)
					(end 85.244178 -72.990456)
				)
				(arc
					(start 85.129878 -72.990456)
					(mid 84.863178 -73.254628)
					(end 84.596478 -72.990456)
				)
				(arc
					(start 84.596478 -72.987916)
					(mid 84.863178 -72.721216)
					(end 85.129878 -72.987916)
				)
				(xy 85.244178 -72.987916) (xy 85.244178 -72.101456)
				(arc
					(start 85.129878 -72.101456)
					(mid 84.863178 -72.365628)
					(end 84.596478 -72.101456)
				)
				(arc
					(start 84.596478 -72.098916)
					(mid 84.863178 -71.832216)
					(end 85.129878 -72.098916)
				)
			)
		)
	)
	(zone
		(layers "B.Cu" "In2.Cu")
		(hatch none 0.5)
		(connect_pads
			(clearance 0)
		)
		(min_thickness 0.25)
		(keepout
			(tracks not_allowed)
			(vias allowed)
			(pads allowed)
			(copperpour not_allowed)
			(footprints allowed)
		)
		(placement
			(enabled no)
			(sheetname "")
		)
		(fill yes
			(thermal_gap 0.5)
			(thermal_bridge_width 0.5)
			(island_removal_mode 0)
		)
		(polygon
			(pts
				(arc
					(start 83.740498 -88.091264)
					(mid 83.359498 -87.710264)
					(end 82.978498 -88.091264)
				)
				(arc
					(start 82.978498 -88.980264)
					(mid 83.358228 -89.361262)
					(end 83.740498 -88.982804)
				)
				(arc
					(start 83.626198 -88.982804)
					(mid 83.359498 -89.246976)
					(end 83.092798 -88.982804)
				)
				(arc
					(start 83.092798 -88.980264)
					(mid 83.359498 -88.713564)
					(end 83.626198 -88.980264)
				)
				(xy 83.740498 -88.980264) (xy 83.740498 -88.093804)
				(arc
					(start 83.626198 -88.093804)
					(mid 83.359498 -88.357976)
					(end 83.092798 -88.093804)
				)
				(arc
					(start 83.092798 -88.091264)
					(mid 83.359498 -87.824564)
					(end 83.626198 -88.091264)
				)
			)
		)
	)
	(zone
		(layers "B.Cu" "In2.Cu")
		(hatch none 0.5)
		(connect_pads
			(clearance 0)
		)
		(min_thickness 0.25)
		(keepout
			(tracks not_allowed)
			(vias allowed)
			(pads allowed)
			(copperpour not_allowed)
			(footprints allowed)
		)
		(placement
			(enabled no)
			(sheetname "")
		)
		(fill yes
			(thermal_gap 0.5)
			(thermal_bridge_width 0.5)
			(island_removal_mode 0)
		)
		(polygon
			(pts
				(arc
					(start 83.739228 -81.692496)
					(mid 83.358228 -81.311496)
					(end 82.977228 -81.692496)
				)
				(arc
					(start 82.977228 -82.581496)
					(mid 83.356958 -82.962494)
					(end 83.739228 -82.584036)
				)
				(arc
					(start 83.624928 -82.584036)
					(mid 83.358228 -82.848208)
					(end 83.091528 -82.584036)
				)
				(arc
					(start 83.091528 -82.581496)
					(mid 83.358228 -82.314796)
					(end 83.624928 -82.581496)
				)
				(xy 83.739228 -82.581496) (xy 83.739228 -81.695036)
				(arc
					(start 83.624928 -81.695036)
					(mid 83.358228 -81.959208)
					(end 83.091528 -81.695036)
				)
				(arc
					(start 83.091528 -81.692496)
					(mid 83.358228 -81.425796)
					(end 83.624928 -81.692496)
				)
			)
		)
	)
	(zone
		(layers "B.Cu" "In2.Cu")
		(hatch none 0.5)
		(connect_pads
			(clearance 0)
		)
		(min_thickness 0.25)
		(keepout
			(tracks not_allowed)
			(vias allowed)
			(pads allowed)
			(copperpour not_allowed)
			(footprints allowed)
		)
		(placement
			(enabled no)
			(sheetname "")
		)
		(fill yes
			(thermal_gap 0.5)
			(thermal_bridge_width 0.5)
			(island_removal_mode 0)
		)
		(polygon
			(pts
				(arc
					(start 83.739228 -94.492572)
					(mid 83.358228 -94.111572)
					(end 82.977228 -94.492572)
				)
				(arc
					(start 82.977228 -95.381572)
					(mid 83.356958 -95.76257)
					(end 83.739228 -95.384112)
				)
				(arc
					(start 83.624928 -95.384112)
					(mid 83.358228 -95.648284)
					(end 83.091528 -95.384112)
				)
				(arc
					(start 83.091528 -95.381572)
					(mid 83.358228 -95.114872)
					(end 83.624928 -95.381572)
				)
				(xy 83.739228 -95.381572) (xy 83.739228 -94.495112)
				(arc
					(start 83.624928 -94.495112)
					(mid 83.358228 -94.759284)
					(end 83.091528 -94.495112)
				)
				(arc
					(start 83.091528 -94.492572)
					(mid 83.358228 -94.225872)
					(end 83.624928 -94.492572)
				)
			)
		)
	)
	(zone
		(layers "B.Cu" "In2.Cu")
		(hatch none 0.5)
		(connect_pads
			(clearance 0)
		)
		(min_thickness 0.25)
		(keepout
			(tracks not_allowed)
			(vias allowed)
			(pads allowed)
			(copperpour not_allowed)
			(footprints allowed)
		)
		(placement
			(enabled no)
			(sheetname "")
		)
		(fill yes
			(thermal_gap 0.5)
			(thermal_bridge_width 0.5)
			(island_removal_mode 0)
		)
		(polygon
			(pts
				(arc
					(start 85.364828 -91.306396)
					(mid 84.983828 -90.925396)
					(end 84.602828 -91.306396)
				)
				(arc
					(start 84.602828 -92.195396)
					(mid 84.982558 -92.576394)
					(end 85.364828 -92.197936)
				)
				(arc
					(start 85.250528 -92.197936)
					(mid 84.983828 -92.462108)
					(end 84.717128 -92.197936)
				)
				(arc
					(start 84.717128 -92.195396)
					(mid 84.983828 -91.928696)
					(end 85.250528 -92.195396)
				)
				(xy 85.364828 -92.195396) (xy 85.364828 -91.308936)
				(arc
					(start 85.250528 -91.308936)
					(mid 84.983828 -91.573108)
					(end 84.717128 -91.308936)
				)
				(arc
					(start 84.717128 -91.306396)
					(mid 84.983828 -91.039696)
					(end 85.250528 -91.306396)
				)
			)
		)
	)
	(zone
		(layers "B.Cu" "In2.Cu")
		(hatch none 0.5)
		(connect_pads
			(clearance 0)
		)
		(min_thickness 0.25)
		(keepout
			(tracks not_allowed)
			(vias allowed)
			(pads allowed)
			(copperpour not_allowed)
			(footprints allowed)
		)
		(placement
			(enabled no)
			(sheetname "")
		)
		(fill yes
			(thermal_gap 0.5)
			(thermal_bridge_width 0.5)
			(island_removal_mode 0)
		)
		(polygon
			(pts
				(arc
					(start 128.467866 -25.830276)
					(mid 128.086866 -26.211276)
					(end 128.467866 -26.592276)
				)
				(arc
					(start 129.53492 -26.592276)
					(mid 129.803592 -26.48167)
					(end 129.916174 -26.213816)
				)
				(arc
					(start 129.801874 -26.213816)
					(mid 129.535174 -26.477988)
					(end 129.268474 -26.213816)
				)
				(arc
					(start 128.734566 -26.213816)
					(mid 128.467866 -26.477988)
					(end 128.201166 -26.213816)
				)
				(arc
					(start 128.201166 -26.211276)
					(mid 128.467866 -25.944576)
					(end 128.734566 -26.211276)
				)
				(arc
					(start 129.268474 -26.211276)
					(mid 129.535174 -25.944576)
					(end 129.801874 -26.211276)
				)
				(arc
					(start 129.916174 -26.211276)
					(mid 129.804582 -25.941868)
					(end 129.535174 -25.830276)
				)
			)
		)
	)
	(zone
		(layers "B.Cu" "In2.Cu")
		(hatch none 0.5)
		(connect_pads
			(clearance 0)
		)
		(min_thickness 0.25)
		(keepout
			(tracks not_allowed)
			(vias allowed)
			(pads allowed)
			(copperpour not_allowed)
			(footprints allowed)
		)
		(placement
			(enabled no)
			(sheetname "")
		)
		(fill yes
			(thermal_gap 0.5)
			(thermal_bridge_width 0.5)
			(island_removal_mode 0)
		)
		(polygon
			(pts
				(arc
					(start 85.364828 -84.892134)
					(mid 84.983828 -84.511134)
					(end 84.602828 -84.892134)
				)
				(arc
					(start 84.602828 -85.781134)
					(mid 84.982558 -86.162132)
					(end 85.364828 -85.783674)
				)
				(arc
					(start 85.250528 -85.783674)
					(mid 84.983828 -86.047846)
					(end 84.717128 -85.783674)
				)
				(arc
					(start 84.717128 -85.781134)
					(mid 84.983828 -85.514434)
					(end 85.250528 -85.781134)
				)
				(xy 85.364828 -85.781134) (xy 85.364828 -84.894674)
				(arc
					(start 85.250528 -84.894674)
					(mid 84.983828 -85.158846)
					(end 84.717128 -84.894674)
				)
				(arc
					(start 84.717128 -84.892134)
					(mid 84.983828 -84.625434)
					(end 85.250528 -84.892134)
				)
			)
		)
	)
	(zone
		(layers "B.Cu" "In2.Cu" "In5.Cu")
		(hatch none 0.5)
		(connect_pads
			(clearance 0)
		)
		(min_thickness 0.25)
		(keepout
			(tracks not_allowed)
			(vias allowed)
			(pads allowed)
			(copperpour not_allowed)
			(footprints allowed)
		)
		(placement
			(enabled no)
			(sheetname "")
		)
		(fill yes
			(thermal_gap 0.5)
			(thermal_bridge_width 0.5)
			(island_removal_mode 0)
		)
		(polygon
			(pts
				(arc
					(start 134.585202 -42.800016)
					(mid 134.100062 -42.314876)
					(end 133.614922 -42.800016)
				)
				(arc
					(start 133.614922 -44.19981)
					(mid 134.098665 -44.685202)
					(end 134.585202 -44.202604)
				)
				(arc
					(start 134.493762 -44.202604)
					(mid 134.100062 -44.593772)
					(end 133.706362 -44.202604)
				)
				(arc
					(start 133.706362 -44.200064)
					(mid 134.100062 -43.806364)
					(end 134.493762 -44.200064)
				)
				(xy 134.585202 -44.200064) (xy 134.585202 -42.802556)
				(arc
					(start 134.493762 -42.802556)
					(mid 134.100062 -43.193724)
					(end 133.706362 -42.802556)
				)
				(arc
					(start 133.706362 -42.800016)
					(mid 134.100062 -42.406316)
					(end 134.493762 -42.800016)
				)
			)
		)
	)
	(zone
		(layers "B.Cu" "In2.Cu" "In5.Cu" "Cmts.User")
		(hatch none 0.5)
		(connect_pads
			(clearance 0)
		)
		(min_thickness 0.25)
		(keepout
			(tracks allowed)
			(vias allowed)
			(pads allowed)
			(copperpour allowed)
			(footprints allowed)
		)
		(placement
			(enabled no)
			(sheetname "")
		)
		(fill yes
			(thermal_gap 0.5)
			(thermal_bridge_width 0.5)
			(island_removal_mode 0)
		)
		(polygon
			(pts
				(xy 24.63673 -150.308564) (xy 24.63673 -134.585964) (xy 15.08633 -134.585964) (xy 15.08633 -150.308564)
			)
		)
	)
	(zone
		(layers "B.Cu" "In5.Cu")
		(hatch none 0.5)
		(connect_pads
			(clearance 0)
		)
		(min_thickness 0.25)
		(keepout
			(tracks not_allowed)
			(vias allowed)
			(pads allowed)
			(copperpour not_allowed)
			(footprints allowed)
		)
		(placement
			(enabled no)
			(sheetname "")
		)
		(fill yes
			(thermal_gap 0.5)
			(thermal_bridge_width 0.5)
			(island_removal_mode 0)
		)
		(polygon
			(pts
				(xy 90.7034 -166.1414) (xy 90.7034 -163.449) (xy 94.5388 -163.449) (xy 94.5388 -166.1414)
			)
		)
	)
	(zone
		(layers "B.Cu" "In5.Cu")
		(hatch none 0.5)
		(connect_pads
			(clearance 0)
		)
		(min_thickness 0.25)
		(keepout
			(tracks not_allowed)
			(vias allowed)
			(pads allowed)
			(copperpour not_allowed)
			(footprints allowed)
		)
		(placement
			(enabled no)
			(sheetname "")
		)
		(fill yes
			(thermal_gap 0.5)
			(thermal_bridge_width 0.5)
			(island_removal_mode 0)
		)
		(polygon
			(pts
				(xy 67.9704 -157.607) (xy 67.9704 -154.9908) (xy 71.7804 -154.9908) (xy 71.7804 -157.607)
			)
		)
	)
	(zone
		(layer "In1.Cu")
		(hatch none 0.5)
		(connect_pads
			(clearance 0)
		)
		(min_thickness 0.25)
		(keepout
			(tracks not_allowed)
			(vias allowed)
			(pads allowed)
			(copperpour not_allowed)
			(footprints allowed)
		)
		(placement
			(enabled no)
			(sheetname "")
		)
		(fill
			(thermal_gap 0.5)
			(thermal_bridge_width 0.5)
			(island_removal_mode 0)
		)
		(polygon
			(pts
				(xy 175.49749 -134.100316) (xy 176.302416 -134.100316) (xy 176.302416 -135.649716) (xy 175.49749 -135.649716)
			)
		)
	)
	(zone
		(layer "In1.Cu")
		(hatch none 0.5)
		(connect_pads
			(clearance 0)
		)
		(min_thickness 0.25)
		(keepout
			(tracks not_allowed)
			(vias allowed)
			(pads allowed)
			(copperpour not_allowed)
			(footprints allowed)
		)
		(placement
			(enabled no)
			(sheetname "")
		)
		(fill
			(thermal_gap 0.5)
			(thermal_bridge_width 0.5)
			(island_removal_mode 0)
		)
		(polygon
			(pts
				(xy 176.997614 -134.100316) (xy 177.802286 -134.100316) (xy 177.802286 -135.649716) (xy 176.997614 -135.649716)
			)
		)
	)
	(zone
		(layer "In1.Cu")
		(hatch none 0.5)
		(connect_pads
			(clearance 0)
		)
		(min_thickness 0.25)
		(keepout
			(tracks not_allowed)
			(vias allowed)
			(pads allowed)
			(copperpour not_allowed)
			(footprints allowed)
		)
		(placement
			(enabled no)
			(sheetname "")
		)
		(fill
			(thermal_gap 0.5)
			(thermal_bridge_width 0.5)
			(island_removal_mode 0)
		)
		(polygon
			(pts
				(xy 198.99757 -134.100316) (xy 199.802242 -134.100316) (xy 199.802242 -135.649716) (xy 198.99757 -135.649716)
			)
		)
	)
	(zone
		(layer "In1.Cu")
		(hatch none 0.5)
		(connect_pads
			(clearance 0)
		)
		(min_thickness 0.25)
		(keepout
			(tracks not_allowed)
			(vias allowed)
			(pads allowed)
			(copperpour not_allowed)
			(footprints allowed)
		)
		(placement
			(enabled no)
			(sheetname "")
		)
		(fill
			(thermal_gap 0.5)
			(thermal_bridge_width 0.5)
			(island_removal_mode 0)
		)
		(polygon
			(pts
				(xy 172.497496 -134.100316) (xy 173.302422 -134.100316) (xy 173.302422 -135.649716) (xy 172.497496 -135.649716)
			)
		)
	)
	(zone
		(layer "In1.Cu")
		(hatch none 0.5)
		(connect_pads
			(clearance 0)
		)
		(min_thickness 0.25)
		(keepout
			(tracks not_allowed)
			(vias allowed)
			(pads allowed)
			(copperpour not_allowed)
			(footprints allowed)
		)
		(placement
			(enabled no)
			(sheetname "")
		)
		(fill
			(thermal_gap 0.5)
			(thermal_bridge_width 0.5)
			(island_removal_mode 0)
		)
		(polygon
			(pts
				(xy 182.997602 -134.100316) (xy 183.802528 -134.100316) (xy 183.802528 -135.649716) (xy 182.997602 -135.649716)
			)
		)
	)
	(zone
		(layer "In1.Cu")
		(hatch none 0.5)
		(connect_pads
			(clearance 0)
		)
		(min_thickness 0.25)
		(keepout
			(tracks not_allowed)
			(vias allowed)
			(pads allowed)
			(copperpour not_allowed)
			(footprints allowed)
		)
		(placement
			(enabled no)
			(sheetname "")
		)
		(fill
			(thermal_gap 0.5)
			(thermal_bridge_width 0.5)
			(island_removal_mode 0)
		)
		(polygon
			(pts
				(xy 206.497428 -134.100316) (xy 207.302354 -134.100316) (xy 207.302354 -135.649716) (xy 206.497428 -135.649716)
			)
		)
	)
	(zone
		(layer "In1.Cu")
		(hatch none 0.5)
		(connect_pads
			(clearance 0)
		)
		(min_thickness 0.25)
		(keepout
			(tracks not_allowed)
			(vias allowed)
			(pads allowed)
			(copperpour not_allowed)
			(footprints allowed)
		)
		(placement
			(enabled no)
			(sheetname "")
		)
		(fill
			(thermal_gap 0.5)
			(thermal_bridge_width 0.5)
			(island_removal_mode 0)
		)
		(polygon
			(pts
				(xy 207.997552 -134.100316) (xy 208.802224 -134.100316) (xy 208.802224 -135.649716) (xy 207.997552 -135.649716)
			)
		)
	)
	(zone
		(layer "In1.Cu")
		(hatch none 0.5)
		(connect_pads
			(clearance 0)
		)
		(min_thickness 0.25)
		(keepout
			(tracks not_allowed)
			(vias allowed)
			(pads allowed)
			(copperpour not_allowed)
			(footprints allowed)
		)
		(placement
			(enabled no)
			(sheetname "")
		)
		(fill
			(thermal_gap 0.5)
			(thermal_bridge_width 0.5)
			(island_removal_mode 0)
		)
		(polygon
			(pts
				(xy 197.497446 -134.100316) (xy 198.302372 -134.100316) (xy 198.302372 -135.649716) (xy 197.497446 -135.649716)
			)
		)
	)
	(zone
		(layer "In1.Cu")
		(hatch none 0.5)
		(connect_pads
			(clearance 0)
		)
		(min_thickness 0.25)
		(keepout
			(tracks not_allowed)
			(vias allowed)
			(pads allowed)
			(copperpour not_allowed)
			(footprints allowed)
		)
		(placement
			(enabled no)
			(sheetname "")
		)
		(fill
			(thermal_gap 0.5)
			(thermal_bridge_width 0.5)
			(island_removal_mode 0)
		)
		(polygon
			(pts
				(xy 195.997576 -134.100316) (xy 196.802248 -134.100316) (xy 196.802248 -135.649716) (xy 195.997576 -135.649716)
			)
		)
	)
	(zone
		(layer "In1.Cu")
		(hatch none 0.5)
		(connect_pads
			(clearance 0)
		)
		(min_thickness 0.25)
		(keepout
			(tracks not_allowed)
			(vias allowed)
			(pads allowed)
			(copperpour not_allowed)
			(footprints allowed)
		)
		(placement
			(enabled no)
			(sheetname "")
		)
		(fill
			(thermal_gap 0.5)
			(thermal_bridge_width 0.5)
			(island_removal_mode 0)
		)
		(polygon
			(pts
				(xy 203.497434 -134.100316) (xy 204.30236 -134.100316) (xy 204.30236 -135.649716) (xy 203.497434 -135.649716)
			)
		)
	)
	(zone
		(layer "In1.Cu")
		(hatch none 0.5)
		(connect_pads
			(clearance 0)
		)
		(min_thickness 0.25)
		(keepout
			(tracks not_allowed)
			(vias allowed)
			(pads allowed)
			(copperpour not_allowed)
			(footprints allowed)
		)
		(placement
			(enabled no)
			(sheetname "")
		)
		(fill
			(thermal_gap 0.5)
			(thermal_bridge_width 0.5)
			(island_removal_mode 0)
		)
		(polygon
			(pts
				(xy 201.997564 -134.100316) (xy 202.802236 -134.100316) (xy 202.802236 -135.649716) (xy 201.997564 -135.649716)
			)
		)
	)
	(zone
		(layer "In1.Cu")
		(hatch none 0.5)
		(connect_pads
			(clearance 0)
		)
		(min_thickness 0.25)
		(keepout
			(tracks not_allowed)
			(vias allowed)
			(pads allowed)
			(copperpour not_allowed)
			(footprints allowed)
		)
		(placement
			(enabled no)
			(sheetname "")
		)
		(fill
			(thermal_gap 0.5)
			(thermal_bridge_width 0.5)
			(island_removal_mode 0)
		)
		(polygon
			(pts
				(xy 178.497484 -134.100316) (xy 179.30241 -134.100316) (xy 179.30241 -135.649716) (xy 178.497484 -135.649716)
			)
		)
	)
	(zone
		(layer "In1.Cu")
		(hatch none 0.5)
		(connect_pads
			(clearance 0)
		)
		(min_thickness 0.25)
		(keepout
			(tracks not_allowed)
			(vias allowed)
			(pads allowed)
			(copperpour not_allowed)
			(footprints allowed)
		)
		(placement
			(enabled no)
			(sheetname "")
		)
		(fill
			(thermal_gap 0.5)
			(thermal_bridge_width 0.5)
			(island_removal_mode 0)
		)
		(polygon
			(pts
				(xy 173.99762 -134.100316) (xy 174.802292 -134.100316) (xy 174.802292 -135.649716) (xy 173.99762 -135.649716)
			)
		)
	)
	(zone
		(net "AGND_CURRENT_MON")
		(layer "In1.Cu")
		(hatch none 0.5)
		(connect_pads
			(clearance 0.5)
		)
		(min_thickness 0.25)
		(fill yes
			(thermal_gap 0.5)
			(thermal_bridge_width 0.5)
			(island_removal_mode 0)
		)
		(polygon
			(pts
				(xy 111.777272 -4.113022) (xy 109.22 -6.670294) (xy 109.22 -14.283944) (xy 109.438694 -14.502638)
				(xy 116.270532 -14.502638) (xy 116.690394 -14.9225) (xy 118.163086 -14.9225) (xy 118.617238 -15.376652)
				(xy 118.617238 -16.929862) (xy 118.86438 -17.177004) (xy 126.751842 -17.177004) (xy 127.93218 -15.996666)
				(xy 127.93218 -12.292076) (xy 126.695962 -11.055858) (xy 126.695962 -5.239004) (xy 125.56998 -4.113022)
			)
		)
	)
	(zone
		(layer "In1.Cu")
		(hatch none 0.5)
		(connect_pads
			(clearance 0)
		)
		(min_thickness 0.25)
		(keepout
			(tracks not_allowed)
			(vias allowed)
			(pads allowed)
			(copperpour not_allowed)
			(footprints allowed)
		)
		(placement
			(enabled no)
			(sheetname "")
		)
		(fill
			(thermal_gap 0.5)
			(thermal_bridge_width 0.5)
			(island_removal_mode 0)
		)
		(polygon
			(pts
				(xy 179.997608 -134.100316) (xy 180.80228 -134.100316) (xy 180.80228 -135.649716) (xy 179.997608 -135.649716)
			)
		)
	)
	(zone
		(net "GND")
		(layer "In1.Cu")
		(hatch none 0.5)
		(connect_pads
			(clearance 0.5)
		)
		(min_thickness 0.25)
		(fill yes
			(thermal_gap 0.5)
			(thermal_bridge_width 0.5)
			(island_removal_mode 0)
		)
		(polygon
			(pts
				(arc
					(start 0.999998 -0.763016)
					(mid 0.832426 -0.832426)
					(end 0.763016 -0.999998)
				)
				(arc
					(start 0.763016 -183.76392)
					(mid 0.769411 -183.818347)
					(end 0.788162 -183.869838)
				)
				(arc
					(start 5.406136 -193.10604)
					(mid 5.493436 -193.201687)
					(end 5.617972 -193.237104)
				)
				(arc
					(start 98.0821 -193.237104)
					(mid 98.206591 -193.201614)
					(end 98.293936 -193.10604)
				)
				(arc
					(start 102.91191 -183.869838)
					(mid 102.930633 -183.818341)
					(end 102.937056 -183.76392)
				)
				(arc
					(start 102.937056 -47.999904)
					(mid 103.797626 -46.802631)
					(end 105.206546 -47.236888)
				)
				(arc
					(start 142.793466 -47.236888)
					(mid 144.202311 -46.802855)
					(end 145.062956 -47.999904)
				)
				(arc
					(start 145.062956 -149.763734)
					(mid 145.069351 -149.818161)
					(end 145.088102 -149.869652)
				)
				(arc
					(start 149.706076 -159.105854)
					(mid 149.793376 -159.201501)
					(end 149.917912 -159.236918)
				)
				(arc
					(start 214.00008 -159.236918)
					(mid 215.246719 -159.753293)
					(end 215.763094 -160.999932)
				)
				(arc
					(start 215.763094 -193.000122)
					(mid 215.832504 -193.167694)
					(end 216.000076 -193.237104)
				)
				(arc
					(start 229.382066 -193.237104)
					(mid 229.506557 -193.201614)
					(end 229.593902 -193.10604)
				)
				(arc
					(start 234.211876 -183.869838)
					(mid 234.230599 -183.818341)
					(end 234.237022 -183.76392)
				)
				(arc
					(start 234.237022 -0.999998)
					(mid 234.167612 -0.832426)
					(end 234.00004 -0.763016)
				)
				(arc
					(start 74.030078 -0.763016)
					(mid 73.862506 -0.832426)
					(end 73.793096 -0.999998)
				)
				(arc
					(start 73.793096 -109.050074)
					(mid 73.276721 -110.296713)
					(end 72.030082 -110.813088)
				)
				(arc
					(start 31.530036 -110.813088)
					(mid 30.283397 -110.296713)
					(end 29.767022 -109.050074)
				)
				(arc
					(start 29.767022 -0.999998)
					(mid 29.697612 -0.832426)
					(end 29.53004 -0.763016)
				)
			)
		)
		(polygon
			(pts
				(arc
					(start 205.276958 -141.807692)
					(mid 205.815756 -141.807883)
					(end 205.815946 -141.268958)
				)
				(arc
					(start 205.187296 -140.640308)
					(mid 204.648308 -140.640308)
					(end 204.648308 -141.179296)
				)
			)
		)
		(polygon
			(pts
				(arc
					(start 200.577958 -141.807692)
					(mid 201.116756 -141.807883)
					(end 201.116946 -141.268958)
				)
				(arc
					(start 200.488296 -140.640308)
					(mid 199.949308 -140.640308)
					(end 199.949308 -141.179296)
				)
			)
		)
		(polygon
			(pts
				(arc
					(start 202.990958 -141.680692)
					(mid 203.529756 -141.680883)
					(end 203.529946 -141.141958)
				)
				(arc
					(start 202.901296 -140.513308)
					(mid 202.362308 -140.513308)
					(end 202.362308 -141.052296)
				)
			)
		)
		(polygon
			(pts
				(arc
					(start 198.164958 -141.553692)
					(mid 198.703756 -141.553883)
					(end 198.703946 -141.014958)
				)
				(arc
					(start 198.075296 -140.386308)
					(mid 197.536308 -140.386308)
					(end 197.536308 -140.925296)
				)
			)
		)
		(polygon
			(pts
				(arc
					(start 209.975958 -141.426692)
					(mid 210.514756 -141.426883)
					(end 210.514946 -140.887958)
				)
				(arc
					(start 209.886296 -140.259308)
					(mid 209.347308 -140.259308)
					(end 209.347308 -140.798296)
				)
			)
		)
		(polygon
			(pts
				(arc
					(start 195.497958 -141.299692)
					(mid 196.036756 -141.299883)
					(end 196.036946 -140.760958)
				)
				(arc
					(start 195.408296 -140.132308)
					(mid 194.869308 -140.132308)
					(end 194.869308 -140.671296)
				)
			)
		)
		(polygon
			(pts
				(arc
					(start 174.653448 -141.130782)
					(mid 175.192246 -141.130973)
					(end 175.192436 -140.592048)
				)
				(arc
					(start 174.563786 -139.963398)
					(mid 174.024798 -139.963398)
					(end 174.024798 -140.502386)
				)
			)
		)
		(polygon
			(pts
				(arc
					(start 180.364384 -141.066774)
					(mid 180.903182 -141.066965)
					(end 180.903372 -140.52804)
				)
				(arc
					(start 180.274722 -139.89939)
					(mid 179.735734 -139.89939)
					(end 179.735734 -140.438378)
				)
			)
		)
		(polygon
			(pts
				(arc
					(start 178.020218 -140.871702)
					(mid 178.559016 -140.871893)
					(end 178.559206 -140.332968)
				)
				(arc
					(start 177.930556 -139.704318)
					(mid 177.391568 -139.704318)
					(end 177.391568 -140.243306)
				)
			)
		)
		(polygon
			(pts
				(arc
					(start 185.444384 -140.584174)
					(mid 185.983182 -140.584365)
					(end 185.983372 -140.04544)
				)
				(arc
					(start 185.354722 -139.41679)
					(mid 184.815734 -139.41679)
					(end 184.815734 -139.955778)
				)
			)
		)
		(polygon
			(pts
				(arc
					(start 182.687722 -140.561314)
					(mid 183.22652 -140.561505)
					(end 183.22671 -140.02258)
				)
				(arc
					(start 182.59806 -139.39393)
					(mid 182.059072 -139.39393)
					(end 182.059072 -139.932918)
				)
			)
		)
		(polygon
			(pts
				(arc
					(start 206.800958 -140.156692)
					(mid 207.339756 -140.156883)
					(end 207.339946 -139.617958)
				)
				(arc
					(start 206.711296 -138.989308)
					(mid 206.172308 -138.989308)
					(end 206.172308 -139.528296)
				)
			)
		)
		(polygon
			(pts
				(arc
					(start 192.449958 -140.156692)
					(mid 192.988756 -140.156883)
					(end 192.988946 -139.617958)
				)
				(arc
					(start 192.360296 -138.989308)
					(mid 191.821308 -138.989308)
					(end 191.821308 -139.528296)
				)
			)
		)
		(polygon
			(pts
				(arc
					(start 213.692486 -139.77493)
					(mid 214.231284 -139.775121)
					(end 214.231474 -139.236196)
				)
				(arc
					(start 213.602824 -138.607546)
					(mid 213.063836 -138.607546)
					(end 213.063836 -139.146534)
				)
			)
		)
		(polygon
			(pts
				(arc
					(start 170.799252 -139.218924)
					(mid 171.33805 -139.219115)
					(end 171.33824 -138.68019)
				)
				(arc
					(start 170.70959 -138.05154)
					(mid 170.170602 -138.05154)
					(end 170.170602 -138.590528)
				)
			)
		)
		(polygon
			(pts
				(arc
					(start 174.302928 -138.822938)
					(mid 174.841726 -138.823129)
					(end 174.841916 -138.284204)
				)
				(arc
					(start 174.213266 -137.655554)
					(mid 173.674278 -137.655554)
					(end 173.674278 -138.194542)
				)
			)
		)
		(polygon
			(pts
				(arc
					(start 167.47109 -137.80389)
					(mid 168.009888 -137.804081)
					(end 168.010078 -137.265156)
				)
				(arc
					(start 167.381428 -136.636506)
					(mid 166.84244 -136.636506)
					(end 166.84244 -137.175494)
				)
			)
		)
		(polygon
			(pts
				(xy 208.802224 -134.100316) (xy 207.997552 -134.100316) (xy 207.997552 -135.649716) (xy 208.802224 -135.649716)
			)
		)
		(polygon
			(pts
				(xy 207.302354 -134.100316) (xy 206.497428 -134.100316) (xy 206.497428 -135.649716) (xy 207.302354 -135.649716)
			)
		)
		(polygon
			(pts
				(xy 205.80223 -134.100316) (xy 204.997558 -134.100316) (xy 204.997558 -135.649716) (xy 205.80223 -135.649716)
			)
		)
		(polygon
			(pts
				(xy 204.30236 -134.100316) (xy 203.497434 -134.100316) (xy 203.497434 -135.649716) (xy 204.30236 -135.649716)
			)
		)
		(polygon
			(pts
				(xy 202.802236 -134.100316) (xy 201.997564 -134.100316) (xy 201.997564 -135.649716) (xy 202.802236 -135.649716)
			)
		)
		(polygon
			(pts
				(xy 201.302366 -134.100316) (xy 200.49744 -134.100316) (xy 200.49744 -135.649716) (xy 201.302366 -135.649716)
			)
		)
		(polygon
			(pts
				(xy 199.802242 -134.100316) (xy 198.99757 -134.100316) (xy 198.99757 -135.649716) (xy 199.802242 -135.649716)
			)
		)
		(polygon
			(pts
				(xy 198.302372 -134.100316) (xy 197.497446 -134.100316) (xy 197.497446 -135.649716) (xy 198.302372 -135.649716)
			)
		)
		(polygon
			(pts
				(xy 196.802248 -134.100316) (xy 195.997576 -134.100316) (xy 195.997576 -135.649716) (xy 196.802248 -135.649716)
			)
		)
		(polygon
			(pts
				(xy 183.802528 -134.100316) (xy 182.997602 -134.100316) (xy 182.997602 -135.649716) (xy 183.802528 -135.649716)
			)
		)
		(polygon
			(pts
				(xy 182.302404 -134.100316) (xy 181.497478 -134.100316) (xy 181.497478 -135.649716) (xy 182.302404 -135.649716)
			)
		)
		(polygon
			(pts
				(xy 180.80228 -134.100316) (xy 179.997608 -134.100316) (xy 179.997608 -135.649716) (xy 180.80228 -135.649716)
			)
		)
		(polygon
			(pts
				(xy 179.30241 -134.100316) (xy 178.497484 -134.100316) (xy 178.497484 -135.649716) (xy 179.30241 -135.649716)
			)
		)
		(polygon
			(pts
				(xy 177.802286 -134.100316) (xy 176.997614 -134.100316) (xy 176.997614 -135.649716) (xy 177.802286 -135.649716)
			)
		)
		(polygon
			(pts
				(xy 176.302416 -134.100316) (xy 175.49749 -134.100316) (xy 175.49749 -135.649716) (xy 176.302416 -135.649716)
			)
		)
		(polygon
			(pts
				(xy 174.802292 -134.100316) (xy 173.99762 -134.100316) (xy 173.99762 -135.649716) (xy 174.802292 -135.649716)
			)
		)
		(polygon
			(pts
				(xy 173.302422 -134.100316) (xy 172.497496 -134.100316) (xy 172.497496 -135.649716) (xy 173.302422 -135.649716)
			)
		)
		(polygon
			(pts
				(xy 171.802298 -134.100316) (xy 170.997626 -134.100316) (xy 170.997626 -135.649716) (xy 171.802298 -135.649716)
			)
		)
		(polygon
			(pts
				(arc
					(start 183.905398 -133.354826)
					(mid 184.286144 -132.973699)
					(end 183.905144 -132.592826)
				)
				(arc
					(start 183.016144 -132.592826)
					(mid 182.635144 -132.973826)
					(end 183.016144 -133.354826)
				)
			)
		)
		(polygon
			(pts
				(xy 80.953864 -94.295976) (xy 78.896464 -94.295976) (xy 78.896464 -95.604076) (xy 80.953864 -95.604076)
			)
		)
		(polygon
			(pts
				(arc
					(start 82.977228 -95.381572)
					(mid 83.358228 -95.762572)
					(end 83.739228 -95.381572)
				)
				(arc
					(start 83.739228 -94.492318)
					(mid 83.358101 -94.111572)
					(end 82.977228 -94.492572)
				)
			)
		)
		(polygon
			(pts
				(xy 76.503784 -92.69603) (xy 74.446384 -92.69603) (xy 74.446384 -94.00413) (xy 76.503784 -94.00413)
			)
		)
		(polygon
			(pts
				(arc
					(start 76.902818 -93.800168)
					(mid 77.283818 -94.181168)
					(end 77.664818 -93.800168)
				)
				(arc
					(start 77.664818 -92.910914)
					(mid 77.283691 -92.530168)
					(end 76.902818 -92.911168)
				)
			)
		)
		(polygon
			(pts
				(xy 80.953864 -91.096084) (xy 78.896464 -91.096084) (xy 78.896464 -92.40393) (xy 80.953864 -92.40393)
			)
		)
		(polygon
			(pts
				(arc
					(start 84.602828 -92.195396)
					(mid 84.983828 -92.576396)
					(end 85.364828 -92.195396)
				)
				(arc
					(start 85.364828 -91.306142)
					(mid 84.983701 -90.925396)
					(end 84.602828 -91.306396)
				)
			)
		)
		(polygon
			(pts
				(xy 76.503784 -89.496138) (xy 74.446384 -89.496138) (xy 74.446384 -90.803984) (xy 76.503784 -90.803984)
			)
		)
		(polygon
			(pts
				(arc
					(start 77.741018 -90.599768)
					(mid 78.122018 -90.980768)
					(end 78.503018 -90.599768)
				)
				(arc
					(start 78.503018 -89.710514)
					(mid 78.121891 -89.329768)
					(end 77.741018 -89.710768)
				)
			)
		)
		(polygon
			(pts
				(xy 80.953864 -87.895938) (xy 78.896464 -87.895938) (xy 78.896464 -89.204038) (xy 80.953864 -89.204038)
			)
		)
		(polygon
			(pts
				(arc
					(start 82.978498 -88.980264)
					(mid 83.359498 -89.361264)
					(end 83.740498 -88.980264)
				)
				(arc
					(start 83.740498 -88.09101)
					(mid 83.359371 -87.710264)
					(end 82.978498 -88.091264)
				)
			)
		)
		(polygon
			(pts
				(xy 76.503784 -86.295992) (xy 74.446384 -86.295992) (xy 74.446384 -87.604092) (xy 76.503784 -87.604092)
			)
		)
		(polygon
			(pts
				(arc
					(start 76.902818 -87.399368)
					(mid 77.283818 -87.780368)
					(end 77.664818 -87.399368)
				)
				(arc
					(start 77.664818 -86.510114)
					(mid 77.283691 -86.129368)
					(end 76.902818 -86.510368)
				)
			)
		)
		(polygon
			(pts
				(xy 80.953864 -84.696046) (xy 78.896464 -84.696046) (xy 78.896464 -86.004146) (xy 80.953864 -86.004146)
			)
		)
		(polygon
			(pts
				(arc
					(start 84.602828 -85.781134)
					(mid 84.983828 -86.162134)
					(end 85.364828 -85.781134)
				)
				(arc
					(start 85.364828 -84.89188)
					(mid 84.983701 -84.511134)
					(end 84.602828 -84.892134)
				)
			)
		)
		(polygon
			(pts
				(xy 76.503784 -83.0961) (xy 74.446384 -83.0961) (xy 74.446384 -84.403946) (xy 76.503784 -84.403946)
			)
		)
		(polygon
			(pts
				(arc
					(start 77.741018 -84.198968)
					(mid 78.122018 -84.579968)
					(end 78.503018 -84.198968)
				)
				(arc
					(start 78.503018 -83.309714)
					(mid 78.121891 -82.928968)
					(end 77.741018 -83.309968)
				)
			)
		)
		(polygon
			(pts
				(xy 80.953864 -81.4959) (xy 78.896464 -81.4959) (xy 78.896464 -82.804) (xy 80.953864 -82.804)
			)
		)
		(polygon
			(pts
				(arc
					(start 82.977228 -82.581496)
					(mid 83.358228 -82.962496)
					(end 83.739228 -82.581496)
				)
				(arc
					(start 83.739228 -81.692242)
					(mid 83.358101 -81.311496)
					(end 82.977228 -81.692496)
				)
			)
		)
		(polygon
			(pts
				(xy 76.503784 -79.895954) (xy 74.446384 -79.895954) (xy 74.446384 -81.204054) (xy 76.503784 -81.204054)
			)
		)
		(polygon
			(pts
				(arc
					(start 76.902818 -80.998568)
					(mid 77.283818 -81.379568)
					(end 77.664818 -80.998568)
				)
				(arc
					(start 77.664818 -80.109314)
					(mid 77.283691 -79.728568)
					(end 76.902818 -80.109568)
				)
			)
		)
		(polygon
			(pts
				(xy 80.953864 -78.296008) (xy 78.896464 -78.296008) (xy 78.896464 -79.604108) (xy 80.953864 -79.604108)
			)
		)
		(polygon
			(pts
				(arc
					(start 84.605622 -79.396336)
					(mid 84.986622 -79.777336)
					(end 85.367622 -79.396336)
				)
				(arc
					(start 85.367622 -78.507082)
					(mid 84.986495 -78.126336)
					(end 84.605622 -78.507336)
				)
			)
		)
		(polygon
			(pts
				(xy 76.503784 -76.696062) (xy 74.446384 -76.696062) (xy 74.446384 -78.003908) (xy 76.503784 -78.003908)
			)
		)
		(polygon
			(pts
				(arc
					(start 77.741018 -77.798168)
					(mid 78.122018 -78.179168)
					(end 78.503018 -77.798168)
				)
				(arc
					(start 78.503018 -76.908914)
					(mid 78.121891 -76.528168)
					(end 77.741018 -76.909168)
				)
			)
		)
		(polygon
			(pts
				(xy 80.953864 -75.096116) (xy 78.896464 -75.096116) (xy 78.896464 -76.403962) (xy 80.953864 -76.403962)
			)
		)
		(polygon
			(pts
				(arc
					(start 82.977228 -76.194158)
					(mid 83.358228 -76.575158)
					(end 83.739228 -76.194158)
				)
				(arc
					(start 83.739228 -75.304904)
					(mid 83.358101 -74.924158)
					(end 82.977228 -75.305158)
				)
			)
		)
		(polygon
			(pts
				(xy 76.503784 -73.495916) (xy 74.446384 -73.495916) (xy 74.446384 -74.804016) (xy 76.503784 -74.804016)
			)
		)
		(polygon
			(pts
				(arc
					(start 76.902818 -74.597768)
					(mid 77.283818 -74.978768)
					(end 77.664818 -74.597768)
				)
				(arc
					(start 77.664818 -73.708514)
					(mid 77.283691 -73.327768)
					(end 76.902818 -73.708768)
				)
			)
		)
		(polygon
			(pts
				(xy 80.953864 -71.89597) (xy 78.896464 -71.89597) (xy 78.896464 -73.20407) (xy 80.953864 -73.20407)
			)
		)
		(polygon
			(pts
				(arc
					(start 84.482178 -72.987916)
					(mid 84.863178 -73.368916)
					(end 85.244178 -72.987916)
				)
				(arc
					(start 85.244178 -72.098662)
					(mid 84.863051 -71.717916)
					(end 84.482178 -72.098916)
				)
			)
		)
		(polygon
			(pts
				(xy 76.503784 -70.296024) (xy 74.446384 -70.296024) (xy 74.446384 -71.604124) (xy 76.503784 -71.604124)
			)
		)
		(polygon
			(pts
				(arc
					(start 77.741018 -71.397368)
					(mid 78.122018 -71.778368)
					(end 78.503018 -71.397368)
				)
				(arc
					(start 78.503018 -70.508114)
					(mid 78.121891 -70.127368)
					(end 77.741018 -70.508368)
				)
			)
		)
		(polygon
			(pts
				(xy 76.503784 -67.096132) (xy 74.446384 -67.096132) (xy 74.446384 -68.403978) (xy 76.503784 -68.403978)
			)
		)
		(polygon
			(pts
				(arc
					(start 76.974192 -68.201032)
					(mid 77.355192 -68.582032)
					(end 77.736192 -68.201032)
				)
				(arc
					(start 77.736192 -67.311778)
					(mid 77.355065 -66.931032)
					(end 76.974192 -67.312032)
				)
			)
		)
		(polygon
			(pts
				(arc
					(start 140.814806 -44.200318)
					(mid 141.300073 -44.685204)
					(end 141.785086 -44.200064)
				)
				(arc
					(start 141.785086 -42.800016)
					(mid 141.299946 -42.314876)
					(end 140.814806 -42.800016)
				)
			)
		)
		(polygon
			(pts
				(arc
					(start 133.614922 -44.200318)
					(mid 134.100189 -44.685204)
					(end 134.585202 -44.200064)
				)
				(arc
					(start 134.585202 -42.800016)
					(mid 134.100062 -42.314876)
					(end 133.614922 -42.800016)
				)
			)
		)
		(polygon
			(pts
				(arc
					(start 119.2149 -44.200318)
					(mid 119.700167 -44.685204)
					(end 120.18518 -44.200064)
				)
				(arc
					(start 120.18518 -42.800016)
					(mid 119.70004 -42.314876)
					(end 119.2149 -42.800016)
				)
			)
		)
		(polygon
			(pts
				(arc
					(start 139.014708 -38.20033)
					(mid 139.499975 -38.685216)
					(end 139.984988 -38.200076)
				)
				(arc
					(start 139.984988 -36.800028)
					(mid 139.499848 -36.314888)
					(end 139.014708 -36.800028)
				)
			)
		)
		(polygon
			(pts
				(arc
					(start 135.414766 -38.20033)
					(mid 135.900033 -38.685216)
					(end 136.385046 -38.200076)
				)
				(arc
					(start 136.385046 -36.800028)
					(mid 135.899906 -36.314888)
					(end 135.414766 -36.800028)
				)
			)
		)
		(polygon
			(pts
				(arc
					(start 131.814824 -38.20033)
					(mid 132.300091 -38.685216)
					(end 132.785104 -38.200076)
				)
				(arc
					(start 132.785104 -36.800028)
					(mid 132.299964 -36.314888)
					(end 131.814824 -36.800028)
				)
			)
		)
		(polygon
			(pts
				(arc
					(start 128.214882 -38.20033)
					(mid 128.700149 -38.685216)
					(end 129.185162 -38.200076)
				)
				(arc
					(start 129.185162 -36.800028)
					(mid 128.700022 -36.314888)
					(end 128.214882 -36.800028)
				)
			)
		)
		(polygon
			(pts
				(arc
					(start 117.414802 -38.20033)
					(mid 117.900069 -38.685216)
					(end 118.385082 -38.200076)
				)
				(arc
					(start 118.385082 -36.800028)
					(mid 117.899942 -36.314888)
					(end 117.414802 -36.800028)
				)
			)
		)
		(polygon
			(pts
				(arc
					(start 113.81486 -38.20033)
					(mid 114.300127 -38.685216)
					(end 114.78514 -38.200076)
				)
				(arc
					(start 114.78514 -36.800028)
					(mid 114.3 -36.314888)
					(end 113.81486 -36.800028)
				)
			)
		)
		(polygon
			(pts
				(arc
					(start 110.214918 -38.20033)
					(mid 110.700185 -38.685216)
					(end 111.185198 -38.200076)
				)
				(arc
					(start 111.185198 -36.800028)
					(mid 110.700058 -36.314888)
					(end 110.214918 -36.800028)
				)
			)
		)
		(polygon
			(pts
				(arc
					(start 106.614722 -38.20033)
					(mid 107.099989 -38.685216)
					(end 107.585002 -38.200076)
				)
				(arc
					(start 107.585002 -36.800028)
					(mid 107.099862 -36.314888)
					(end 106.614722 -36.800028)
				)
			)
		)
		(polygon
			(pts
				(arc
					(start 140.814806 -37.000434)
					(mid 141.300073 -37.48532)
					(end 141.785086 -37.00018)
				)
				(arc
					(start 141.785086 -35.600132)
					(mid 141.299946 -35.114992)
					(end 140.814806 -35.600132)
				)
			)
		)
		(polygon
			(pts
				(arc
					(start 137.214864 -37.000434)
					(mid 137.700131 -37.48532)
					(end 138.185144 -37.00018)
				)
				(arc
					(start 138.185144 -35.600132)
					(mid 137.700004 -35.114992)
					(end 137.214864 -35.600132)
				)
			)
		)
		(polygon
			(pts
				(arc
					(start 133.614922 -37.000434)
					(mid 134.100189 -37.48532)
					(end 134.585202 -37.00018)
				)
				(arc
					(start 134.585202 -35.600132)
					(mid 134.100062 -35.114992)
					(end 133.614922 -35.600132)
				)
			)
		)
		(polygon
			(pts
				(arc
					(start 130.014726 -37.000434)
					(mid 130.499993 -37.48532)
					(end 130.985006 -37.00018)
				)
				(arc
					(start 130.985006 -35.600132)
					(mid 130.499866 -35.114992)
					(end 130.014726 -35.600132)
				)
			)
		)
		(polygon
			(pts
				(arc
					(start 119.2149 -37.000434)
					(mid 119.700167 -37.48532)
					(end 120.18518 -37.00018)
				)
				(arc
					(start 120.18518 -35.600132)
					(mid 119.70004 -35.114992)
					(end 119.2149 -35.600132)
				)
			)
		)
		(polygon
			(pts
				(arc
					(start 115.614704 -37.000434)
					(mid 116.099971 -37.48532)
					(end 116.584984 -37.00018)
				)
				(arc
					(start 116.584984 -35.600132)
					(mid 116.099844 -35.114992)
					(end 115.614704 -35.600132)
				)
			)
		)
		(polygon
			(pts
				(arc
					(start 112.014762 -37.000434)
					(mid 112.500029 -37.48532)
					(end 112.985042 -37.00018)
				)
				(arc
					(start 112.985042 -35.600132)
					(mid 112.499902 -35.114992)
					(end 112.014762 -35.600132)
				)
			)
		)
		(polygon
			(pts
				(arc
					(start 108.41482 -37.000434)
					(mid 108.900087 -37.48532)
					(end 109.3851 -37.00018)
				)
				(arc
					(start 109.3851 -35.600132)
					(mid 108.89996 -35.114992)
					(end 108.41482 -35.600132)
				)
			)
		)
		(polygon
			(pts
				(arc
					(start 139.014708 -34.600134)
					(mid 139.499848 -35.085274)
					(end 139.984988 -34.600134)
				)
				(arc
					(start 139.984988 -33.199832)
					(mid 139.499721 -32.714946)
					(end 139.014708 -33.200086)
				)
			)
		)
		(polygon
			(pts
				(arc
					(start 135.414766 -34.600134)
					(mid 135.899906 -35.085274)
					(end 136.385046 -34.600134)
				)
				(arc
					(start 136.385046 -33.199832)
					(mid 135.899779 -32.714946)
					(end 135.414766 -33.200086)
				)
			)
		)
		(polygon
			(pts
				(arc
					(start 131.814824 -34.600134)
					(mid 132.299964 -35.085274)
					(end 132.785104 -34.600134)
				)
				(arc
					(start 132.785104 -33.199832)
					(mid 132.299837 -32.714946)
					(end 131.814824 -33.200086)
				)
			)
		)
		(polygon
			(pts
				(arc
					(start 128.214882 -34.600134)
					(mid 128.700022 -35.085274)
					(end 129.185162 -34.600134)
				)
				(arc
					(start 129.185162 -33.199832)
					(mid 128.699895 -32.714946)
					(end 128.214882 -33.200086)
				)
			)
		)
		(polygon
			(pts
				(arc
					(start 117.414802 -34.600134)
					(mid 117.899942 -35.085274)
					(end 118.385082 -34.600134)
				)
				(arc
					(start 118.385082 -33.199832)
					(mid 117.899815 -32.714946)
					(end 117.414802 -33.200086)
				)
			)
		)
		(polygon
			(pts
				(arc
					(start 113.81486 -34.600134)
					(mid 114.3 -35.085274)
					(end 114.78514 -34.600134)
				)
				(arc
					(start 114.78514 -33.199832)
					(mid 114.299873 -32.714946)
					(end 113.81486 -33.200086)
				)
			)
		)
		(polygon
			(pts
				(arc
					(start 110.214918 -34.600134)
					(mid 110.700058 -35.085274)
					(end 111.185198 -34.600134)
				)
				(arc
					(start 111.185198 -33.199832)
					(mid 110.699931 -32.714946)
					(end 110.214918 -33.200086)
				)
			)
		)
		(polygon
			(pts
				(arc
					(start 106.614722 -34.600134)
					(mid 107.099862 -35.085274)
					(end 107.585002 -34.600134)
				)
				(arc
					(start 107.585002 -33.199832)
					(mid 107.099735 -32.714946)
					(end 106.614722 -33.200086)
				)
			)
		)
		(polygon
			(pts
				(arc
					(start 140.814806 -33.400238)
					(mid 141.300073 -33.885124)
					(end 141.785086 -33.399984)
				)
				(arc
					(start 141.785086 -32.00019)
					(mid 141.299946 -31.51505)
					(end 140.814806 -32.00019)
				)
			)
		)
		(polygon
			(pts
				(arc
					(start 137.214864 -33.400238)
					(mid 137.700131 -33.885124)
					(end 138.185144 -33.399984)
				)
				(arc
					(start 138.185144 -32.00019)
					(mid 137.700004 -31.51505)
					(end 137.214864 -32.00019)
				)
			)
		)
		(polygon
			(pts
				(arc
					(start 133.614922 -33.400238)
					(mid 134.100189 -33.885124)
					(end 134.585202 -33.399984)
				)
				(arc
					(start 134.585202 -32.00019)
					(mid 134.100062 -31.51505)
					(end 133.614922 -32.00019)
				)
			)
		)
		(polygon
			(pts
				(arc
					(start 130.014726 -33.400238)
					(mid 130.499993 -33.885124)
					(end 130.985006 -33.399984)
				)
				(arc
					(start 130.985006 -32.00019)
					(mid 130.499866 -31.51505)
					(end 130.014726 -32.00019)
				)
			)
		)
		(polygon
			(pts
				(arc
					(start 119.2149 -33.400238)
					(mid 119.700167 -33.885124)
					(end 120.18518 -33.399984)
				)
				(arc
					(start 120.18518 -32.00019)
					(mid 119.70004 -31.51505)
					(end 119.2149 -32.00019)
				)
			)
		)
		(polygon
			(pts
				(arc
					(start 115.614704 -33.400238)
					(mid 116.099971 -33.885124)
					(end 116.584984 -33.399984)
				)
				(arc
					(start 116.584984 -32.00019)
					(mid 116.099844 -31.51505)
					(end 115.614704 -32.00019)
				)
			)
		)
		(polygon
			(pts
				(arc
					(start 112.014762 -33.400238)
					(mid 112.500029 -33.885124)
					(end 112.985042 -33.399984)
				)
				(arc
					(start 112.985042 -32.00019)
					(mid 112.499902 -31.51505)
					(end 112.014762 -32.00019)
				)
			)
		)
		(polygon
			(pts
				(arc
					(start 108.41482 -33.400238)
					(mid 108.900087 -33.885124)
					(end 109.3851 -33.399984)
				)
				(arc
					(start 109.3851 -32.00019)
					(mid 108.89996 -31.51505)
					(end 108.41482 -32.00019)
				)
			)
		)
		(polygon
			(pts
				(arc
					(start 129.535428 -26.592276)
					(mid 129.916174 -26.211149)
					(end 129.535174 -25.830276)
				)
				(arc
					(start 128.467866 -25.830276)
					(mid 128.086866 -26.211276)
					(end 128.467866 -26.592276)
				)
			)
		)
		(polygon
			(pts
				(xy 125.727968 -3.732022) (xy 111.619284 -3.732022) (xy 108.839 -6.512306) (xy 108.839 -14.441932)
				(xy 109.280706 -14.883638) (xy 116.112544 -14.883638) (xy 116.532406 -15.3035) (xy 118.005098 -15.3035)
				(xy 118.236238 -15.53464) (xy 118.236238 -17.08785) (xy 118.706392 -17.558004) (xy 126.90983 -17.558004)
				(xy 128.31318 -16.154654) (xy 128.31318 -12.134088) (xy 127.076962 -10.89787) (xy 127.076962 -5.081016)
			)
		)
	)
	(zone
		(layer "In1.Cu")
		(hatch none 0.5)
		(connect_pads
			(clearance 0)
		)
		(min_thickness 0.25)
		(keepout
			(tracks not_allowed)
			(vias allowed)
			(pads allowed)
			(copperpour not_allowed)
			(footprints allowed)
		)
		(placement
			(enabled no)
			(sheetname "")
		)
		(fill
			(thermal_gap 0.5)
			(thermal_bridge_width 0.5)
			(island_removal_mode 0)
		)
		(polygon
			(pts
				(xy 200.49744 -134.100316) (xy 201.302366 -134.100316) (xy 201.302366 -135.649716) (xy 200.49744 -135.649716)
			)
		)
	)
	(zone
		(layer "In1.Cu")
		(hatch none 0.5)
		(connect_pads
			(clearance 0)
		)
		(min_thickness 0.25)
		(keepout
			(tracks not_allowed)
			(vias allowed)
			(pads allowed)
			(copperpour not_allowed)
			(footprints allowed)
		)
		(placement
			(enabled no)
			(sheetname "")
		)
		(fill
			(thermal_gap 0.5)
			(thermal_bridge_width 0.5)
			(island_removal_mode 0)
		)
		(polygon
			(pts
				(xy 181.497478 -134.100316) (xy 182.302404 -134.100316) (xy 182.302404 -135.649716) (xy 181.497478 -135.649716)
			)
		)
	)
	(zone
		(layer "In1.Cu")
		(hatch none 0.5)
		(connect_pads
			(clearance 0)
		)
		(min_thickness 0.25)
		(keepout
			(tracks not_allowed)
			(vias allowed)
			(pads allowed)
			(copperpour not_allowed)
			(footprints allowed)
		)
		(placement
			(enabled no)
			(sheetname "")
		)
		(fill
			(thermal_gap 0.5)
			(thermal_bridge_width 0.5)
			(island_removal_mode 0)
		)
		(polygon
			(pts
				(xy 170.997626 -134.100316) (xy 171.802298 -134.100316) (xy 171.802298 -135.649716) (xy 170.997626 -135.649716)
			)
		)
	)
	(zone
		(layer "In1.Cu")
		(hatch none 0.5)
		(connect_pads
			(clearance 0)
		)
		(min_thickness 0.25)
		(keepout
			(tracks not_allowed)
			(vias allowed)
			(pads allowed)
			(copperpour not_allowed)
			(footprints allowed)
		)
		(placement
			(enabled no)
			(sheetname "")
		)
		(fill
			(thermal_gap 0.5)
			(thermal_bridge_width 0.5)
			(island_removal_mode 0)
		)
		(polygon
			(pts
				(xy 204.997558 -134.100316) (xy 205.80223 -134.100316) (xy 205.80223 -135.649716) (xy 204.997558 -135.649716)
			)
		)
	)
	(zone
		(layers "In1.Cu" "In2.Cu")
		(hatch none 0.5)
		(connect_pads
			(clearance 0)
		)
		(min_thickness 0.25)
		(keepout
			(tracks not_allowed)
			(vias allowed)
			(pads allowed)
			(copperpour not_allowed)
			(footprints allowed)
		)
		(placement
			(enabled no)
			(sheetname "")
		)
		(fill yes
			(thermal_gap 0.5)
			(thermal_bridge_width 0.5)
			(island_removal_mode 0)
		)
		(polygon
			(pts
				(xy 74.446384 -83.0961) (xy 76.503784 -83.0961) (xy 76.503784 -84.403946) (xy 74.446384 -84.403946)
			)
		)
	)
	(zone
		(layers "In1.Cu" "In2.Cu")
		(hatch none 0.5)
		(connect_pads
			(clearance 0)
		)
		(min_thickness 0.25)
		(keepout
			(tracks not_allowed)
			(vias allowed)
			(pads allowed)
			(copperpour not_allowed)
			(footprints allowed)
		)
		(placement
			(enabled no)
			(sheetname "")
		)
		(fill yes
			(thermal_gap 0.5)
			(thermal_bridge_width 0.5)
			(island_removal_mode 0)
		)
		(polygon
			(pts
				(xy 78.896464 -75.096116) (xy 80.953864 -75.096116) (xy 80.953864 -76.403962) (xy 78.896464 -76.403962)
			)
		)
	)
	(zone
		(layers "In1.Cu" "In2.Cu")
		(hatch none 0.5)
		(connect_pads
			(clearance 0)
		)
		(min_thickness 0.25)
		(keepout
			(tracks not_allowed)
			(vias allowed)
			(pads allowed)
			(copperpour not_allowed)
			(footprints allowed)
		)
		(placement
			(enabled no)
			(sheetname "")
		)
		(fill yes
			(thermal_gap 0.5)
			(thermal_bridge_width 0.5)
			(island_removal_mode 0)
		)
		(polygon
			(pts
				(xy 78.896464 -78.296008) (xy 80.953864 -78.296008) (xy 80.953864 -79.604108) (xy 78.896464 -79.604108)
			)
		)
	)
	(zone
		(layers "In1.Cu" "In2.Cu")
		(hatch none 0.5)
		(connect_pads
			(clearance 0)
		)
		(min_thickness 0.25)
		(keepout
			(tracks not_allowed)
			(vias allowed)
			(pads allowed)
			(copperpour not_allowed)
			(footprints allowed)
		)
		(placement
			(enabled no)
			(sheetname "")
		)
		(fill yes
			(thermal_gap 0.5)
			(thermal_bridge_width 0.5)
			(island_removal_mode 0)
		)
		(polygon
			(pts
				(xy 74.446384 -76.696062) (xy 76.503784 -76.696062) (xy 76.503784 -78.003908) (xy 74.446384 -78.003908)
			)
		)
	)
	(zone
		(layers "In1.Cu" "In2.Cu")
		(hatch none 0.5)
		(connect_pads
			(clearance 0)
		)
		(min_thickness 0.25)
		(keepout
			(tracks not_allowed)
			(vias allowed)
			(pads allowed)
			(copperpour not_allowed)
			(footprints allowed)
		)
		(placement
			(enabled no)
			(sheetname "")
		)
		(fill yes
			(thermal_gap 0.5)
			(thermal_bridge_width 0.5)
			(island_removal_mode 0)
		)
		(polygon
			(pts
				(xy 78.896464 -84.696046) (xy 80.953864 -84.696046) (xy 80.953864 -86.004146) (xy 78.896464 -86.004146)
			)
		)
	)
	(zone
		(layers "In1.Cu" "In2.Cu")
		(hatch none 0.5)
		(connect_pads
			(clearance 0)
		)
		(min_thickness 0.25)
		(keepout
			(tracks not_allowed)
			(vias allowed)
			(pads allowed)
			(copperpour not_allowed)
			(footprints allowed)
		)
		(placement
			(enabled no)
			(sheetname "")
		)
		(fill yes
			(thermal_gap 0.5)
			(thermal_bridge_width 0.5)
			(island_removal_mode 0)
		)
		(polygon
			(pts
				(xy 74.446384 -92.69603) (xy 76.503784 -92.69603) (xy 76.503784 -94.00413) (xy 74.446384 -94.00413)
			)
		)
	)
	(zone
		(layers "In1.Cu" "In2.Cu")
		(hatch none 0.5)
		(connect_pads
			(clearance 0)
		)
		(min_thickness 0.25)
		(keepout
			(tracks not_allowed)
			(vias allowed)
			(pads allowed)
			(copperpour not_allowed)
			(footprints allowed)
		)
		(placement
			(enabled no)
			(sheetname "")
		)
		(fill yes
			(thermal_gap 0.5)
			(thermal_bridge_width 0.5)
			(island_removal_mode 0)
		)
		(polygon
			(pts
				(xy 78.896464 -87.895938) (xy 80.953864 -87.895938) (xy 80.953864 -89.204038) (xy 78.896464 -89.204038)
			)
		)
	)
	(zone
		(layers "In1.Cu" "In2.Cu")
		(hatch none 0.5)
		(connect_pads
			(clearance 0)
		)
		(min_thickness 0.25)
		(keepout
			(tracks not_allowed)
			(vias allowed)
			(pads allowed)
			(copperpour not_allowed)
			(footprints allowed)
		)
		(placement
			(enabled no)
			(sheetname "")
		)
		(fill yes
			(thermal_gap 0.5)
			(thermal_bridge_width 0.5)
			(island_removal_mode 0)
		)
		(polygon
			(pts
				(xy 74.446384 -67.096132) (xy 76.503784 -67.096132) (xy 76.503784 -68.403978) (xy 74.446384 -68.403978)
			)
		)
	)
	(zone
		(layers "In1.Cu" "In2.Cu")
		(hatch none 0.5)
		(connect_pads
			(clearance 0)
		)
		(min_thickness 0.25)
		(keepout
			(tracks not_allowed)
			(vias allowed)
			(pads allowed)
			(copperpour not_allowed)
			(footprints allowed)
		)
		(placement
			(enabled no)
			(sheetname "")
		)
		(fill yes
			(thermal_gap 0.5)
			(thermal_bridge_width 0.5)
			(island_removal_mode 0)
		)
		(polygon
			(pts
				(xy 74.446384 -79.895954) (xy 76.503784 -79.895954) (xy 76.503784 -81.204054) (xy 74.446384 -81.204054)
			)
		)
	)
	(zone
		(layers "In1.Cu" "In2.Cu")
		(hatch none 0.5)
		(connect_pads
			(clearance 0)
		)
		(min_thickness 0.25)
		(keepout
			(tracks not_allowed)
			(vias allowed)
			(pads allowed)
			(copperpour not_allowed)
			(footprints allowed)
		)
		(placement
			(enabled no)
			(sheetname "")
		)
		(fill yes
			(thermal_gap 0.5)
			(thermal_bridge_width 0.5)
			(island_removal_mode 0)
		)
		(polygon
			(pts
				(xy 74.446384 -73.495916) (xy 76.503784 -73.495916) (xy 76.503784 -74.804016) (xy 74.446384 -74.804016)
			)
		)
	)
	(zone
		(layers "In1.Cu" "In2.Cu")
		(hatch none 0.5)
		(connect_pads
			(clearance 0)
		)
		(min_thickness 0.25)
		(keepout
			(tracks not_allowed)
			(vias allowed)
			(pads allowed)
			(copperpour not_allowed)
			(footprints allowed)
		)
		(placement
			(enabled no)
			(sheetname "")
		)
		(fill yes
			(thermal_gap 0.5)
			(thermal_bridge_width 0.5)
			(island_removal_mode 0)
		)
		(polygon
			(pts
				(xy 74.446384 -70.296024) (xy 76.503784 -70.296024) (xy 76.503784 -71.604124) (xy 74.446384 -71.604124)
			)
		)
	)
	(zone
		(layers "In1.Cu" "In2.Cu")
		(hatch none 0.5)
		(connect_pads
			(clearance 0)
		)
		(min_thickness 0.25)
		(keepout
			(tracks not_allowed)
			(vias allowed)
			(pads allowed)
			(copperpour not_allowed)
			(footprints allowed)
		)
		(placement
			(enabled no)
			(sheetname "")
		)
		(fill yes
			(thermal_gap 0.5)
			(thermal_bridge_width 0.5)
			(island_removal_mode 0)
		)
		(polygon
			(pts
				(xy 78.896464 -94.295976) (xy 80.953864 -94.295976) (xy 80.953864 -95.604076) (xy 78.896464 -95.604076)
			)
		)
	)
	(zone
		(layers "In1.Cu" "In2.Cu")
		(hatch none 0.5)
		(connect_pads
			(clearance 0)
		)
		(min_thickness 0.25)
		(keepout
			(tracks not_allowed)
			(vias allowed)
			(pads allowed)
			(copperpour not_allowed)
			(footprints allowed)
		)
		(placement
			(enabled no)
			(sheetname "")
		)
		(fill yes
			(thermal_gap 0.5)
			(thermal_bridge_width 0.5)
			(island_removal_mode 0)
		)
		(polygon
			(pts
				(xy 74.446384 -89.496138) (xy 76.503784 -89.496138) (xy 76.503784 -90.803984) (xy 74.446384 -90.803984)
			)
		)
	)
	(zone
		(layers "In1.Cu" "In2.Cu")
		(hatch none 0.5)
		(connect_pads
			(clearance 0)
		)
		(min_thickness 0.25)
		(keepout
			(tracks not_allowed)
			(vias allowed)
			(pads allowed)
			(copperpour not_allowed)
			(footprints allowed)
		)
		(placement
			(enabled no)
			(sheetname "")
		)
		(fill yes
			(thermal_gap 0.5)
			(thermal_bridge_width 0.5)
			(island_removal_mode 0)
		)
		(polygon
			(pts
				(xy 74.446384 -86.295992) (xy 76.503784 -86.295992) (xy 76.503784 -87.604092) (xy 74.446384 -87.604092)
			)
		)
	)
	(zone
		(layers "In1.Cu" "In2.Cu")
		(hatch none 0.5)
		(connect_pads
			(clearance 0)
		)
		(min_thickness 0.25)
		(keepout
			(tracks not_allowed)
			(vias allowed)
			(pads allowed)
			(copperpour not_allowed)
			(footprints allowed)
		)
		(placement
			(enabled no)
			(sheetname "")
		)
		(fill yes
			(thermal_gap 0.5)
			(thermal_bridge_width 0.5)
			(island_removal_mode 0)
		)
		(polygon
			(pts
				(xy 78.896464 -71.89597) (xy 80.953864 -71.89597) (xy 80.953864 -73.20407) (xy 78.896464 -73.20407)
			)
		)
	)
	(zone
		(layers "In1.Cu" "In2.Cu")
		(hatch none 0.5)
		(connect_pads
			(clearance 0)
		)
		(min_thickness 0.25)
		(keepout
			(tracks not_allowed)
			(vias allowed)
			(pads allowed)
			(copperpour not_allowed)
			(footprints allowed)
		)
		(placement
			(enabled no)
			(sheetname "")
		)
		(fill yes
			(thermal_gap 0.5)
			(thermal_bridge_width 0.5)
			(island_removal_mode 0)
		)
		(polygon
			(pts
				(xy 78.896464 -91.096084) (xy 80.953864 -91.096084) (xy 80.953864 -92.40393) (xy 78.896464 -92.40393)
			)
		)
	)
	(zone
		(layers "In1.Cu" "In2.Cu")
		(hatch none 0.5)
		(connect_pads
			(clearance 0)
		)
		(min_thickness 0.25)
		(keepout
			(tracks not_allowed)
			(vias allowed)
			(pads allowed)
			(copperpour not_allowed)
			(footprints allowed)
		)
		(placement
			(enabled no)
			(sheetname "")
		)
		(fill yes
			(thermal_gap 0.5)
			(thermal_bridge_width 0.5)
			(island_removal_mode 0)
		)
		(polygon
			(pts
				(xy 78.896464 -81.4959) (xy 80.953864 -81.4959) (xy 80.953864 -82.804) (xy 78.896464 -82.804)
			)
		)
	)
	(zone
		(layers "In1.Cu" "In2.Cu" "In3.Cu" "In4.Cu" "In5.Cu" "In6.Cu")
		(hatch none 0.5)
		(connect_pads
			(clearance 0)
		)
		(min_thickness 0.25)
		(keepout
			(tracks not_allowed)
			(vias allowed)
			(pads allowed)
			(copperpour not_allowed)
			(footprints allowed)
		)
		(placement
			(enabled no)
			(sheetname "")
		)
		(fill yes
			(thermal_gap 0.5)
			(thermal_bridge_width 0.5)
			(island_removal_mode 0)
		)
		(polygon
			(pts
				(arc
					(start 45.209206 -169.999914)
					(mid 37.690806 -169.999914)
					(end 45.209206 -169.999914)
				)
			)
		)
	)
	(zone
		(layers "In1.Cu" "In3.Cu" "In4.Cu" "In6.Cu")
		(hatch none 0.5)
		(connect_pads
			(clearance 0)
		)
		(min_thickness 0.25)
		(keepout
			(tracks not_allowed)
			(vias allowed)
			(pads allowed)
			(copperpour not_allowed)
			(footprints allowed)
		)
		(placement
			(enabled no)
			(sheetname "")
		)
		(fill yes
			(thermal_gap 0.5)
			(thermal_bridge_width 0.5)
			(island_removal_mode 0)
		)
		(polygon
			(pts
				(arc
					(start 78.503018 -76.909422)
					(mid 78.122145 -76.528168)
					(end 77.741018 -76.909168)
				)
				(arc
					(start 77.741018 -77.798168)
					(mid 78.122018 -78.179168)
					(end 78.503018 -77.798168)
				)
			)
		)
	)
	(zone
		(layers "In1.Cu" "In3.Cu" "In4.Cu" "In6.Cu")
		(hatch none 0.5)
		(connect_pads
			(clearance 0)
		)
		(min_thickness 0.25)
		(keepout
			(tracks not_allowed)
			(vias allowed)
			(pads allowed)
			(copperpour not_allowed)
			(footprints allowed)
		)
		(placement
			(enabled no)
			(sheetname "")
		)
		(fill yes
			(thermal_gap 0.5)
			(thermal_bridge_width 0.5)
			(island_removal_mode 0)
		)
		(polygon
			(pts
				(arc
					(start 132.785104 -36.800028)
					(mid 132.299964 -36.314888)
					(end 131.814824 -36.800028)
				)
				(arc
					(start 131.814824 -38.199822)
					(mid 132.299837 -38.685216)
					(end 132.785104 -38.200076)
				)
			)
		)
	)
	(zone
		(layers "In1.Cu" "In3.Cu" "In4.Cu" "In6.Cu")
		(hatch none 0.5)
		(connect_pads
			(clearance 0)
		)
		(min_thickness 0.25)
		(keepout
			(tracks not_allowed)
			(vias allowed)
			(pads allowed)
			(copperpour not_allowed)
			(footprints allowed)
		)
		(placement
			(enabled no)
			(sheetname "")
		)
		(fill yes
			(thermal_gap 0.5)
			(thermal_bridge_width 0.5)
			(island_removal_mode 0)
		)
		(polygon
			(pts
				(arc
					(start 118.385082 -36.800028)
					(mid 117.899942 -36.314888)
					(end 117.414802 -36.800028)
				)
				(arc
					(start 117.414802 -38.199822)
					(mid 117.899815 -38.685216)
					(end 118.385082 -38.200076)
				)
			)
		)
	)
	(zone
		(layers "In1.Cu" "In3.Cu" "In4.Cu" "In6.Cu")
		(hatch none 0.5)
		(connect_pads
			(clearance 0)
		)
		(min_thickness 0.25)
		(keepout
			(tracks not_allowed)
			(vias allowed)
			(pads allowed)
			(copperpour not_allowed)
			(footprints allowed)
		)
		(placement
			(enabled no)
			(sheetname "")
		)
		(fill yes
			(thermal_gap 0.5)
			(thermal_bridge_width 0.5)
			(island_removal_mode 0)
		)
		(polygon
			(pts
				(arc
					(start 227.24999 -153.999946)
					(mid 217.749882 -153.999946)
					(end 227.24999 -153.999946)
				)
			)
		)
	)
	(zone
		(layers "In1.Cu" "In3.Cu" "In4.Cu" "In6.Cu")
		(hatch none 0.5)
		(connect_pads
			(clearance 0)
		)
		(min_thickness 0.25)
		(keepout
			(tracks not_allowed)
			(vias allowed)
			(pads allowed)
			(copperpour not_allowed)
			(footprints allowed)
		)
		(placement
			(enabled no)
			(sheetname "")
		)
		(fill yes
			(thermal_gap 0.5)
			(thermal_bridge_width 0.5)
			(island_removal_mode 0)
		)
		(polygon
			(pts
				(arc
					(start 77.664818 -92.911422)
					(mid 77.283945 -92.530168)
					(end 76.902818 -92.911168)
				)
				(arc
					(start 76.902818 -93.800168)
					(mid 77.283818 -94.181168)
					(end 77.664818 -93.800168)
				)
			)
		)
	)
	(zone
		(layers "In1.Cu" "In3.Cu" "In4.Cu" "In6.Cu")
		(hatch none 0.5)
		(connect_pads
			(clearance 0)
		)
		(min_thickness 0.25)
		(keepout
			(tracks not_allowed)
			(vias allowed)
			(pads allowed)
			(copperpour not_allowed)
			(footprints allowed)
		)
		(placement
			(enabled no)
			(sheetname "")
		)
		(fill yes
			(thermal_gap 0.5)
			(thermal_bridge_width 0.5)
			(island_removal_mode 0)
		)
		(polygon
			(pts
				(arc
					(start 130.985006 -32.00019)
					(mid 130.499866 -31.51505)
					(end 130.014726 -32.00019)
				)
				(arc
					(start 130.014726 -33.39973)
					(mid 130.499739 -33.885124)
					(end 130.985006 -33.399984)
				)
			)
		)
	)
	(zone
		(layers "In1.Cu" "In3.Cu" "In4.Cu" "In6.Cu")
		(hatch none 0.5)
		(connect_pads
			(clearance 0)
		)
		(min_thickness 0.25)
		(keepout
			(tracks not_allowed)
			(vias allowed)
			(pads allowed)
			(copperpour not_allowed)
			(footprints allowed)
		)
		(placement
			(enabled no)
			(sheetname "")
		)
		(fill yes
			(thermal_gap 0.5)
			(thermal_bridge_width 0.5)
			(island_removal_mode 0)
		)
		(polygon
			(pts
				(arc
					(start 85.244178 -72.09917)
					(mid 84.863305 -71.717916)
					(end 84.482178 -72.098916)
				)
				(arc
					(start 84.482178 -72.987916)
					(mid 84.863178 -73.368916)
					(end 85.244178 -72.987916)
				)
			)
		)
	)
	(zone
		(layers "In1.Cu" "In3.Cu" "In4.Cu" "In6.Cu")
		(hatch none 0.5)
		(connect_pads
			(clearance 0)
		)
		(min_thickness 0.25)
		(keepout
			(tracks not_allowed)
			(vias allowed)
			(pads allowed)
			(copperpour not_allowed)
			(footprints allowed)
		)
		(placement
			(enabled no)
			(sheetname "")
		)
		(fill yes
			(thermal_gap 0.5)
			(thermal_bridge_width 0.5)
			(island_removal_mode 0)
		)
		(polygon
			(pts
				(arc
					(start 107.585002 -36.800028)
					(mid 107.099862 -36.314888)
					(end 106.614722 -36.800028)
				)
				(arc
					(start 106.614722 -38.199822)
					(mid 107.099735 -38.685216)
					(end 107.585002 -38.200076)
				)
			)
		)
	)
	(zone
		(layers "In1.Cu" "In3.Cu" "In4.Cu" "In6.Cu")
		(hatch none 0.5)
		(connect_pads
			(clearance 0)
		)
		(min_thickness 0.25)
		(keepout
			(tracks not_allowed)
			(vias allowed)
			(pads allowed)
			(copperpour not_allowed)
			(footprints allowed)
		)
		(placement
			(enabled no)
			(sheetname "")
		)
		(fill yes
			(thermal_gap 0.5)
			(thermal_bridge_width 0.5)
			(island_removal_mode 0)
		)
		(polygon
			(pts
				(arc
					(start 85.364828 -91.30665)
					(mid 84.983955 -90.925396)
					(end 84.602828 -91.306396)
				)
				(arc
					(start 84.602828 -92.195396)
					(mid 84.983828 -92.576396)
					(end 85.364828 -92.195396)
				)
			)
		)
	)
	(zone
		(layers "In1.Cu" "In3.Cu" "In4.Cu" "In6.Cu")
		(hatch none 0.5)
		(connect_pads
			(clearance 0)
		)
		(min_thickness 0.25)
		(keepout
			(tracks not_allowed)
			(vias allowed)
			(pads allowed)
			(copperpour not_allowed)
			(footprints allowed)
		)
		(placement
			(enabled no)
			(sheetname "")
		)
		(fill yes
			(thermal_gap 0.5)
			(thermal_bridge_width 0.5)
			(island_removal_mode 0)
		)
		(polygon
			(pts
				(arc
					(start 83.740498 -88.091518)
					(mid 83.359625 -87.710264)
					(end 82.978498 -88.091264)
				)
				(arc
					(start 82.978498 -88.980264)
					(mid 83.359498 -89.361264)
					(end 83.740498 -88.980264)
				)
			)
		)
	)
	(zone
		(layers "In1.Cu" "In3.Cu" "In4.Cu" "In6.Cu")
		(hatch none 0.5)
		(connect_pads
			(clearance 0)
		)
		(min_thickness 0.25)
		(keepout
			(tracks not_allowed)
			(vias allowed)
			(pads allowed)
			(copperpour not_allowed)
			(footprints allowed)
		)
		(placement
			(enabled no)
			(sheetname "")
		)
		(fill yes
			(thermal_gap 0.5)
			(thermal_bridge_width 0.5)
			(island_removal_mode 0)
		)
		(polygon
			(pts
				(arc
					(start 129.185162 -33.20034)
					(mid 128.700149 -32.714946)
					(end 128.214882 -33.200086)
				)
				(arc
					(start 128.214882 -34.600134)
					(mid 128.700022 -35.085274)
					(end 129.185162 -34.600134)
				)
			)
		)
	)
	(zone
		(layers "In1.Cu" "In3.Cu" "In4.Cu" "In6.Cu")
		(hatch none 0.5)
		(connect_pads
			(clearance 0)
		)
		(min_thickness 0.25)
		(keepout
			(tracks not_allowed)
			(vias allowed)
			(pads allowed)
			(copperpour not_allowed)
			(footprints allowed)
		)
		(placement
			(enabled no)
			(sheetname "")
		)
		(fill yes
			(thermal_gap 0.5)
			(thermal_bridge_width 0.5)
			(island_removal_mode 0)
		)
		(polygon
			(pts
				(arc
					(start 134.585202 -42.800016)
					(mid 134.100062 -42.314876)
					(end 133.614922 -42.800016)
				)
				(arc
					(start 133.614922 -44.19981)
					(mid 134.099935 -44.685204)
					(end 134.585202 -44.200064)
				)
			)
		)
	)
	(zone
		(layers "In1.Cu" "In3.Cu" "In4.Cu" "In6.Cu")
		(hatch none 0.5)
		(connect_pads
			(clearance 0)
		)
		(min_thickness 0.25)
		(keepout
			(tracks not_allowed)
			(vias allowed)
			(pads allowed)
			(copperpour not_allowed)
			(footprints allowed)
		)
		(placement
			(enabled no)
			(sheetname "")
		)
		(fill yes
			(thermal_gap 0.5)
			(thermal_bridge_width 0.5)
			(island_removal_mode 0)
		)
		(polygon
			(pts
				(arc
					(start 139.984988 -33.20034)
					(mid 139.499975 -32.714946)
					(end 139.014708 -33.200086)
				)
				(arc
					(start 139.014708 -34.600134)
					(mid 139.499848 -35.085274)
					(end 139.984988 -34.600134)
				)
			)
		)
	)
	(zone
		(layers "In1.Cu" "In3.Cu" "In4.Cu" "In6.Cu")
		(hatch none 0.5)
		(connect_pads
			(clearance 0)
		)
		(min_thickness 0.25)
		(keepout
			(tracks not_allowed)
			(vias allowed)
			(pads allowed)
			(copperpour not_allowed)
			(footprints allowed)
		)
		(placement
			(enabled no)
			(sheetname "")
		)
		(fill yes
			(thermal_gap 0.5)
			(thermal_bridge_width 0.5)
			(island_removal_mode 0)
		)
		(polygon
			(pts
				(arc
					(start 97.249996 -187.999878)
					(mid 87.749888 -187.999878)
					(end 97.249996 -187.999878)
				)
			)
		)
	)
	(zone
		(layers "In1.Cu" "In3.Cu" "In4.Cu" "In6.Cu")
		(hatch none 0.5)
		(connect_pads
			(clearance 0)
		)
		(min_thickness 0.25)
		(keepout
			(tracks not_allowed)
			(vias allowed)
			(pads allowed)
			(copperpour not_allowed)
			(footprints allowed)
		)
		(placement
			(enabled no)
			(sheetname "")
		)
		(fill yes
			(thermal_gap 0.5)
			(thermal_bridge_width 0.5)
			(island_removal_mode 0)
		)
		(polygon
			(pts
				(arc
					(start 85.367622 -78.50759)
					(mid 84.986749 -78.126336)
					(end 84.605622 -78.507336)
				)
				(arc
					(start 84.605622 -79.396336)
					(mid 84.986622 -79.777336)
					(end 85.367622 -79.396336)
				)
			)
		)
	)
	(zone
		(layers "In1.Cu" "In3.Cu" "In4.Cu" "In6.Cu")
		(hatch none 0.5)
		(connect_pads
			(clearance 0)
		)
		(min_thickness 0.25)
		(keepout
			(tracks not_allowed)
			(vias allowed)
			(pads allowed)
			(copperpour not_allowed)
			(footprints allowed)
		)
		(placement
			(enabled no)
			(sheetname "")
		)
		(fill yes
			(thermal_gap 0.5)
			(thermal_bridge_width 0.5)
			(island_removal_mode 0)
		)
		(polygon
			(pts
				(arc
					(start 141.785086 -32.00019)
					(mid 141.299946 -31.51505)
					(end 140.814806 -32.00019)
				)
				(arc
					(start 140.814806 -33.39973)
					(mid 141.299819 -33.885124)
					(end 141.785086 -33.399984)
				)
			)
		)
	)
	(zone
		(layers "In1.Cu" "In3.Cu" "In4.Cu" "In6.Cu")
		(hatch none 0.5)
		(connect_pads
			(clearance 0)
		)
		(min_thickness 0.25)
		(keepout
			(tracks not_allowed)
			(vias allowed)
			(pads allowed)
			(copperpour not_allowed)
			(footprints allowed)
		)
		(placement
			(enabled no)
			(sheetname "")
		)
		(fill yes
			(thermal_gap 0.5)
			(thermal_bridge_width 0.5)
			(island_removal_mode 0)
		)
		(polygon
			(pts
				(arc
					(start 83.739228 -81.69275)
					(mid 83.358355 -81.311496)
					(end 82.977228 -81.692496)
				)
				(arc
					(start 82.977228 -82.581496)
					(mid 83.358228 -82.962496)
					(end 83.739228 -82.581496)
				)
			)
		)
	)
	(zone
		(layers "In1.Cu" "In3.Cu" "In4.Cu" "In6.Cu")
		(hatch none 0.5)
		(connect_pads
			(clearance 0)
		)
		(min_thickness 0.25)
		(keepout
			(tracks not_allowed)
			(vias allowed)
			(pads allowed)
			(copperpour not_allowed)
			(footprints allowed)
		)
		(placement
			(enabled no)
			(sheetname "")
		)
		(fill yes
			(thermal_gap 0.5)
			(thermal_bridge_width 0.5)
			(island_removal_mode 0)
		)
		(polygon
			(pts
				(arc
					(start 111.185198 -33.20034)
					(mid 110.700185 -32.714946)
					(end 110.214918 -33.200086)
				)
				(arc
					(start 110.214918 -34.600134)
					(mid 110.700058 -35.085274)
					(end 111.185198 -34.600134)
				)
			)
		)
	)
	(zone
		(layers "In1.Cu" "In3.Cu" "In4.Cu" "In6.Cu")
		(hatch none 0.5)
		(connect_pads
			(clearance 0)
		)
		(min_thickness 0.25)
		(keepout
			(tracks not_allowed)
			(vias allowed)
			(pads allowed)
			(copperpour not_allowed)
			(footprints allowed)
		)
		(placement
			(enabled no)
			(sheetname "")
		)
		(fill yes
			(thermal_gap 0.5)
			(thermal_bridge_width 0.5)
			(island_removal_mode 0)
		)
		(polygon
			(pts
				(arc
					(start 132.785104 -33.20034)
					(mid 132.300091 -32.714946)
					(end 131.814824 -33.200086)
				)
				(arc
					(start 131.814824 -34.600134)
					(mid 132.299964 -35.085274)
					(end 132.785104 -34.600134)
				)
			)
		)
	)
	(zone
		(layers "In1.Cu" "In3.Cu" "In4.Cu" "In6.Cu")
		(hatch none 0.5)
		(connect_pads
			(clearance 0)
		)
		(min_thickness 0.25)
		(keepout
			(tracks not_allowed)
			(vias allowed)
			(pads allowed)
			(copperpour not_allowed)
			(footprints allowed)
		)
		(placement
			(enabled no)
			(sheetname "")
		)
		(fill yes
			(thermal_gap 0.5)
			(thermal_bridge_width 0.5)
			(island_removal_mode 0)
		)
		(polygon
			(pts
				(arc
					(start 154.750008 -120.000014)
					(mid 145.2499 -120.000014)
					(end 154.750008 -120.000014)
				)
			)
		)
	)
	(zone
		(layers "In1.Cu" "In3.Cu" "In4.Cu" "In6.Cu")
		(hatch none 0.5)
		(connect_pads
			(clearance 0)
		)
		(min_thickness 0.25)
		(keepout
			(tracks not_allowed)
			(vias allowed)
			(pads allowed)
			(copperpour not_allowed)
			(footprints allowed)
		)
		(placement
			(enabled no)
			(sheetname "")
		)
		(fill yes
			(thermal_gap 0.5)
			(thermal_bridge_width 0.5)
			(island_removal_mode 0)
		)
		(polygon
			(pts
				(arc
					(start 78.503018 -89.711022)
					(mid 78.122145 -89.329768)
					(end 77.741018 -89.710768)
				)
				(arc
					(start 77.741018 -90.599768)
					(mid 78.122018 -90.980768)
					(end 78.503018 -90.599768)
				)
			)
		)
	)
	(zone
		(layers "In1.Cu" "In3.Cu" "In4.Cu" "In6.Cu")
		(hatch none 0.5)
		(connect_pads
			(clearance 0)
		)
		(min_thickness 0.25)
		(keepout
			(tracks not_allowed)
			(vias allowed)
			(pads allowed)
			(copperpour not_allowed)
			(footprints allowed)
		)
		(placement
			(enabled no)
			(sheetname "")
		)
		(fill yes
			(thermal_gap 0.5)
			(thermal_bridge_width 0.5)
			(island_removal_mode 0)
		)
		(polygon
			(pts
				(arc
					(start 85.364828 -84.892388)
					(mid 84.983955 -84.511134)
					(end 84.602828 -84.892134)
				)
				(arc
					(start 84.602828 -85.781134)
					(mid 84.983828 -86.162134)
					(end 85.364828 -85.781134)
				)
			)
		)
	)
	(zone
		(layers "In1.Cu" "In3.Cu" "In4.Cu" "In6.Cu")
		(hatch none 0.5)
		(connect_pads
			(clearance 0)
		)
		(min_thickness 0.25)
		(keepout
			(tracks not_allowed)
			(vias allowed)
			(pads allowed)
			(copperpour not_allowed)
			(footprints allowed)
		)
		(placement
			(enabled no)
			(sheetname "")
		)
		(fill yes
			(thermal_gap 0.5)
			(thermal_bridge_width 0.5)
			(island_removal_mode 0)
		)
		(polygon
			(pts
				(arc
					(start 84.750148 -120.000014)
					(mid 75.25004 -120.000014)
					(end 84.750148 -120.000014)
				)
			)
		)
	)
	(zone
		(layers "In1.Cu" "In3.Cu" "In4.Cu" "In6.Cu")
		(hatch none 0.5)
		(connect_pads
			(clearance 0)
		)
		(min_thickness 0.25)
		(keepout
			(tracks not_allowed)
			(vias allowed)
			(pads allowed)
			(copperpour not_allowed)
			(footprints allowed)
		)
		(placement
			(enabled no)
			(sheetname "")
		)
		(fill yes
			(thermal_gap 0.5)
			(thermal_bridge_width 0.5)
			(island_removal_mode 0)
		)
		(polygon
			(pts
				(arc
					(start 77.664818 -73.709022)
					(mid 77.283945 -73.327768)
					(end 76.902818 -73.708768)
				)
				(arc
					(start 76.902818 -74.597768)
					(mid 77.283818 -74.978768)
					(end 77.664818 -74.597768)
				)
			)
		)
	)
	(zone
		(layers "In1.Cu" "In3.Cu" "In4.Cu" "In6.Cu")
		(hatch none 0.5)
		(connect_pads
			(clearance 0)
		)
		(min_thickness 0.25)
		(keepout
			(tracks not_allowed)
			(vias allowed)
			(pads allowed)
			(copperpour not_allowed)
			(footprints allowed)
		)
		(placement
			(enabled no)
			(sheetname "")
		)
		(fill yes
			(thermal_gap 0.5)
			(thermal_bridge_width 0.5)
			(island_removal_mode 0)
		)
		(polygon
			(pts
				(arc
					(start 227.24999 -187.999878)
					(mid 217.749882 -187.999878)
					(end 227.24999 -187.999878)
				)
			)
		)
	)
	(zone
		(layers "In1.Cu" "In3.Cu" "In4.Cu" "In6.Cu")
		(hatch none 0.5)
		(connect_pads
			(clearance 0)
		)
		(min_thickness 0.25)
		(keepout
			(tracks not_allowed)
			(vias allowed)
			(pads allowed)
			(copperpour not_allowed)
			(footprints allowed)
		)
		(placement
			(enabled no)
			(sheetname "")
		)
		(fill yes
			(thermal_gap 0.5)
			(thermal_bridge_width 0.5)
			(island_removal_mode 0)
		)
		(polygon
			(pts
				(arc
					(start 129.185162 -36.800028)
					(mid 128.700022 -36.314888)
					(end 128.214882 -36.800028)
				)
				(arc
					(start 128.214882 -38.199822)
					(mid 128.699895 -38.685216)
					(end 129.185162 -38.200076)
				)
			)
		)
	)
	(zone
		(layers "In1.Cu" "In3.Cu" "In4.Cu" "In6.Cu")
		(hatch none 0.5)
		(connect_pads
			(clearance 0)
		)
		(min_thickness 0.25)
		(keepout
			(tracks not_allowed)
			(vias allowed)
			(pads allowed)
			(copperpour not_allowed)
			(footprints allowed)
		)
		(placement
			(enabled no)
			(sheetname "")
		)
		(fill yes
			(thermal_gap 0.5)
			(thermal_bridge_width 0.5)
			(island_removal_mode 0)
		)
		(polygon
			(pts
				(arc
					(start 116.584984 -32.00019)
					(mid 116.099844 -31.51505)
					(end 115.614704 -32.00019)
				)
				(arc
					(start 115.614704 -33.39973)
					(mid 116.099717 -33.885124)
					(end 116.584984 -33.399984)
				)
			)
		)
	)
	(zone
		(layers "In1.Cu" "In3.Cu" "In4.Cu" "In6.Cu")
		(hatch none 0.5)
		(connect_pads
			(clearance 0)
		)
		(min_thickness 0.25)
		(keepout
			(tracks not_allowed)
			(vias allowed)
			(pads allowed)
			(copperpour not_allowed)
			(footprints allowed)
		)
		(placement
			(enabled no)
			(sheetname "")
		)
		(fill yes
			(thermal_gap 0.5)
			(thermal_bridge_width 0.5)
			(island_removal_mode 0)
		)
		(polygon
			(pts
				(arc
					(start 77.664818 -80.109822)
					(mid 77.283945 -79.728568)
					(end 76.902818 -80.109568)
				)
				(arc
					(start 76.902818 -80.998568)
					(mid 77.283818 -81.379568)
					(end 77.664818 -80.998568)
				)
			)
		)
	)
	(zone
		(layers "In1.Cu" "In3.Cu" "In4.Cu" "In6.Cu")
		(hatch none 0.5)
		(connect_pads
			(clearance 0)
		)
		(min_thickness 0.25)
		(keepout
			(tracks not_allowed)
			(vias allowed)
			(pads allowed)
			(copperpour not_allowed)
			(footprints allowed)
		)
		(placement
			(enabled no)
			(sheetname "")
		)
		(fill yes
			(thermal_gap 0.5)
			(thermal_bridge_width 0.5)
			(island_removal_mode 0)
		)
		(polygon
			(pts
				(arc
					(start 120.18518 -35.600132)
					(mid 119.70004 -35.114992)
					(end 119.2149 -35.600132)
				)
				(arc
					(start 119.2149 -36.999926)
					(mid 119.699913 -37.48532)
					(end 120.18518 -37.00018)
				)
			)
		)
	)
	(zone
		(layers "In1.Cu" "In3.Cu" "In4.Cu" "In6.Cu")
		(hatch none 0.5)
		(connect_pads
			(clearance 0)
		)
		(min_thickness 0.25)
		(keepout
			(tracks not_allowed)
			(vias allowed)
			(pads allowed)
			(copperpour not_allowed)
			(footprints allowed)
		)
		(placement
			(enabled no)
			(sheetname "")
		)
		(fill yes
			(thermal_gap 0.5)
			(thermal_bridge_width 0.5)
			(island_removal_mode 0)
		)
		(polygon
			(pts
				(arc
					(start 22.750018 -120.000014)
					(mid 13.24991 -120.000014)
					(end 22.750018 -120.000014)
				)
			)
		)
	)
	(zone
		(layers "In1.Cu" "In3.Cu" "In4.Cu" "In6.Cu")
		(hatch none 0.5)
		(connect_pads
			(clearance 0)
		)
		(min_thickness 0.25)
		(keepout
			(tracks not_allowed)
			(vias allowed)
			(pads allowed)
			(copperpour not_allowed)
			(footprints allowed)
		)
		(placement
			(enabled no)
			(sheetname "")
		)
		(fill yes
			(thermal_gap 0.5)
			(thermal_bridge_width 0.5)
			(island_removal_mode 0)
		)
		(polygon
			(pts
				(arc
					(start 107.750102 -9.99998)
					(mid 98.249994 -9.99998)
					(end 107.750102 -9.99998)
				)
			)
		)
	)
	(zone
		(layers "In1.Cu" "In3.Cu" "In4.Cu" "In6.Cu")
		(hatch none 0.5)
		(connect_pads
			(clearance 0)
		)
		(min_thickness 0.25)
		(keepout
			(tracks not_allowed)
			(vias allowed)
			(pads allowed)
			(copperpour not_allowed)
			(footprints allowed)
		)
		(placement
			(enabled no)
			(sheetname "")
		)
		(fill yes
			(thermal_gap 0.5)
			(thermal_bridge_width 0.5)
			(island_removal_mode 0)
		)
		(polygon
			(pts
				(arc
					(start 141.785086 -35.600132)
					(mid 141.299946 -35.114992)
					(end 140.814806 -35.600132)
				)
				(arc
					(start 140.814806 -36.999926)
					(mid 141.299819 -37.48532)
					(end 141.785086 -37.00018)
				)
			)
		)
	)
	(zone
		(layers "In1.Cu" "In3.Cu" "In4.Cu" "In6.Cu")
		(hatch none 0.5)
		(connect_pads
			(clearance 0)
		)
		(min_thickness 0.25)
		(keepout
			(tracks not_allowed)
			(vias allowed)
			(pads allowed)
			(copperpour not_allowed)
			(footprints allowed)
		)
		(placement
			(enabled no)
			(sheetname "")
		)
		(fill yes
			(thermal_gap 0.5)
			(thermal_bridge_width 0.5)
			(island_removal_mode 0)
		)
		(polygon
			(pts
				(arc
					(start 120.18518 -42.800016)
					(mid 119.70004 -42.314876)
					(end 119.2149 -42.800016)
				)
				(arc
					(start 119.2149 -44.19981)
					(mid 119.699913 -44.685204)
					(end 120.18518 -44.200064)
				)
			)
		)
	)
	(zone
		(layers "In1.Cu" "In3.Cu" "In4.Cu" "In6.Cu")
		(hatch none 0.5)
		(connect_pads
			(clearance 0)
		)
		(min_thickness 0.25)
		(keepout
			(tracks not_allowed)
			(vias allowed)
			(pads allowed)
			(copperpour not_allowed)
			(footprints allowed)
		)
		(placement
			(enabled no)
			(sheetname "")
		)
		(fill yes
			(thermal_gap 0.5)
			(thermal_bridge_width 0.5)
			(island_removal_mode 0)
		)
		(polygon
			(pts
				(arc
					(start 109.3851 -35.600132)
					(mid 108.89996 -35.114992)
					(end 108.41482 -35.600132)
				)
				(arc
					(start 108.41482 -36.999926)
					(mid 108.899833 -37.48532)
					(end 109.3851 -37.00018)
				)
			)
		)
	)
	(zone
		(layers "In1.Cu" "In3.Cu" "In4.Cu" "In6.Cu")
		(hatch none 0.5)
		(connect_pads
			(clearance 0)
		)
		(min_thickness 0.25)
		(keepout
			(tracks not_allowed)
			(vias allowed)
			(pads allowed)
			(copperpour not_allowed)
			(footprints allowed)
		)
		(placement
			(enabled no)
			(sheetname "")
		)
		(fill yes
			(thermal_gap 0.5)
			(thermal_bridge_width 0.5)
			(island_removal_mode 0)
		)
		(polygon
			(pts
				(arc
					(start 118.385082 -33.20034)
					(mid 117.900069 -32.714946)
					(end 117.414802 -33.200086)
				)
				(arc
					(start 117.414802 -34.600134)
					(mid 117.899942 -35.085274)
					(end 118.385082 -34.600134)
				)
			)
		)
	)
	(zone
		(layers "In1.Cu" "In3.Cu" "In4.Cu" "In6.Cu")
		(hatch none 0.5)
		(connect_pads
			(clearance 0)
		)
		(min_thickness 0.25)
		(keepout
			(tracks not_allowed)
			(vias allowed)
			(pads allowed)
			(copperpour not_allowed)
			(footprints allowed)
		)
		(placement
			(enabled no)
			(sheetname "")
		)
		(fill yes
			(thermal_gap 0.5)
			(thermal_bridge_width 0.5)
			(island_removal_mode 0)
		)
		(polygon
			(pts
				(arc
					(start 22.750018 -24.99995)
					(mid 13.24991 -24.99995)
					(end 22.750018 -24.99995)
				)
			)
		)
	)
	(zone
		(layers "In1.Cu" "In3.Cu" "In4.Cu" "In6.Cu")
		(hatch none 0.5)
		(connect_pads
			(clearance 0)
		)
		(min_thickness 0.25)
		(keepout
			(tracks not_allowed)
			(vias allowed)
			(pads allowed)
			(copperpour not_allowed)
			(footprints allowed)
		)
		(placement
			(enabled no)
			(sheetname "")
		)
		(fill yes
			(thermal_gap 0.5)
			(thermal_bridge_width 0.5)
			(island_removal_mode 0)
		)
		(polygon
			(pts
				(arc
					(start 111.185198 -36.800028)
					(mid 110.700058 -36.314888)
					(end 110.214918 -36.800028)
				)
				(arc
					(start 110.214918 -38.199822)
					(mid 110.699931 -38.685216)
					(end 111.185198 -38.200076)
				)
			)
		)
	)
	(zone
		(layers "In1.Cu" "In3.Cu" "In4.Cu" "In6.Cu")
		(hatch none 0.5)
		(connect_pads
			(clearance 0)
		)
		(min_thickness 0.25)
		(keepout
			(tracks not_allowed)
			(vias allowed)
			(pads allowed)
			(copperpour not_allowed)
			(footprints allowed)
		)
		(placement
			(enabled no)
			(sheetname "")
		)
		(fill yes
			(thermal_gap 0.5)
			(thermal_bridge_width 0.5)
			(island_removal_mode 0)
		)
		(polygon
			(pts
				(arc
					(start 130.985006 -35.600132)
					(mid 130.499866 -35.114992)
					(end 130.014726 -35.600132)
				)
				(arc
					(start 130.014726 -36.999926)
					(mid 130.499739 -37.48532)
					(end 130.985006 -37.00018)
				)
			)
		)
	)
	(zone
		(layers "In1.Cu" "In3.Cu" "In4.Cu" "In6.Cu")
		(hatch none 0.5)
		(connect_pads
			(clearance 0)
		)
		(min_thickness 0.25)
		(keepout
			(tracks not_allowed)
			(vias allowed)
			(pads allowed)
			(copperpour not_allowed)
			(footprints allowed)
		)
		(placement
			(enabled no)
			(sheetname "")
		)
		(fill yes
			(thermal_gap 0.5)
			(thermal_bridge_width 0.5)
			(island_removal_mode 0)
		)
		(polygon
			(pts
				(arc
					(start 139.984988 -36.800028)
					(mid 139.499848 -36.314888)
					(end 139.014708 -36.800028)
				)
				(arc
					(start 139.014708 -38.199822)
					(mid 139.499721 -38.685216)
					(end 139.984988 -38.200076)
				)
			)
		)
	)
	(zone
		(layers "In1.Cu" "In3.Cu" "In4.Cu" "In6.Cu")
		(hatch none 0.5)
		(connect_pads
			(clearance 0)
		)
		(min_thickness 0.25)
		(keepout
			(tracks not_allowed)
			(vias allowed)
			(pads allowed)
			(copperpour not_allowed)
			(footprints allowed)
		)
		(placement
			(enabled no)
			(sheetname "")
		)
		(fill yes
			(thermal_gap 0.5)
			(thermal_bridge_width 0.5)
			(island_removal_mode 0)
		)
		(polygon
			(pts
				(arc
					(start 78.503018 -83.310222)
					(mid 78.122145 -82.928968)
					(end 77.741018 -83.309968)
				)
				(arc
					(start 77.741018 -84.198968)
					(mid 78.122018 -84.579968)
					(end 78.503018 -84.198968)
				)
			)
		)
	)
	(zone
		(layers "In1.Cu" "In3.Cu" "In4.Cu" "In6.Cu")
		(hatch none 0.5)
		(connect_pads
			(clearance 0)
		)
		(min_thickness 0.25)
		(keepout
			(tracks not_allowed)
			(vias allowed)
			(pads allowed)
			(copperpour not_allowed)
			(footprints allowed)
		)
		(placement
			(enabled no)
			(sheetname "")
		)
		(fill yes
			(thermal_gap 0.5)
			(thermal_bridge_width 0.5)
			(island_removal_mode 0)
		)
		(polygon
			(pts
				(arc
					(start 129.53492 -26.592276)
					(mid 129.916174 -26.211403)
					(end 129.535174 -25.830276)
				)
				(arc
					(start 128.467866 -25.830276)
					(mid 128.086866 -26.211276)
					(end 128.467866 -26.592276)
				)
			)
		)
	)
	(zone
		(layers "In1.Cu" "In3.Cu" "In4.Cu" "In6.Cu")
		(hatch none 0.5)
		(connect_pads
			(clearance 0)
		)
		(min_thickness 0.25)
		(keepout
			(tracks not_allowed)
			(vias allowed)
			(pads allowed)
			(copperpour not_allowed)
			(footprints allowed)
		)
		(placement
			(enabled no)
			(sheetname "")
		)
		(fill yes
			(thermal_gap 0.5)
			(thermal_bridge_width 0.5)
			(island_removal_mode 0)
		)
		(polygon
			(pts
				(arc
					(start 83.739228 -75.305412)
					(mid 83.358355 -74.924158)
					(end 82.977228 -75.305158)
				)
				(arc
					(start 82.977228 -76.194158)
					(mid 83.358228 -76.575158)
					(end 83.739228 -76.194158)
				)
			)
		)
	)
	(zone
		(layers "In1.Cu" "In3.Cu" "In4.Cu" "In6.Cu")
		(hatch none 0.5)
		(connect_pads
			(clearance 0)
		)
		(min_thickness 0.25)
		(keepout
			(tracks not_allowed)
			(vias allowed)
			(pads allowed)
			(copperpour not_allowed)
			(footprints allowed)
		)
		(placement
			(enabled no)
			(sheetname "")
		)
		(fill yes
			(thermal_gap 0.5)
			(thermal_bridge_width 0.5)
			(island_removal_mode 0)
		)
		(polygon
			(pts
				(arc
					(start 141.785086 -42.800016)
					(mid 141.299946 -42.314876)
					(end 140.814806 -42.800016)
				)
				(arc
					(start 140.814806 -44.19981)
					(mid 141.299819 -44.685204)
					(end 141.785086 -44.200064)
				)
			)
		)
	)
	(zone
		(layers "In1.Cu" "In3.Cu" "In4.Cu" "In6.Cu")
		(hatch none 0.5)
		(connect_pads
			(clearance 0)
		)
		(min_thickness 0.25)
		(keepout
			(tracks not_allowed)
			(vias allowed)
			(pads allowed)
			(copperpour not_allowed)
			(footprints allowed)
		)
		(placement
			(enabled no)
			(sheetname "")
		)
		(fill yes
			(thermal_gap 0.5)
			(thermal_bridge_width 0.5)
			(island_removal_mode 0)
		)
		(polygon
			(pts
				(arc
					(start 116.584984 -35.600132)
					(mid 116.099844 -35.114992)
					(end 115.614704 -35.600132)
				)
				(arc
					(start 115.614704 -36.999926)
					(mid 116.099717 -37.48532)
					(end 116.584984 -37.00018)
				)
			)
		)
	)
	(zone
		(layers "In1.Cu" "In3.Cu" "In4.Cu" "In6.Cu")
		(hatch none 0.5)
		(connect_pads
			(clearance 0)
		)
		(min_thickness 0.25)
		(keepout
			(tracks not_allowed)
			(vias allowed)
			(pads allowed)
			(copperpour not_allowed)
			(footprints allowed)
		)
		(placement
			(enabled no)
			(sheetname "")
		)
		(fill yes
			(thermal_gap 0.5)
			(thermal_bridge_width 0.5)
			(island_removal_mode 0)
		)
		(polygon
			(pts
				(arc
					(start 136.385046 -36.800028)
					(mid 135.899906 -36.314888)
					(end 135.414766 -36.800028)
				)
				(arc
					(start 135.414766 -38.199822)
					(mid 135.899779 -38.685216)
					(end 136.385046 -38.200076)
				)
			)
		)
	)
	(zone
		(layers "In1.Cu" "In3.Cu" "In4.Cu" "In6.Cu")
		(hatch none 0.5)
		(connect_pads
			(clearance 0)
		)
		(min_thickness 0.25)
		(keepout
			(tracks not_allowed)
			(vias allowed)
			(pads allowed)
			(copperpour not_allowed)
			(footprints allowed)
		)
		(placement
			(enabled no)
			(sheetname "")
		)
		(fill yes
			(thermal_gap 0.5)
			(thermal_bridge_width 0.5)
			(island_removal_mode 0)
		)
		(polygon
			(pts
				(arc
					(start 134.585202 -35.600132)
					(mid 134.100062 -35.114992)
					(end 133.614922 -35.600132)
				)
				(arc
					(start 133.614922 -36.999926)
					(mid 134.099935 -37.48532)
					(end 134.585202 -37.00018)
				)
			)
		)
	)
	(zone
		(layers "In1.Cu" "In3.Cu" "In4.Cu" "In6.Cu")
		(hatch none 0.5)
		(connect_pads
			(clearance 0)
		)
		(min_thickness 0.25)
		(keepout
			(tracks not_allowed)
			(vias allowed)
			(pads allowed)
			(copperpour not_allowed)
			(footprints allowed)
		)
		(placement
			(enabled no)
			(sheetname "")
		)
		(fill yes
			(thermal_gap 0.5)
			(thermal_bridge_width 0.5)
			(island_removal_mode 0)
		)
		(polygon
			(pts
				(arc
					(start 17.249902 -187.999878)
					(mid 7.749794 -187.999878)
					(end 17.249902 -187.999878)
				)
			)
		)
	)
	(zone
		(layers "In1.Cu" "In3.Cu" "In4.Cu" "In6.Cu")
		(hatch none 0.5)
		(connect_pads
			(clearance 0)
		)
		(min_thickness 0.25)
		(keepout
			(tracks not_allowed)
			(vias allowed)
			(pads allowed)
			(copperpour not_allowed)
			(footprints allowed)
		)
		(placement
			(enabled no)
			(sheetname "")
		)
		(fill yes
			(thermal_gap 0.5)
			(thermal_bridge_width 0.5)
			(island_removal_mode 0)
		)
		(polygon
			(pts
				(arc
					(start 107.585002 -33.20034)
					(mid 107.099989 -32.714946)
					(end 106.614722 -33.200086)
				)
				(arc
					(start 106.614722 -34.600134)
					(mid 107.099862 -35.085274)
					(end 107.585002 -34.600134)
				)
			)
		)
	)
	(zone
		(layers "In1.Cu" "In3.Cu" "In4.Cu" "In6.Cu")
		(hatch none 0.5)
		(connect_pads
			(clearance 0)
		)
		(min_thickness 0.25)
		(keepout
			(tracks not_allowed)
			(vias allowed)
			(pads allowed)
			(copperpour not_allowed)
			(footprints allowed)
		)
		(placement
			(enabled no)
			(sheetname "")
		)
		(fill yes
			(thermal_gap 0.5)
			(thermal_bridge_width 0.5)
			(island_removal_mode 0)
		)
		(polygon
			(pts
				(arc
					(start 134.585202 -32.00019)
					(mid 134.100062 -31.51505)
					(end 133.614922 -32.00019)
				)
				(arc
					(start 133.614922 -33.39973)
					(mid 134.099935 -33.885124)
					(end 134.585202 -33.399984)
				)
			)
		)
	)
	(zone
		(layers "In1.Cu" "In3.Cu" "In4.Cu" "In6.Cu")
		(hatch none 0.5)
		(connect_pads
			(clearance 0)
		)
		(min_thickness 0.25)
		(keepout
			(tracks not_allowed)
			(vias allowed)
			(pads allowed)
			(copperpour not_allowed)
			(footprints allowed)
		)
		(placement
			(enabled no)
			(sheetname "")
		)
		(fill yes
			(thermal_gap 0.5)
			(thermal_bridge_width 0.5)
			(island_removal_mode 0)
		)
		(polygon
			(pts
				(arc
					(start 120.18518 -32.00019)
					(mid 119.70004 -31.51505)
					(end 119.2149 -32.00019)
				)
				(arc
					(start 119.2149 -33.39973)
					(mid 119.699913 -33.885124)
					(end 120.18518 -33.399984)
				)
			)
		)
	)
	(zone
		(layers "In1.Cu" "In3.Cu" "In4.Cu" "In6.Cu")
		(hatch none 0.5)
		(connect_pads
			(clearance 0)
		)
		(min_thickness 0.25)
		(keepout
			(tracks not_allowed)
			(vias allowed)
			(pads allowed)
			(copperpour not_allowed)
			(footprints allowed)
		)
		(placement
			(enabled no)
			(sheetname "")
		)
		(fill yes
			(thermal_gap 0.5)
			(thermal_bridge_width 0.5)
			(island_removal_mode 0)
		)
		(polygon
			(pts
				(arc
					(start 78.503018 -70.508622)
					(mid 78.122145 -70.127368)
					(end 77.741018 -70.508368)
				)
				(arc
					(start 77.741018 -71.397368)
					(mid 78.122018 -71.778368)
					(end 78.503018 -71.397368)
				)
			)
		)
	)
	(zone
		(layers "In1.Cu" "In3.Cu" "In4.Cu" "In6.Cu")
		(hatch none 0.5)
		(connect_pads
			(clearance 0)
		)
		(min_thickness 0.25)
		(keepout
			(tracks not_allowed)
			(vias allowed)
			(pads allowed)
			(copperpour not_allowed)
			(footprints allowed)
		)
		(placement
			(enabled no)
			(sheetname "")
		)
		(fill yes
			(thermal_gap 0.5)
			(thermal_bridge_width 0.5)
			(island_removal_mode 0)
		)
		(polygon
			(pts
				(arc
					(start 77.664818 -86.510622)
					(mid 77.283945 -86.129368)
					(end 76.902818 -86.510368)
				)
				(arc
					(start 76.902818 -87.399368)
					(mid 77.283818 -87.780368)
					(end 77.664818 -87.399368)
				)
			)
		)
	)
	(zone
		(layers "In1.Cu" "In3.Cu" "In4.Cu" "In6.Cu")
		(hatch none 0.5)
		(connect_pads
			(clearance 0)
		)
		(min_thickness 0.25)
		(keepout
			(tracks not_allowed)
			(vias allowed)
			(pads allowed)
			(copperpour not_allowed)
			(footprints allowed)
		)
		(placement
			(enabled no)
			(sheetname "")
		)
		(fill yes
			(thermal_gap 0.5)
			(thermal_bridge_width 0.5)
			(island_removal_mode 0)
		)
		(polygon
			(pts
				(arc
					(start 112.985042 -32.00019)
					(mid 112.499902 -31.51505)
					(end 112.014762 -32.00019)
				)
				(arc
					(start 112.014762 -33.39973)
					(mid 112.499775 -33.885124)
					(end 112.985042 -33.399984)
				)
			)
		)
	)
	(zone
		(layers "In1.Cu" "In3.Cu" "In4.Cu" "In6.Cu")
		(hatch none 0.5)
		(connect_pads
			(clearance 0)
		)
		(min_thickness 0.25)
		(keepout
			(tracks not_allowed)
			(vias allowed)
			(pads allowed)
			(copperpour not_allowed)
			(footprints allowed)
		)
		(placement
			(enabled no)
			(sheetname "")
		)
		(fill yes
			(thermal_gap 0.5)
			(thermal_bridge_width 0.5)
			(island_removal_mode 0)
		)
		(polygon
			(pts
				(arc
					(start 227.24999 -120.000014)
					(mid 217.749882 -120.000014)
					(end 227.24999 -120.000014)
				)
			)
		)
	)
	(zone
		(layers "In1.Cu" "In3.Cu" "In4.Cu" "In6.Cu")
		(hatch none 0.5)
		(connect_pads
			(clearance 0)
		)
		(min_thickness 0.25)
		(keepout
			(tracks not_allowed)
			(vias allowed)
			(pads allowed)
			(copperpour not_allowed)
			(footprints allowed)
		)
		(placement
			(enabled no)
			(sheetname "")
		)
		(fill yes
			(thermal_gap 0.5)
			(thermal_bridge_width 0.5)
			(island_removal_mode 0)
		)
		(polygon
			(pts
				(arc
					(start 77.736192 -67.312286)
					(mid 77.355319 -66.931032)
					(end 76.974192 -67.312032)
				)
				(arc
					(start 76.974192 -68.201032)
					(mid 77.355192 -68.582032)
					(end 77.736192 -68.201032)
				)
			)
		)
	)
	(zone
		(layers "In1.Cu" "In3.Cu" "In4.Cu" "In6.Cu")
		(hatch none 0.5)
		(connect_pads
			(clearance 0)
		)
		(min_thickness 0.25)
		(keepout
			(tracks not_allowed)
			(vias allowed)
			(pads allowed)
			(copperpour not_allowed)
			(footprints allowed)
		)
		(placement
			(enabled no)
			(sheetname "")
		)
		(fill yes
			(thermal_gap 0.5)
			(thermal_bridge_width 0.5)
			(island_removal_mode 0)
		)
		(polygon
			(pts
				(arc
					(start 109.3851 -32.00019)
					(mid 108.89996 -31.51505)
					(end 108.41482 -32.00019)
				)
				(arc
					(start 108.41482 -33.39973)
					(mid 108.899833 -33.885124)
					(end 109.3851 -33.399984)
				)
			)
		)
	)
	(zone
		(layers "In1.Cu" "In3.Cu" "In4.Cu" "In6.Cu")
		(hatch none 0.5)
		(connect_pads
			(clearance 0)
		)
		(min_thickness 0.25)
		(keepout
			(tracks not_allowed)
			(vias allowed)
			(pads allowed)
			(copperpour not_allowed)
			(footprints allowed)
		)
		(placement
			(enabled no)
			(sheetname "")
		)
		(fill yes
			(thermal_gap 0.5)
			(thermal_bridge_width 0.5)
			(island_removal_mode 0)
		)
		(polygon
			(pts
				(arc
					(start 138.185144 -32.00019)
					(mid 137.700004 -31.51505)
					(end 137.214864 -32.00019)
				)
				(arc
					(start 137.214864 -33.39973)
					(mid 137.699877 -33.885124)
					(end 138.185144 -33.399984)
				)
			)
		)
	)
	(zone
		(layers "In1.Cu" "In3.Cu" "In4.Cu" "In6.Cu")
		(hatch none 0.5)
		(connect_pads
			(clearance 0)
		)
		(min_thickness 0.25)
		(keepout
			(tracks not_allowed)
			(vias allowed)
			(pads allowed)
			(copperpour not_allowed)
			(footprints allowed)
		)
		(placement
			(enabled no)
			(sheetname "")
		)
		(fill yes
			(thermal_gap 0.5)
			(thermal_bridge_width 0.5)
			(island_removal_mode 0)
		)
		(polygon
			(pts
				(arc
					(start 114.78514 -33.20034)
					(mid 114.300127 -32.714946)
					(end 113.81486 -33.200086)
				)
				(arc
					(start 113.81486 -34.600134)
					(mid 114.3 -35.085274)
					(end 114.78514 -34.600134)
				)
			)
		)
	)
	(zone
		(layers "In1.Cu" "In3.Cu" "In4.Cu" "In6.Cu")
		(hatch none 0.5)
		(connect_pads
			(clearance 0)
		)
		(min_thickness 0.25)
		(keepout
			(tracks not_allowed)
			(vias allowed)
			(pads allowed)
			(copperpour not_allowed)
			(footprints allowed)
		)
		(placement
			(enabled no)
			(sheetname "")
		)
		(fill yes
			(thermal_gap 0.5)
			(thermal_bridge_width 0.5)
			(island_removal_mode 0)
		)
		(polygon
			(pts
				(arc
					(start 136.385046 -33.20034)
					(mid 135.900033 -32.714946)
					(end 135.414766 -33.200086)
				)
				(arc
					(start 135.414766 -34.600134)
					(mid 135.899906 -35.085274)
					(end 136.385046 -34.600134)
				)
			)
		)
	)
	(zone
		(layers "In1.Cu" "In3.Cu" "In4.Cu" "In6.Cu")
		(hatch none 0.5)
		(connect_pads
			(clearance 0)
		)
		(min_thickness 0.25)
		(keepout
			(tracks not_allowed)
			(vias allowed)
			(pads allowed)
			(copperpour not_allowed)
			(footprints allowed)
		)
		(placement
			(enabled no)
			(sheetname "")
		)
		(fill yes
			(thermal_gap 0.5)
			(thermal_bridge_width 0.5)
			(island_removal_mode 0)
		)
		(polygon
			(pts
				(arc
					(start 160.250124 -153.999946)
					(mid 150.750016 -153.999946)
					(end 160.250124 -153.999946)
				)
			)
		)
	)
	(zone
		(layers "In1.Cu" "In3.Cu" "In4.Cu" "In6.Cu")
		(hatch none 0.5)
		(connect_pads
			(clearance 0)
		)
		(min_thickness 0.25)
		(keepout
			(tracks not_allowed)
			(vias allowed)
			(pads allowed)
			(copperpour not_allowed)
			(footprints allowed)
		)
		(placement
			(enabled no)
			(sheetname "")
		)
		(fill yes
			(thermal_gap 0.5)
			(thermal_bridge_width 0.5)
			(island_removal_mode 0)
		)
		(polygon
			(pts
				(arc
					(start 83.739228 -94.492826)
					(mid 83.358355 -94.111572)
					(end 82.977228 -94.492572)
				)
				(arc
					(start 82.977228 -95.381572)
					(mid 83.358228 -95.762572)
					(end 83.739228 -95.381572)
				)
			)
		)
	)
	(zone
		(layers "In1.Cu" "In3.Cu" "In4.Cu" "In6.Cu")
		(hatch none 0.5)
		(connect_pads
			(clearance 0)
		)
		(min_thickness 0.25)
		(keepout
			(tracks not_allowed)
			(vias allowed)
			(pads allowed)
			(copperpour not_allowed)
			(footprints allowed)
		)
		(placement
			(enabled no)
			(sheetname "")
		)
		(fill yes
			(thermal_gap 0.5)
			(thermal_bridge_width 0.5)
			(island_removal_mode 0)
		)
		(polygon
			(pts
				(arc
					(start 112.985042 -35.600132)
					(mid 112.499902 -35.114992)
					(end 112.014762 -35.600132)
				)
				(arc
					(start 112.014762 -36.999926)
					(mid 112.499775 -37.48532)
					(end 112.985042 -37.00018)
				)
			)
		)
	)
	(zone
		(layers "In1.Cu" "In3.Cu" "In4.Cu" "In6.Cu")
		(hatch none 0.5)
		(connect_pads
			(clearance 0)
		)
		(min_thickness 0.25)
		(keepout
			(tracks not_allowed)
			(vias allowed)
			(pads allowed)
			(copperpour not_allowed)
			(footprints allowed)
		)
		(placement
			(enabled no)
			(sheetname "")
		)
		(fill yes
			(thermal_gap 0.5)
			(thermal_bridge_width 0.5)
			(island_removal_mode 0)
		)
		(polygon
			(pts
				(arc
					(start 138.185144 -35.600132)
					(mid 137.700004 -35.114992)
					(end 137.214864 -35.600132)
				)
				(arc
					(start 137.214864 -36.999926)
					(mid 137.699877 -37.48532)
					(end 138.185144 -37.00018)
				)
			)
		)
	)
	(zone
		(layers "In1.Cu" "In3.Cu" "In4.Cu" "In6.Cu")
		(hatch none 0.5)
		(connect_pads
			(clearance 0)
		)
		(min_thickness 0.25)
		(keepout
			(tracks not_allowed)
			(vias allowed)
			(pads allowed)
			(copperpour not_allowed)
			(footprints allowed)
		)
		(placement
			(enabled no)
			(sheetname "")
		)
		(fill yes
			(thermal_gap 0.5)
			(thermal_bridge_width 0.5)
			(island_removal_mode 0)
		)
		(polygon
			(pts
				(arc
					(start 227.24999 -7.999984)
					(mid 217.749882 -7.999984)
					(end 227.24999 -7.999984)
				)
			)
		)
	)
	(zone
		(layers "In1.Cu" "In3.Cu" "In4.Cu" "In6.Cu")
		(hatch none 0.5)
		(connect_pads
			(clearance 0)
		)
		(min_thickness 0.25)
		(keepout
			(tracks not_allowed)
			(vias allowed)
			(pads allowed)
			(copperpour not_allowed)
			(footprints allowed)
		)
		(placement
			(enabled no)
			(sheetname "")
		)
		(fill yes
			(thermal_gap 0.5)
			(thermal_bridge_width 0.5)
			(island_removal_mode 0)
		)
		(polygon
			(pts
				(arc
					(start 114.78514 -36.800028)
					(mid 114.3 -36.314888)
					(end 113.81486 -36.800028)
				)
				(arc
					(start 113.81486 -38.199822)
					(mid 114.299873 -38.685216)
					(end 114.78514 -38.200076)
				)
			)
		)
	)
	(zone
		(net "VPLLAV33")
		(layer "In2.Cu")
		(hatch none 0.5)
		(connect_pads
			(clearance 0.5)
		)
		(min_thickness 0.25)
		(fill yes
			(thermal_gap 0.5)
			(thermal_bridge_width 0.5)
			(island_removal_mode 0)
		)
		(polygon
			(pts
				(xy 49.8856 -149.2758) (xy 51.054 -149.2758) (xy 51.2318 -149.098) (xy 51.2318 -148.3106) (xy 50.927 -148.0058)
				(xy 50.0888 -148.0058) (xy 49.7586 -148.336) (xy 49.7586 -149.1488)
			)
		)
	)
	(zone
		(net "P1V15_STBY")
		(layer "In2.Cu")
		(hatch none 0.5)
		(connect_pads
			(clearance 0.5)
		)
		(min_thickness 0.25)
		(fill yes
			(thermal_gap 0.5)
			(thermal_bridge_width 0.5)
			(island_removal_mode 0)
		)
		(polygon
			(pts
				(xy 33.231582 -165.32098) (xy 34.415984 -165.32098) (xy 34.603436 -165.133528) (xy 34.603436 -164.261292)
				(xy 34.366962 -164.024818) (xy 33.225232 -164.024818) (xy 33.086802 -164.163248) (xy 33.086802 -165.1762)
			)
		)
	)
	(zone
		(net "GND")
		(layer "In2.Cu")
		(hatch none 0.5)
		(connect_pads
			(clearance 0.5)
		)
		(min_thickness 0.25)
		(fill yes
			(thermal_gap 0.5)
			(thermal_bridge_width 0.5)
			(island_removal_mode 0)
		)
		(polygon
			(pts
				(xy 31.254954 -132.816346) (xy 31.209488 -132.77088) (xy 31.209488 -130.244596) (xy 31.247842 -130.206242)
				(xy 33.750758 -130.206242) (xy 33.922716 -130.034284) (xy 33.922716 -129.367534) (xy 34.022792 -129.267458)
				(xy 34.906458 -129.267458) (xy 35.014916 -129.375916) (xy 35.014916 -131.811522) (xy 35.08375 -131.880356)
				(xy 35.457638 -131.880356) (xy 35.756596 -132.179314) (xy 35.756596 -133.86181) (xy 35.630104 -133.988302)
				(xy 35.04184 -133.988302) (xy 34.866326 -133.812788) (xy 34.866326 -133.033516) (xy 34.649156 -132.816346)
			)
		)
	)
	(zone
		(net "GND")
		(layer "In2.Cu")
		(hatch none 0.5)
		(connect_pads
			(clearance 0.5)
		)
		(min_thickness 0.25)
		(fill yes
			(thermal_gap 0.5)
			(thermal_bridge_width 0.5)
			(island_removal_mode 0)
		)
		(polygon
			(pts
				(xy 71.755 -157.607) (xy 69.171312 -157.607) (xy 68.99656 -157.781752) (xy 68.99656 -158.418784)
				(xy 68.91909 -158.496254) (xy 68.07327 -158.496254) (xy 67.98945 -158.412434) (xy 67.98945 -155.002484)
				(xy 68.025518 -154.966416) (xy 69.253862 -154.966416) (xy 69.401182 -154.819096) (xy 69.401182 -154.05862)
				(xy 69.513704 -153.946098) (xy 70.183502 -153.946098) (xy 70.245986 -154.008582) (xy 70.245986 -154.852624)
				(xy 70.38467 -154.991308) (xy 71.755254 -154.991308) (xy 71.782432 -155.018486) (xy 71.782432 -157.579568)
			)
		)
	)
	(zone
		(net "GND")
		(layer "In2.Cu")
		(hatch none 0.5)
		(connect_pads
			(clearance 0.5)
		)
		(min_thickness 0.25)
		(fill yes
			(thermal_gap 0.5)
			(thermal_bridge_width 0.5)
			(island_removal_mode 0)
		)
		(polygon
			(pts
				(xy 90.04935 -166.135558) (xy 94.492064 -166.135558) (xy 94.542864 -166.084758) (xy 94.542864 -164.470842)
				(xy 94.611952 -164.401754) (xy 95.212916 -164.401754) (xy 95.353378 -164.261292) (xy 95.353378 -163.579048)
				(xy 95.230696 -163.456366) (xy 90.800174 -163.456366) (xy 90.73134 -163.5252) (xy 90.73134 -164.605208)
				(xy 90.73134 -165.1762) (xy 90.671904 -165.235636) (xy 90.110056 -165.235636) (xy 89.92743 -165.418262)
				(xy 89.92743 -166.013638)
			)
		)
	)
	(zone
		(net "GND")
		(layer "In2.Cu")
		(hatch none 0.5)
		(connect_pads
			(clearance 0.5)
		)
		(min_thickness 0.25)
		(fill yes
			(thermal_gap 0.5)
			(thermal_bridge_width 0.5)
			(island_removal_mode 0)
		)
		(polygon
			(pts
				(xy 44.720764 -147.753578) (xy 44.943268 -147.976082) (xy 44.943268 -150.04923) (xy 44.775628 -150.21687)
				(xy 42.631614 -150.21687) (xy 42.416984 -150.00224) (xy 42.416984 -148.971254) (xy 41.704768 -148.259038)
				(xy 41.704768 -147.969732) (xy 41.920922 -147.753578) (xy 42.000932 -147.673568) (xy 44.640754 -147.673568)
			)
		)
	)
	(zone
		(net "GND")
		(layer "In2.Cu")
		(hatch none 0.5)
		(connect_pads
			(clearance 0.5)
		)
		(min_thickness 0.25)
		(fill yes
			(thermal_gap 0.5)
			(thermal_bridge_width 0.5)
			(island_removal_mode 0)
		)
		(polygon
			(pts
				(xy 168.475152 -98.392996) (xy 168.475152 -99.146106) (xy 175.829214 -106.500168) (xy 201.075544 -106.500168)
				(xy 202.140312 -105.4354) (xy 202.140312 -100.612448) (xy 204.26934 -98.48342) (xy 204.26934 -85.96757)
				(xy 211.84362 -78.39329) (xy 211.84362 -14.538706) (xy 209.354166 -12.049252) (xy 179.547012 -12.049252)
				(xy 174.174912 -17.421352) (xy 174.174912 -33.471612) (xy 168.475152 -39.171372)
			)
		)
	)
	(zone
		(net "GND")
		(layer "In2.Cu")
		(hatch none 0.5)
		(connect_pads
			(clearance 0.5)
		)
		(min_thickness 0.25)
		(fill yes
			(thermal_gap 0.5)
			(thermal_bridge_width 0.5)
			(island_removal_mode 0)
		)
		(polygon
			(pts
				(xy 54.544468 -149.152356) (xy 54.544468 -148.8694) (xy 54.25059 -148.575268) (xy 53.937916 -148.575268)
				(xy 52.166012 -150.347172) (xy 52.166012 -150.741634) (xy 52.452524 -151.0284) (xy 52.668424 -151.0284)
			)
		)
	)
	(zone
		(layers "In2.Cu" "In5.Cu")
		(hatch none 0.5)
		(connect_pads
			(clearance 0)
		)
		(min_thickness 0.25)
		(keepout
			(tracks not_allowed)
			(vias allowed)
			(pads allowed)
			(copperpour not_allowed)
			(footprints allowed)
		)
		(placement
			(enabled no)
			(sheetname "")
		)
		(fill yes
			(thermal_gap 0.5)
			(thermal_bridge_width 0.5)
			(island_removal_mode 0)
		)
		(polygon
			(pts
				(arc
					(start 17.608042 -187.999878)
					(mid 7.392162 -187.999878)
					(end 17.608042 -187.999878)
				)
			)
		)
	)
	(zone
		(layers "In2.Cu" "In5.Cu")
		(hatch none 0.5)
		(connect_pads
			(clearance 0)
		)
		(min_thickness 0.25)
		(keepout
			(tracks not_allowed)
			(vias allowed)
			(pads allowed)
			(copperpour not_allowed)
			(footprints allowed)
		)
		(placement
			(enabled no)
			(sheetname "")
		)
		(fill yes
			(thermal_gap 0.5)
			(thermal_bridge_width 0.5)
			(island_removal_mode 0)
		)
		(polygon
			(pts
				(arc
					(start 108.107988 -9.99998)
					(mid 97.892108 -9.99998)
					(end 108.107988 -9.99998)
				)
			)
		)
	)
	(zone
		(layers "In2.Cu" "In5.Cu")
		(hatch none 0.5)
		(connect_pads
			(clearance 0)
		)
		(min_thickness 0.25)
		(keepout
			(tracks not_allowed)
			(vias allowed)
			(pads allowed)
			(copperpour not_allowed)
			(footprints allowed)
		)
		(placement
			(enabled no)
			(sheetname "")
		)
		(fill yes
			(thermal_gap 0.5)
			(thermal_bridge_width 0.5)
			(island_removal_mode 0)
		)
		(polygon
			(pts
				(arc
					(start 76.900024 -102.96906)
					(mid 74.819002 -105.050082)
					(end 76.900024 -107.131104)
				)
				(arc
					(start 80.199992 -107.131104)
					(mid 82.281014 -105.050082)
					(end 80.199992 -102.96906)
				)
			)
		)
	)
	(zone
		(layers "In2.Cu" "In5.Cu")
		(hatch none 0.5)
		(connect_pads
			(clearance 0)
		)
		(min_thickness 0.25)
		(keepout
			(tracks not_allowed)
			(vias allowed)
			(pads allowed)
			(copperpour not_allowed)
			(footprints allowed)
		)
		(placement
			(enabled no)
			(sheetname "")
		)
		(fill yes
			(thermal_gap 0.5)
			(thermal_bridge_width 0.5)
			(island_removal_mode 0)
		)
		(polygon
			(pts
				(arc
					(start 23.107904 -120.000014)
					(mid 12.892024 -120.000014)
					(end 23.107904 -120.000014)
				)
			)
		)
	)
	(zone
		(layers "In2.Cu" "In5.Cu")
		(hatch none 0.5)
		(connect_pads
			(clearance 0)
		)
		(min_thickness 0.25)
		(keepout
			(tracks not_allowed)
			(vias allowed)
			(pads allowed)
			(copperpour not_allowed)
			(footprints allowed)
		)
		(placement
			(enabled no)
			(sheetname "")
		)
		(fill yes
			(thermal_gap 0.5)
			(thermal_bridge_width 0.5)
			(island_removal_mode 0)
		)
		(polygon
			(pts
				(arc
					(start 227.607876 -187.999878)
					(mid 217.391996 -187.999878)
					(end 227.607876 -187.999878)
				)
			)
		)
	)
	(zone
		(layers "In2.Cu" "In5.Cu")
		(hatch none 0.5)
		(connect_pads
			(clearance 0)
		)
		(min_thickness 0.25)
		(keepout
			(tracks not_allowed)
			(vias allowed)
			(pads allowed)
			(copperpour not_allowed)
			(footprints allowed)
		)
		(placement
			(enabled no)
			(sheetname "")
		)
		(fill yes
			(thermal_gap 0.5)
			(thermal_bridge_width 0.5)
			(island_removal_mode 0)
		)
		(polygon
			(pts
				(arc
					(start 78.503018 -83.309968)
					(mid 78.122018 -82.928968)
					(end 77.741018 -83.309968)
				)
				(arc
					(start 77.741018 -84.198968)
					(mid 78.120748 -84.579966)
					(end 78.503018 -84.201508)
				)
				(arc
					(start 78.388718 -84.201508)
					(mid 78.122018 -84.46568)
					(end 77.855318 -84.201508)
				)
				(arc
					(start 77.855318 -84.198968)
					(mid 78.122018 -83.932268)
					(end 78.388718 -84.198968)
				)
				(xy 78.503018 -84.198968) (xy 78.503018 -83.312508)
				(arc
					(start 78.388718 -83.312508)
					(mid 78.122018 -83.57668)
					(end 77.855318 -83.312508)
				)
				(arc
					(start 77.855318 -83.309968)
					(mid 78.122018 -83.043268)
					(end 78.388718 -83.309968)
				)
			)
		)
	)
	(zone
		(layers "In2.Cu" "In5.Cu")
		(hatch none 0.5)
		(connect_pads
			(clearance 0)
		)
		(min_thickness 0.25)
		(keepout
			(tracks not_allowed)
			(vias allowed)
			(pads allowed)
			(copperpour not_allowed)
			(footprints allowed)
		)
		(placement
			(enabled no)
			(sheetname "")
		)
		(fill yes
			(thermal_gap 0.5)
			(thermal_bridge_width 0.5)
			(island_removal_mode 0)
		)
		(polygon
			(pts
				(arc
					(start 77.736192 -67.312032)
					(mid 77.355192 -66.931032)
					(end 76.974192 -67.312032)
				)
				(arc
					(start 76.974192 -68.201032)
					(mid 77.353922 -68.58203)
					(end 77.736192 -68.203572)
				)
				(arc
					(start 77.621892 -68.203572)
					(mid 77.355192 -68.467744)
					(end 77.088492 -68.203572)
				)
				(arc
					(start 77.088492 -68.201032)
					(mid 77.355192 -67.934332)
					(end 77.621892 -68.201032)
				)
				(xy 77.736192 -68.201032) (xy 77.736192 -67.314572)
				(arc
					(start 77.621892 -67.314572)
					(mid 77.355192 -67.578744)
					(end 77.088492 -67.314572)
				)
				(arc
					(start 77.088492 -67.312032)
					(mid 77.355192 -67.045332)
					(end 77.621892 -67.312032)
				)
			)
		)
	)
	(zone
		(layers "In2.Cu" "In5.Cu")
		(hatch none 0.5)
		(connect_pads
			(clearance 0)
		)
		(min_thickness 0.25)
		(keepout
			(tracks not_allowed)
			(vias allowed)
			(pads allowed)
			(copperpour not_allowed)
			(footprints allowed)
		)
		(placement
			(enabled no)
			(sheetname "")
		)
		(fill yes
			(thermal_gap 0.5)
			(thermal_bridge_width 0.5)
			(island_removal_mode 0)
		)
		(polygon
			(pts
				(arc
					(start 21.249894 -58.088022)
					(mid 18.787872 -60.550044)
					(end 21.249894 -63.012066)
				)
				(arc
					(start 24.549862 -63.012066)
					(mid 27.011884 -60.550044)
					(end 24.549862 -58.088022)
				)
			)
		)
	)
	(zone
		(layers "In2.Cu" "In5.Cu")
		(hatch none 0.5)
		(connect_pads
			(clearance 0)
		)
		(min_thickness 0.25)
		(keepout
			(tracks not_allowed)
			(vias allowed)
			(pads allowed)
			(copperpour not_allowed)
			(footprints allowed)
		)
		(placement
			(enabled no)
			(sheetname "")
		)
		(fill yes
			(thermal_gap 0.5)
			(thermal_bridge_width 0.5)
			(island_removal_mode 0)
		)
		(polygon
			(pts
				(arc
					(start 0.999998 -0.762)
					(mid 0.831708 -0.831708)
					(end 0.762 -0.999998)
				)
				(arc
					(start 0.762 -183.76392)
					(mid 0.768367 -183.818601)
					(end 0.787146 -183.870346)
				)
				(arc
					(start 5.40512 -193.106548)
					(mid 5.492861 -193.202556)
					(end 5.617972 -193.23812)
				)
				(arc
					(start 98.0821 -193.23812)
					(mid 98.207223 -193.202575)
					(end 98.294952 -193.106548)
				)
				(arc
					(start 102.912926 -183.870346)
					(mid 102.931684 -183.818596)
					(end 102.938072 -183.76392)
				)
				(xy 102.938072 -183.652668) (xy 102.169722 -183.652668) (xy 97.75825 -192.47612) (xy 5.941822 -192.47612)
				(xy 1.53035 -183.652668) (xy 1.5113 -183.652668) (xy 1.5113 -183.627268) (xy 1.524 -183.627268)
				(xy 1.524 -1.524) (xy 29.006038 -1.524)
				(arc
					(start 29.006038 -109.050074)
					(mid 29.7453 -110.83481)
					(end 31.530036 -111.574072)
				)
				(arc
					(start 72.030082 -111.574072)
					(mid 73.814818 -110.83481)
					(end 74.55408 -109.050074)
				)
				(xy 74.55408 -1.524) (xy 233.476038 -1.524) (xy 233.476038 -183.640222) (xy 229.058216 -192.47612)
				(xy 216.524078 -192.47612)
				(arc
					(start 216.524078 -160.999932)
					(mid 215.784816 -159.215196)
					(end 214.00008 -158.475934)
				)
				(xy 150.241762 -158.475934) (xy 145.82394 -149.640036)
				(arc
					(start 145.82394 -47.999904)
					(mid 144.636825 -46.156945)
					(end 142.468092 -46.475904)
				)
				(arc
					(start 105.53192 -46.475904)
					(mid 103.363292 -46.157176)
					(end 102.176072 -47.999904)
				)
				(xy 102.176072 -183.627268) (xy 102.938072 -183.627268)
				(arc
					(start 102.938072 -47.999904)
					(mid 103.798188 -46.803514)
					(end 105.206038 -47.237904)
				)
				(arc
					(start 142.793974 -47.237904)
					(mid 144.201748 -46.80374)
					(end 145.06194 -47.999904)
				)
				(arc
					(start 145.06194 -149.763734)
					(mid 145.068307 -149.818415)
					(end 145.087086 -149.87016)
				)
				(arc
					(start 149.70506 -159.106362)
					(mid 149.792801 -159.20237)
					(end 149.917912 -159.237934)
				)
				(arc
					(start 214.00008 -159.237934)
					(mid 215.246001 -159.754011)
					(end 215.762078 -160.999932)
				)
				(arc
					(start 215.762078 -193.000122)
					(mid 215.831786 -193.168412)
					(end 216.000076 -193.23812)
				)
				(arc
					(start 229.382066 -193.23812)
					(mid 229.507189 -193.202575)
					(end 229.594918 -193.106548)
				)
				(arc
					(start 234.212892 -183.870346)
					(mid 234.23165 -183.818596)
					(end 234.238038 -183.76392)
				)
				(arc
					(start 234.238038 -0.999998)
					(mid 234.16833 -0.831708)
					(end 234.00004 -0.762)
				)
				(arc
					(start 74.030078 -0.762)
					(mid 73.861788 -0.831708)
					(end 73.79208 -0.999998)
				)
				(arc
					(start 73.79208 -109.050074)
					(mid 73.276003 -110.295995)
					(end 72.030082 -110.812072)
				)
				(arc
					(start 31.530036 -110.812072)
					(mid 30.284115 -110.295995)
					(end 29.768038 -109.050074)
				)
				(arc
					(start 29.768038 -0.999998)
					(mid 29.69833 -0.831708)
					(end 29.53004 -0.762)
				)
			)
		)
	)
	(zone
		(layers "In2.Cu" "In5.Cu")
		(hatch none 0.5)
		(connect_pads
			(clearance 0)
		)
		(min_thickness 0.25)
		(keepout
			(tracks not_allowed)
			(vias allowed)
			(pads allowed)
			(copperpour not_allowed)
			(footprints allowed)
		)
		(placement
			(enabled no)
			(sheetname "")
		)
		(fill yes
			(thermal_gap 0.5)
			(thermal_bridge_width 0.5)
			(island_removal_mode 0)
		)
		(polygon
			(pts
				(arc
					(start 85.108034 -120.000014)
					(mid 74.892154 -120.000014)
					(end 85.108034 -120.000014)
				)
			)
		)
	)
	(zone
		(layers "In2.Cu" "In5.Cu")
		(hatch none 0.5)
		(connect_pads
			(clearance 0)
		)
		(min_thickness 0.25)
		(keepout
			(tracks not_allowed)
			(vias allowed)
			(pads allowed)
			(copperpour not_allowed)
			(footprints allowed)
		)
		(placement
			(enabled no)
			(sheetname "")
		)
		(fill yes
			(thermal_gap 0.5)
			(thermal_bridge_width 0.5)
			(island_removal_mode 0)
		)
		(polygon
			(pts
				(arc
					(start 78.503018 -70.508368)
					(mid 78.122018 -70.127368)
					(end 77.741018 -70.508368)
				)
				(arc
					(start 77.741018 -71.397368)
					(mid 78.120748 -71.778366)
					(end 78.503018 -71.399908)
				)
				(arc
					(start 78.388718 -71.399908)
					(mid 78.122018 -71.66408)
					(end 77.855318 -71.399908)
				)
				(arc
					(start 77.855318 -71.397368)
					(mid 78.122018 -71.130668)
					(end 78.388718 -71.397368)
				)
				(xy 78.503018 -71.397368) (xy 78.503018 -70.510908)
				(arc
					(start 78.388718 -70.510908)
					(mid 78.122018 -70.77508)
					(end 77.855318 -70.510908)
				)
				(arc
					(start 77.855318 -70.508368)
					(mid 78.122018 -70.241668)
					(end 78.388718 -70.508368)
				)
			)
		)
	)
	(zone
		(layers "In2.Cu" "In5.Cu")
		(hatch none 0.5)
		(connect_pads
			(clearance 0)
		)
		(min_thickness 0.25)
		(keepout
			(tracks not_allowed)
			(vias allowed)
			(pads allowed)
			(copperpour not_allowed)
			(footprints allowed)
		)
		(placement
			(enabled no)
			(sheetname "")
		)
		(fill yes
			(thermal_gap 0.5)
			(thermal_bridge_width 0.5)
			(island_removal_mode 0)
		)
		(polygon
			(pts
				(arc
					(start 77.664818 -92.911168)
					(mid 77.283818 -92.530168)
					(end 76.902818 -92.911168)
				)
				(arc
					(start 76.902818 -93.800168)
					(mid 77.282548 -94.181166)
					(end 77.664818 -93.802708)
				)
				(arc
					(start 77.550518 -93.802708)
					(mid 77.283818 -94.06688)
					(end 77.017118 -93.802708)
				)
				(arc
					(start 77.017118 -93.800168)
					(mid 77.283818 -93.533468)
					(end 77.550518 -93.800168)
				)
				(xy 77.664818 -93.800168) (xy 77.664818 -92.913708)
				(arc
					(start 77.550518 -92.913708)
					(mid 77.283818 -93.17788)
					(end 77.017118 -92.913708)
				)
				(arc
					(start 77.017118 -92.911168)
					(mid 77.283818 -92.644468)
					(end 77.550518 -92.911168)
				)
			)
		)
	)
	(zone
		(layers "In2.Cu" "In5.Cu")
		(hatch none 0.5)
		(connect_pads
			(clearance 0)
		)
		(min_thickness 0.25)
		(keepout
			(tracks not_allowed)
			(vias allowed)
			(pads allowed)
			(copperpour not_allowed)
			(footprints allowed)
		)
		(placement
			(enabled no)
			(sheetname "")
		)
		(fill yes
			(thermal_gap 0.5)
			(thermal_bridge_width 0.5)
			(island_removal_mode 0)
		)
		(polygon
			(pts
				(arc
					(start 77.664818 -80.109568)
					(mid 77.283818 -79.728568)
					(end 76.902818 -80.109568)
				)
				(arc
					(start 76.902818 -80.998568)
					(mid 77.282548 -81.379566)
					(end 77.664818 -81.001108)
				)
				(arc
					(start 77.550518 -81.001108)
					(mid 77.283818 -81.26528)
					(end 77.017118 -81.001108)
				)
				(arc
					(start 77.017118 -80.998568)
					(mid 77.283818 -80.731868)
					(end 77.550518 -80.998568)
				)
				(xy 77.664818 -80.998568) (xy 77.664818 -80.112108)
				(arc
					(start 77.550518 -80.112108)
					(mid 77.283818 -80.37628)
					(end 77.017118 -80.112108)
				)
				(arc
					(start 77.017118 -80.109568)
					(mid 77.283818 -79.842868)
					(end 77.550518 -80.109568)
				)
			)
		)
	)
	(zone
		(layers "In2.Cu" "In5.Cu")
		(hatch none 0.5)
		(connect_pads
			(clearance 0)
		)
		(min_thickness 0.25)
		(keepout
			(tracks not_allowed)
			(vias allowed)
			(pads allowed)
			(copperpour not_allowed)
			(footprints allowed)
		)
		(placement
			(enabled no)
			(sheetname "")
		)
		(fill yes
			(thermal_gap 0.5)
			(thermal_bridge_width 0.5)
			(island_removal_mode 0)
		)
		(polygon
			(pts
				(arc
					(start 78.503018 -89.710768)
					(mid 78.122018 -89.329768)
					(end 77.741018 -89.710768)
				)
				(arc
					(start 77.741018 -90.599768)
					(mid 78.120748 -90.980766)
					(end 78.503018 -90.602308)
				)
				(arc
					(start 78.388718 -90.602308)
					(mid 78.122018 -90.86648)
					(end 77.855318 -90.602308)
				)
				(arc
					(start 77.855318 -90.599768)
					(mid 78.122018 -90.333068)
					(end 78.388718 -90.599768)
				)
				(xy 78.503018 -90.599768) (xy 78.503018 -89.713308)
				(arc
					(start 78.388718 -89.713308)
					(mid 78.122018 -89.97748)
					(end 77.855318 -89.713308)
				)
				(arc
					(start 77.855318 -89.710768)
					(mid 78.122018 -89.444068)
					(end 78.388718 -89.710768)
				)
			)
		)
	)
	(zone
		(layers "In2.Cu" "In5.Cu")
		(hatch none 0.5)
		(connect_pads
			(clearance 0)
		)
		(min_thickness 0.25)
		(keepout
			(tracks not_allowed)
			(vias allowed)
			(pads allowed)
			(copperpour not_allowed)
			(footprints allowed)
		)
		(placement
			(enabled no)
			(sheetname "")
		)
		(fill yes
			(thermal_gap 0.5)
			(thermal_bridge_width 0.5)
			(island_removal_mode 0)
		)
		(polygon
			(pts
				(arc
					(start 155.107894 -120.000014)
					(mid 144.892014 -120.000014)
					(end 155.107894 -120.000014)
				)
			)
		)
	)
	(zone
		(layers "In2.Cu" "In5.Cu")
		(hatch none 0.5)
		(connect_pads
			(clearance 0)
		)
		(min_thickness 0.25)
		(keepout
			(tracks not_allowed)
			(vias allowed)
			(pads allowed)
			(copperpour not_allowed)
			(footprints allowed)
		)
		(placement
			(enabled no)
			(sheetname "")
		)
		(fill yes
			(thermal_gap 0.5)
			(thermal_bridge_width 0.5)
			(island_removal_mode 0)
		)
		(polygon
			(pts
				(arc
					(start 77.664818 -86.510368)
					(mid 77.283818 -86.129368)
					(end 76.902818 -86.510368)
				)
				(arc
					(start 76.902818 -87.399368)
					(mid 77.282548 -87.780366)
					(end 77.664818 -87.401908)
				)
				(arc
					(start 77.550518 -87.401908)
					(mid 77.283818 -87.66608)
					(end 77.017118 -87.401908)
				)
				(arc
					(start 77.017118 -87.399368)
					(mid 77.283818 -87.132668)
					(end 77.550518 -87.399368)
				)
				(xy 77.664818 -87.399368) (xy 77.664818 -86.512908)
				(arc
					(start 77.550518 -86.512908)
					(mid 77.283818 -86.77708)
					(end 77.017118 -86.512908)
				)
				(arc
					(start 77.017118 -86.510368)
					(mid 77.283818 -86.243668)
					(end 77.550518 -86.510368)
				)
			)
		)
	)
	(zone
		(layers "In2.Cu" "In5.Cu")
		(hatch none 0.5)
		(connect_pads
			(clearance 0)
		)
		(min_thickness 0.25)
		(keepout
			(tracks not_allowed)
			(vias allowed)
			(pads allowed)
			(copperpour not_allowed)
			(footprints allowed)
		)
		(placement
			(enabled no)
			(sheetname "")
		)
		(fill yes
			(thermal_gap 0.5)
			(thermal_bridge_width 0.5)
			(island_removal_mode 0)
		)
		(polygon
			(pts
				(arc
					(start 97.607882 -187.999878)
					(mid 87.392002 -187.999878)
					(end 97.607882 -187.999878)
				)
			)
		)
	)
	(zone
		(layers "In2.Cu" "In5.Cu")
		(hatch none 0.5)
		(connect_pads
			(clearance 0)
		)
		(min_thickness 0.25)
		(keepout
			(tracks not_allowed)
			(vias allowed)
			(pads allowed)
			(copperpour not_allowed)
			(footprints allowed)
		)
		(placement
			(enabled no)
			(sheetname "")
		)
		(fill yes
			(thermal_gap 0.5)
			(thermal_bridge_width 0.5)
			(island_removal_mode 0)
		)
		(polygon
			(pts
				(arc
					(start 227.607876 -120.000014)
					(mid 217.391996 -120.000014)
					(end 227.607876 -120.000014)
				)
			)
		)
	)
	(zone
		(layers "In2.Cu" "In5.Cu")
		(hatch none 0.5)
		(connect_pads
			(clearance 0)
		)
		(min_thickness 0.25)
		(keepout
			(tracks not_allowed)
			(vias allowed)
			(pads allowed)
			(copperpour not_allowed)
			(footprints allowed)
		)
		(placement
			(enabled no)
			(sheetname "")
		)
		(fill yes
			(thermal_gap 0.5)
			(thermal_bridge_width 0.5)
			(island_removal_mode 0)
		)
		(polygon
			(pts
				(arc
					(start 77.664818 -73.708768)
					(mid 77.283818 -73.327768)
					(end 76.902818 -73.708768)
				)
				(arc
					(start 76.902818 -74.597768)
					(mid 77.282548 -74.978766)
					(end 77.664818 -74.600308)
				)
				(arc
					(start 77.550518 -74.600308)
					(mid 77.283818 -74.86448)
					(end 77.017118 -74.600308)
				)
				(arc
					(start 77.017118 -74.597768)
					(mid 77.283818 -74.331068)
					(end 77.550518 -74.597768)
				)
				(xy 77.664818 -74.597768) (xy 77.664818 -73.711308)
				(arc
					(start 77.550518 -73.711308)
					(mid 77.283818 -73.97548)
					(end 77.017118 -73.711308)
				)
				(arc
					(start 77.017118 -73.708768)
					(mid 77.283818 -73.442068)
					(end 77.550518 -73.708768)
				)
			)
		)
	)
	(zone
		(layers "In2.Cu" "In5.Cu")
		(hatch none 0.5)
		(connect_pads
			(clearance 0)
		)
		(min_thickness 0.25)
		(keepout
			(tracks not_allowed)
			(vias allowed)
			(pads allowed)
			(copperpour not_allowed)
			(footprints allowed)
		)
		(placement
			(enabled no)
			(sheetname "")
		)
		(fill yes
			(thermal_gap 0.5)
			(thermal_bridge_width 0.5)
			(island_removal_mode 0)
		)
		(polygon
			(pts
				(arc
					(start 227.607876 -7.999984)
					(mid 217.391996 -7.999984)
					(end 227.607876 -7.999984)
				)
			)
		)
	)
	(zone
		(layers "In2.Cu" "In5.Cu")
		(hatch none 0.5)
		(connect_pads
			(clearance 0)
		)
		(min_thickness 0.25)
		(keepout
			(tracks not_allowed)
			(vias allowed)
			(pads allowed)
			(copperpour not_allowed)
			(footprints allowed)
		)
		(placement
			(enabled no)
			(sheetname "")
		)
		(fill yes
			(thermal_gap 0.5)
			(thermal_bridge_width 0.5)
			(island_removal_mode 0)
		)
		(polygon
			(pts
				(arc
					(start 78.503018 -76.909168)
					(mid 78.122018 -76.528168)
					(end 77.741018 -76.909168)
				)
				(arc
					(start 77.741018 -77.798168)
					(mid 78.120748 -78.179166)
					(end 78.503018 -77.800708)
				)
				(arc
					(start 78.388718 -77.800708)
					(mid 78.122018 -78.06488)
					(end 77.855318 -77.800708)
				)
				(arc
					(start 77.855318 -77.798168)
					(mid 78.122018 -77.531468)
					(end 78.388718 -77.798168)
				)
				(xy 78.503018 -77.798168) (xy 78.503018 -76.911708)
				(arc
					(start 78.388718 -76.911708)
					(mid 78.122018 -77.17588)
					(end 77.855318 -76.911708)
				)
				(arc
					(start 77.855318 -76.909168)
					(mid 78.122018 -76.642468)
					(end 78.388718 -76.909168)
				)
			)
		)
	)
	(zone
		(net "P1V8_STBY")
		(layer "In3.Cu")
		(hatch none 0.5)
		(connect_pads
			(clearance 0.5)
		)
		(min_thickness 0.25)
		(fill yes
			(thermal_gap 0.5)
			(thermal_bridge_width 0.5)
			(island_removal_mode 0)
		)
		(polygon
			(pts
				(xy 135.206994 -9.5885) (xy 133.555994 -11.2395) (xy 128.826006 -11.2395) (xy 128.064006 -10.4775)
				(xy 110.568994 -10.4775) (xy 104.075484 -16.97101) (xy 101.874066 -16.97101) (xy 97.8535 -20.991576)
				(xy 97.8535 -134.718806) (xy 99.1997 -136.065006) (xy 99.1997 -139.778994) (xy 97.2185 -141.760194)
				(xy 97.2185 -145.556732) (xy 98.6155 -146.953732) (xy 98.6155 -162.384994) (xy 97.640394 -163.3601)
				(xy 86.134194 -163.3601) (xy 84.965794 -164.5285) (xy 76.659994 -164.5285) (xy 76.0095 -165.178994)
				(xy 76.0095 -167.942006) (xy 76.278994 -168.2115) (xy 77.802994 -168.2115) (xy 78.183994 -168.5925)
				(xy 81.104994 -168.5925) (xy 84.3915 -171.879006) (xy 84.3915 -176.354994) (xy 81.0895 -179.656994)
				(xy 81.0895 -184.990994) (xy 79.961994 -186.1185) (xy 75.643994 -186.1185) (xy 75.3745 -186.387994)
				(xy 75.3745 -187.657994) (xy 74.500994 -188.5315) (xy 46.276006 -188.5315) (xy 39.647622 -181.903116)
				(xy 39.647622 -180.609494) (xy 38.748208 -179.71008) (xy 37.454586 -179.71008) (xy 31.069534 -173.325028)
				(xy 24.719534 -173.325028) (xy 22.781006 -171.3865) (xy 16.715994 -171.3865) (xy 16.0655 -172.036994)
				(xy 16.0655 -174.038006) (xy 18.144236 -176.116742)
				(arc
					(start 23.145242 -176.116742)
					(mid 23.218089 -176.131326)
					(end 23.279862 -176.172622)
				)
				(xy 25.0825 -177.975006) (xy 25.0825 -184.863994) (xy 24.4475 -185.498994) (xy 24.4475 -188.287406)
				(xy 27.663394 -191.5033) (xy 82.420206 -191.5033) (xy 102.430072 -171.493434)
				(arc
					(start 102.430072 -47.999904)
					(mid 103.092721 -46.61902)
					(end 104.5845 -46.272196)
				)
				(xy 104.5845 -25.575006) (xy 115.618006 -14.5415) (xy 125.300994 -14.5415) (xy 125.935994 -15.1765)
				(xy 132.255006 -15.1765) (xy 133.525006 -13.9065) (xy 140.413994 -13.9065) (xy 144.2339 -17.726406)
				(xy 144.2339 -22.33803) (xy 144.679924 -22.784054) (xy 153.915364 -22.784054) (xy 159.159956 -17.539462)
				(xy 169.427652 -17.539462) (xy 172.1231 -14.844014) (xy 172.1231 -11.71829) (xy 171.64431 -11.2395)
				(xy 157.586172 -11.2395) (xy 157.530292 -11.29538) (xy 157.333188 -11.29538) (xy 155.46197 -13.166598)
				(xy 152.103328 -13.166598) (xy 148.52523 -9.5885)
			)
		)
	)
	(zone
		(net "P12V_STBY")
		(layer "In3.Cu")
		(hatch none 0.5)
		(connect_pads
			(clearance 0.5)
		)
		(min_thickness 0.25)
		(fill yes
			(thermal_gap 0.5)
			(thermal_bridge_width 0.5)
			(island_removal_mode 0)
		)
		(polygon
			(pts
				(xy 74.754994 -2.9845) (xy 74.373994 -3.3655) (xy 74.30008 -3.3655)
				(arc
					(start 74.30008 -109.050074)
					(mid 73.635213 -110.655205)
					(end 72.030082 -111.320072)
				)
				(arc
					(start 31.530036 -111.320072)
					(mid 30.019179 -110.744241)
					(end 29.27477 -109.3089)
				)
				(xy 12.198096 -109.3089) (xy 2.8321 -118.674896) (xy 2.8321 -171.980606) (xy 16.080994 -185.2295)
				(xy 24.178006 -185.2295) (xy 24.7015 -184.706006) (xy 24.7015 -178.132994) (xy 23.066248 -176.497742)
				(xy 18.065242 -176.497742) (xy 17.986248 -176.497742) (xy 11.3665 -169.877994) (xy 11.3665 -161.661348)
				(xy 11.3665 -161.64179) (xy 11.3665 -160.462214) (xy 11.3665 -160.442656) (xy 11.3665 -133.036564)
				(xy 11.3665 -133.017006) (xy 11.3665 -119.428006) (xy 15.923006 -114.8715) (xy 19.979386 -114.8715)
				(arc
					(start 19.980148 -114.8715)
					(mid 20.062194 -114.88801)
					(end 20.131786 -114.934492)
				)
				(xy 22.202394 -117.0051) (xy 75.740006 -117.0051) (xy 77.810614 -114.934746)
				(arc
					(start 77.811122 -114.934238)
					(mid 77.880749 -114.887907)
					(end 77.96276 -114.8715)
				)
				(xy 79.931006 -114.8715) (xy 87.20455 -107.597956) (xy 87.20455 -100.587302) (xy 83.9851 -97.367852)
				(xy 83.9851 -52.600606) (xy 84.706206 -51.8795) (xy 92.758006 -51.8795) (xy 93.1545 -51.483006)
				(xy 93.1545 -49.241964) (xy 95.596964 -46.7995) (xy 97.203006 -46.7995) (xy 97.4725 -46.530006)
				(xy 97.4725 -20.833588) (xy 101.716078 -16.59001) (xy 103.917496 -16.59001) (xy 110.411006 -10.0965)
				(xy 128.221994 -10.0965) (xy 128.983994 -10.8585) (xy 133.398006 -10.8585) (xy 135.049006 -9.2075)
				(xy 148.683218 -9.2075) (xy 152.261316 -12.785598) (xy 155.303982 -12.785598) (xy 157.23108 -10.8585)
				(xy 171.802298 -10.8585) (xy 172.5041 -11.560302) (xy 172.5041 -14.921992) (xy 173.600618 -16.01851)
				(xy 203.496418 -16.01851) (xy 211.465668 -23.98776) (xy 211.465668 -96.353122) (xy 213.754208 -98.641662)
				(xy 222.911924 -98.641662) (xy 224.065084 -97.488502) (xy 231.13746 -97.488502) (xy 232.1179 -96.508062)
				(xy 232.1179 -30.101794) (xy 210.160616 -8.14451) (xy 180.056536 -8.14451) (xy 174.896526 -2.9845)
			)
		)
		(polygon
			(pts
				(arc
					(start 82.977228 -95.381572)
					(mid 83.358228 -95.762572)
					(end 83.739228 -95.381572)
				)
				(arc
					(start 83.739228 -94.492318)
					(mid 83.358101 -94.111572)
					(end 82.977228 -94.492572)
				)
			)
		)
		(polygon
			(pts
				(arc
					(start 76.902818 -93.800168)
					(mid 77.283818 -94.181168)
					(end 77.664818 -93.800168)
				)
				(arc
					(start 77.664818 -92.910914)
					(mid 77.283691 -92.530168)
					(end 76.902818 -92.911168)
				)
			)
		)
		(polygon
			(pts
				(arc
					(start 77.741018 -90.599768)
					(mid 78.122018 -90.980768)
					(end 78.503018 -90.599768)
				)
				(arc
					(start 78.503018 -89.710514)
					(mid 78.121891 -89.329768)
					(end 77.741018 -89.710768)
				)
			)
		)
		(polygon
			(pts
				(arc
					(start 82.978498 -88.980264)
					(mid 83.359498 -89.361264)
					(end 83.740498 -88.980264)
				)
				(arc
					(start 83.740498 -88.09101)
					(mid 83.359371 -87.710264)
					(end 82.978498 -88.091264)
				)
			)
		)
		(polygon
			(pts
				(arc
					(start 76.902818 -87.399368)
					(mid 77.283818 -87.780368)
					(end 77.664818 -87.399368)
				)
				(arc
					(start 77.664818 -86.510114)
					(mid 77.283691 -86.129368)
					(end 76.902818 -86.510368)
				)
			)
		)
		(polygon
			(pts
				(arc
					(start 77.741018 -84.198968)
					(mid 78.122018 -84.579968)
					(end 78.503018 -84.198968)
				)
				(arc
					(start 78.503018 -83.309714)
					(mid 78.121891 -82.928968)
					(end 77.741018 -83.309968)
				)
			)
		)
		(polygon
			(pts
				(arc
					(start 82.977228 -82.581496)
					(mid 83.358228 -82.962496)
					(end 83.739228 -82.581496)
				)
				(arc
					(start 83.739228 -81.692242)
					(mid 83.358101 -81.311496)
					(end 82.977228 -81.692496)
				)
			)
		)
		(polygon
			(pts
				(arc
					(start 76.902818 -80.998568)
					(mid 77.283818 -81.379568)
					(end 77.664818 -80.998568)
				)
				(arc
					(start 77.664818 -80.109314)
					(mid 77.283691 -79.728568)
					(end 76.902818 -80.109568)
				)
			)
		)
		(polygon
			(pts
				(arc
					(start 77.741018 -77.798168)
					(mid 78.122018 -78.179168)
					(end 78.503018 -77.798168)
				)
				(arc
					(start 78.503018 -76.908914)
					(mid 78.121891 -76.528168)
					(end 77.741018 -76.909168)
				)
			)
		)
		(polygon
			(pts
				(arc
					(start 82.977228 -76.194158)
					(mid 83.358228 -76.575158)
					(end 83.739228 -76.194158)
				)
				(arc
					(start 83.739228 -75.304904)
					(mid 83.358101 -74.924158)
					(end 82.977228 -75.305158)
				)
			)
		)
		(polygon
			(pts
				(arc
					(start 76.902818 -74.597768)
					(mid 77.283818 -74.978768)
					(end 77.664818 -74.597768)
				)
				(arc
					(start 77.664818 -73.708514)
					(mid 77.283691 -73.327768)
					(end 76.902818 -73.708768)
				)
			)
		)
		(polygon
			(pts
				(arc
					(start 77.741018 -71.397368)
					(mid 78.122018 -71.778368)
					(end 78.503018 -71.397368)
				)
				(arc
					(start 78.503018 -70.508114)
					(mid 78.121891 -70.127368)
					(end 77.741018 -70.508368)
				)
			)
		)
		(polygon
			(pts
				(arc
					(start 76.974192 -68.201032)
					(mid 77.355192 -68.582032)
					(end 77.736192 -68.201032)
				)
				(arc
					(start 77.736192 -67.311778)
					(mid 77.355065 -66.931032)
					(end 76.974192 -67.312032)
				)
			)
		)
	)
	(zone
		(net "P1V2_STBY")
		(layer "In3.Cu")
		(hatch none 0.5)
		(connect_pads
			(clearance 0.5)
		)
		(min_thickness 0.25)
		(fill yes
			(thermal_gap 0.5)
			(thermal_bridge_width 0.5)
			(island_removal_mode 0)
		)
		(polygon
			(pts
				(xy 12.026646 -131.79933) (xy 11.7475 -132.078476)
				(arc
					(start 11.7475 -133.00964)
					(mid 11.748282 -133.026786)
					(end 11.7475 -133.04393)
				)
				(xy 11.7475 -153.958036) (xy 11.747754 -153.95829) (xy 11.747754 -154.037284) (xy 11.747754 -154.116278)
				(xy 11.7475 -154.116532) (xy 11.7475 -160.373568) (xy 12.254738 -160.880806) (xy 21.361654 -160.880806)
				(xy 25.070562 -157.171898) (xy 25.070562 -154.437588) (xy 25.661366 -153.846784) (xy 31.77667 -153.846784)
				(xy 31.832296 -153.90241) (xy 31.832296 -153.902664) (xy 32.246824 -154.316938) (xy 36.497768 -154.316938)
				(xy 39.207694 -151.607012) (xy 39.207694 -150.953978) (xy 40.119554 -150.042118) (xy 40.489632 -150.042118)
				(xy 40.65016 -149.88159) (xy 40.65016 -149.636734) (xy 40.97401 -149.312884) (xy 42.024046 -149.312884)
				(xy 42.304716 -149.032214)
				(arc
					(start 42.304716 -148.099018)
					(mid 42.3193 -148.026171)
					(end 42.360596 -147.964398)
				)
				(arc
					(start 42.631614 -147.69338)
					(mid 42.693363 -147.652028)
					(end 42.766234 -147.6375)
				)
				(xy 44.371006 -147.6375) (xy 44.7675 -147.241006) (xy 44.7675 -144.858994) (xy 44.2595 -144.350994)
				(xy 44.2595 -142.445994)
				(arc
					(start 43.12793 -141.31417)
					(mid 43.086578 -141.252421)
					(end 43.07205 -141.17955)
				)
				(xy 43.07205 -140.923772) (xy 42.89933 -140.751052) (xy 40.375078 -140.751052) (xy 35.140392 -135.516366)
				(xy 27.454098 -135.516366) (xy 25.531318 -133.593586) (xy 25.531318 -132.264912) (xy 25.065736 -131.79933)
			)
		)
	)
	(zone
		(net "GND")
		(layer "In3.Cu")
		(hatch none 0.5)
		(connect_pads
			(clearance 0.5)
		)
		(min_thickness 0.25)
		(fill yes
			(thermal_gap 0.5)
			(thermal_bridge_width 0.5)
			(island_removal_mode 0)
		)
		(polygon
			(pts
				(xy 74.30008 -1.27) (xy 74.30008 -2.1971) (xy 74.348594 -2.1971) (xy 74.754994 -2.6035) (xy 175.054514 -2.6035)
				(xy 180.214524 -7.76351) (xy 210.318604 -7.76351) (xy 232.4989 -29.943806) (xy 232.4989 -96.66605)
				(xy 231.295448 -97.869502) (xy 224.223072 -97.869502) (xy 223.069912 -99.022662) (xy 213.59622 -99.022662)
				(xy 211.084668 -96.51111) (xy 211.084668 -24.145748) (xy 203.33843 -16.39951) (xy 173.44263 -16.39951)
				(xy 172.274484 -15.231364) (xy 169.58564 -17.920462) (xy 159.317944 -17.920462) (xy 154.184858 -23.053548)
				(xy 154.073352 -23.165054) (xy 144.679924 -23.165054) (xy 144.2339 -23.611078) (xy 144.2339 -29.457904)
				(xy 144.234662 -29.458666) (xy 144.234662 -29.616654) (xy 144.2339 -29.617416)
				(arc
					(start 144.2339 -46.284134)
					(mid 145.196486 -46.912516)
					(end 145.56994 -47.99965)
				)
				(xy 145.56994 -47.999904) (xy 145.56994 -149.69998) (xy 150.08479 -158.729934)
				(arc
					(start 214.00008 -158.729934)
					(mid 215.605211 -159.394801)
					(end 216.270078 -160.999932)
				)
				(xy 216.270078 -192.73012) (xy 229.214934 -192.73012) (xy 233.730038 -183.700166) (xy 233.730038 -1.27)
			)
		)
		(polygon
			(pts
				(arc
					(start 205.276958 -141.807692)
					(mid 205.815756 -141.807883)
					(end 205.815946 -141.268958)
				)
				(arc
					(start 205.187296 -140.640308)
					(mid 204.648308 -140.640308)
					(end 204.648308 -141.179296)
				)
			)
		)
		(polygon
			(pts
				(arc
					(start 200.577958 -141.807692)
					(mid 201.116756 -141.807883)
					(end 201.116946 -141.268958)
				)
				(arc
					(start 200.488296 -140.640308)
					(mid 199.949308 -140.640308)
					(end 199.949308 -141.179296)
				)
			)
		)
		(polygon
			(pts
				(arc
					(start 202.990958 -141.680692)
					(mid 203.529756 -141.680883)
					(end 203.529946 -141.141958)
				)
				(arc
					(start 202.901296 -140.513308)
					(mid 202.362308 -140.513308)
					(end 202.362308 -141.052296)
				)
			)
		)
		(polygon
			(pts
				(arc
					(start 198.164958 -141.553692)
					(mid 198.703756 -141.553883)
					(end 198.703946 -141.014958)
				)
				(arc
					(start 198.075296 -140.386308)
					(mid 197.536308 -140.386308)
					(end 197.536308 -140.925296)
				)
			)
		)
		(polygon
			(pts
				(arc
					(start 209.975958 -141.426692)
					(mid 210.514756 -141.426883)
					(end 210.514946 -140.887958)
				)
				(arc
					(start 209.886296 -140.259308)
					(mid 209.347308 -140.259308)
					(end 209.347308 -140.798296)
				)
			)
		)
		(polygon
			(pts
				(arc
					(start 195.497958 -141.299692)
					(mid 196.036756 -141.299883)
					(end 196.036946 -140.760958)
				)
				(arc
					(start 195.408296 -140.132308)
					(mid 194.869308 -140.132308)
					(end 194.869308 -140.671296)
				)
			)
		)
		(polygon
			(pts
				(arc
					(start 174.653448 -141.130782)
					(mid 175.192246 -141.130973)
					(end 175.192436 -140.592048)
				)
				(arc
					(start 174.563786 -139.963398)
					(mid 174.024798 -139.963398)
					(end 174.024798 -140.502386)
				)
			)
		)
		(polygon
			(pts
				(arc
					(start 180.364384 -141.066774)
					(mid 180.903182 -141.066965)
					(end 180.903372 -140.52804)
				)
				(arc
					(start 180.274722 -139.89939)
					(mid 179.735734 -139.89939)
					(end 179.735734 -140.438378)
				)
			)
		)
		(polygon
			(pts
				(arc
					(start 178.020218 -140.871702)
					(mid 178.559016 -140.871893)
					(end 178.559206 -140.332968)
				)
				(arc
					(start 177.930556 -139.704318)
					(mid 177.391568 -139.704318)
					(end 177.391568 -140.243306)
				)
			)
		)
		(polygon
			(pts
				(arc
					(start 185.444384 -140.584174)
					(mid 185.983182 -140.584365)
					(end 185.983372 -140.04544)
				)
				(arc
					(start 185.354722 -139.41679)
					(mid 184.815734 -139.41679)
					(end 184.815734 -139.955778)
				)
			)
		)
		(polygon
			(pts
				(arc
					(start 182.687722 -140.561314)
					(mid 183.22652 -140.561505)
					(end 183.22671 -140.02258)
				)
				(arc
					(start 182.59806 -139.39393)
					(mid 182.059072 -139.39393)
					(end 182.059072 -139.932918)
				)
			)
		)
		(polygon
			(pts
				(arc
					(start 206.800958 -140.156692)
					(mid 207.339756 -140.156883)
					(end 207.339946 -139.617958)
				)
				(arc
					(start 206.711296 -138.989308)
					(mid 206.172308 -138.989308)
					(end 206.172308 -139.528296)
				)
			)
		)
		(polygon
			(pts
				(arc
					(start 192.449958 -140.156692)
					(mid 192.988756 -140.156883)
					(end 192.988946 -139.617958)
				)
				(arc
					(start 192.360296 -138.989308)
					(mid 191.821308 -138.989308)
					(end 191.821308 -139.528296)
				)
			)
		)
		(polygon
			(pts
				(arc
					(start 213.692486 -139.77493)
					(mid 214.231284 -139.775121)
					(end 214.231474 -139.236196)
				)
				(arc
					(start 213.602824 -138.607546)
					(mid 213.063836 -138.607546)
					(end 213.063836 -139.146534)
				)
			)
		)
		(polygon
			(pts
				(arc
					(start 170.799252 -139.218924)
					(mid 171.33805 -139.219115)
					(end 171.33824 -138.68019)
				)
				(arc
					(start 170.70959 -138.05154)
					(mid 170.170602 -138.05154)
					(end 170.170602 -138.590528)
				)
			)
		)
		(polygon
			(pts
				(arc
					(start 174.302928 -138.822938)
					(mid 174.841726 -138.823129)
					(end 174.841916 -138.284204)
				)
				(arc
					(start 174.213266 -137.655554)
					(mid 173.674278 -137.655554)
					(end 173.674278 -138.194542)
				)
			)
		)
		(polygon
			(pts
				(arc
					(start 167.47109 -137.80389)
					(mid 168.009888 -137.804081)
					(end 168.010078 -137.265156)
				)
				(arc
					(start 167.381428 -136.636506)
					(mid 166.84244 -136.636506)
					(end 166.84244 -137.175494)
				)
			)
		)
		(polygon
			(pts
				(arc
					(start 183.905398 -133.354826)
					(mid 184.286144 -132.973699)
					(end 183.905144 -132.592826)
				)
				(arc
					(start 183.016144 -132.592826)
					(mid 182.635144 -132.973826)
					(end 183.016144 -133.354826)
				)
			)
		)
	)
	(zone
		(net "GND")
		(layer "In3.Cu")
		(hatch none 0.5)
		(connect_pads
			(clearance 0.5)
		)
		(min_thickness 0.25)
		(fill yes
			(thermal_gap 0.5)
			(thermal_bridge_width 0.5)
			(island_removal_mode 0)
		)
		(polygon
			(pts
				(xy 1.27 -1.27) (xy 1.27 -183.700166) (xy 5.785104 -192.73012) (xy 97.914968 -192.73012) (xy 102.430072 -183.700166)
				(xy 102.430072 -172.032422) (xy 82.578194 -191.8843) (xy 27.505406 -191.8843) (xy 24.0665 -188.445394)
				(xy 24.0665 -185.6105) (xy 15.923006 -185.6105) (xy 2.4511 -172.138594)
				(arc
					(start 2.4511 -118.595902)
					(mid 2.465684 -118.523055)
					(end 2.50698 -118.461282)
				)
				(arc
					(start 11.984482 -108.98378)
					(mid 12.046231 -108.942428)
					(end 12.119102 -108.9279)
				)
				(xy 29.260038 -108.9279) (xy 29.260038 -1.27)
			)
		)
	)
	(zone
		(net "P12V_IOM")
		(layer "In3.Cu")
		(hatch none 0.5)
		(connect_pads
			(clearance 0.5)
		)
		(min_thickness 0.25)
		(fill yes
			(thermal_gap 0.5)
			(thermal_bridge_width 0.5)
			(island_removal_mode 0)
		)
		(polygon
			(pts
				(xy 133.682994 -14.2875) (xy 132.412994 -15.5575) (xy 125.778006 -15.5575) (xy 125.143006 -14.9225)
				(xy 121.724928 -14.9225) (xy 121.497852 -15.149576) (xy 121.497852 -46.729904) (xy 134.867142 -46.729904)
				(xy 134.867142 -30.492192) (xy 135.725662 -29.633672) (xy 143.678656 -29.633672) (xy 143.8529 -29.459428)
				(xy 143.8529 -17.884394) (xy 140.256006 -14.2875)
			)
		)
		(polygon
			(pts
				(arc
					(start 133.614922 -44.200318)
					(mid 134.100189 -44.685204)
					(end 134.585202 -44.200064)
				)
				(arc
					(start 134.585202 -42.800016)
					(mid 134.100062 -42.314876)
					(end 133.614922 -42.800016)
				)
			)
		)
		(polygon
			(pts
				(arc
					(start 131.814824 -38.20033)
					(mid 132.300091 -38.685216)
					(end 132.785104 -38.200076)
				)
				(arc
					(start 132.785104 -36.800028)
					(mid 132.299964 -36.314888)
					(end 131.814824 -36.800028)
				)
			)
		)
		(polygon
			(pts
				(arc
					(start 128.214882 -38.20033)
					(mid 128.700149 -38.685216)
					(end 129.185162 -38.200076)
				)
				(arc
					(start 129.185162 -36.800028)
					(mid 128.700022 -36.314888)
					(end 128.214882 -36.800028)
				)
			)
		)
		(polygon
			(pts
				(arc
					(start 133.614922 -37.000434)
					(mid 134.100189 -37.48532)
					(end 134.585202 -37.00018)
				)
				(arc
					(start 134.585202 -35.600132)
					(mid 134.100062 -35.114992)
					(end 133.614922 -35.600132)
				)
			)
		)
		(polygon
			(pts
				(arc
					(start 130.014726 -37.000434)
					(mid 130.499993 -37.48532)
					(end 130.985006 -37.00018)
				)
				(arc
					(start 130.985006 -35.600132)
					(mid 130.499866 -35.114992)
					(end 130.014726 -35.600132)
				)
			)
		)
		(polygon
			(pts
				(arc
					(start 131.814824 -34.600134)
					(mid 132.299964 -35.085274)
					(end 132.785104 -34.600134)
				)
				(arc
					(start 132.785104 -33.199832)
					(mid 132.299837 -32.714946)
					(end 131.814824 -33.200086)
				)
			)
		)
		(polygon
			(pts
				(arc
					(start 128.214882 -34.600134)
					(mid 128.700022 -35.085274)
					(end 129.185162 -34.600134)
				)
				(arc
					(start 129.185162 -33.199832)
					(mid 128.699895 -32.714946)
					(end 128.214882 -33.200086)
				)
			)
		)
		(polygon
			(pts
				(arc
					(start 133.614922 -33.400238)
					(mid 134.100189 -33.885124)
					(end 134.585202 -33.399984)
				)
				(arc
					(start 134.585202 -32.00019)
					(mid 134.100062 -31.51505)
					(end 133.614922 -32.00019)
				)
			)
		)
		(polygon
			(pts
				(arc
					(start 130.014726 -33.400238)
					(mid 130.499993 -33.885124)
					(end 130.985006 -33.399984)
				)
				(arc
					(start 130.985006 -32.00019)
					(mid 130.499866 -31.51505)
					(end 130.014726 -32.00019)
				)
			)
		)
		(polygon
			(pts
				(arc
					(start 129.535428 -26.592276)
					(mid 129.916174 -26.211149)
					(end 129.535174 -25.830276)
				)
				(arc
					(start 128.467866 -25.830276)
					(mid 128.086866 -26.211276)
					(end 128.467866 -26.592276)
				)
			)
		)
	)
	(zone
		(net "GND")
		(layer "In3.Cu")
		(hatch none 0.5)
		(connect_pads
			(clearance 0.5)
		)
		(min_thickness 0.25)
		(fill yes
			(thermal_gap 0.5)
			(thermal_bridge_width 0.5)
			(island_removal_mode 0)
		)
		(polygon
			(pts
				(xy 135.88365 -30.014672) (xy 135.248142 -30.65018) (xy 135.248142 -46.729904)
				(arc
					(start 142.567152 -46.729904)
					(mid 143.159413 -46.349982)
					(end 143.8529 -46.230794)
				)
				(xy 143.8529 -30.219142) (xy 143.64843 -30.014672)
			)
		)
		(polygon
			(pts
				(arc
					(start 140.814806 -44.200318)
					(mid 141.300073 -44.685204)
					(end 141.785086 -44.200064)
				)
				(arc
					(start 141.785086 -42.800016)
					(mid 141.299946 -42.314876)
					(end 140.814806 -42.800016)
				)
			)
		)
		(polygon
			(pts
				(arc
					(start 139.014708 -38.20033)
					(mid 139.499975 -38.685216)
					(end 139.984988 -38.200076)
				)
				(arc
					(start 139.984988 -36.800028)
					(mid 139.499848 -36.314888)
					(end 139.014708 -36.800028)
				)
			)
		)
		(polygon
			(pts
				(arc
					(start 135.414766 -38.20033)
					(mid 135.900033 -38.685216)
					(end 136.385046 -38.200076)
				)
				(arc
					(start 136.385046 -36.800028)
					(mid 135.899906 -36.314888)
					(end 135.414766 -36.800028)
				)
			)
		)
		(polygon
			(pts
				(arc
					(start 140.814806 -37.000434)
					(mid 141.300073 -37.48532)
					(end 141.785086 -37.00018)
				)
				(arc
					(start 141.785086 -35.600132)
					(mid 141.299946 -35.114992)
					(end 140.814806 -35.600132)
				)
			)
		)
		(polygon
			(pts
				(arc
					(start 137.214864 -37.000434)
					(mid 137.700131 -37.48532)
					(end 138.185144 -37.00018)
				)
				(arc
					(start 138.185144 -35.600132)
					(mid 137.700004 -35.114992)
					(end 137.214864 -35.600132)
				)
			)
		)
		(polygon
			(pts
				(arc
					(start 139.014708 -34.600134)
					(mid 139.499848 -35.085274)
					(end 139.984988 -34.600134)
				)
				(arc
					(start 139.984988 -33.199832)
					(mid 139.499721 -32.714946)
					(end 139.014708 -33.200086)
				)
			)
		)
		(polygon
			(pts
				(arc
					(start 135.414766 -34.600134)
					(mid 135.899906 -35.085274)
					(end 136.385046 -34.600134)
				)
				(arc
					(start 136.385046 -33.199832)
					(mid 135.899779 -32.714946)
					(end 135.414766 -33.200086)
				)
			)
		)
		(polygon
			(pts
				(arc
					(start 140.814806 -33.400238)
					(mid 141.300073 -33.885124)
					(end 141.785086 -33.399984)
				)
				(arc
					(start 141.785086 -32.00019)
					(mid 141.299946 -31.51505)
					(end 140.814806 -32.00019)
				)
			)
		)
		(polygon
			(pts
				(arc
					(start 137.214864 -33.400238)
					(mid 137.700131 -33.885124)
					(end 138.185144 -33.399984)
				)
				(arc
					(start 138.185144 -32.00019)
					(mid 137.700004 -31.51505)
					(end 137.214864 -32.00019)
				)
			)
		)
	)
	(zone
		(net "P3V3_STBY")
		(layer "In3.Cu")
		(hatch none 0.5)
		(connect_pads
			(clearance 0.5)
		)
		(min_thickness 0.25)
		(fill yes
			(thermal_gap 0.5)
			(thermal_bridge_width 0.5)
			(island_removal_mode 0)
		)
		(polygon
			(pts
				(xy 95.754952 -47.1805) (xy 93.5355 -49.399952) (xy 93.5355 -51.640994) (xy 92.915994 -52.2605)
				(xy 84.864194 -52.2605) (xy 84.3661 -52.758594) (xy 84.3661 -97.209864) (xy 87.58555 -100.429314)
				(xy 87.58555 -107.755944) (xy 77.968094 -117.3734) (xy 76.1238 -117.3734) (xy 76.1111 -117.3861)
				(xy 22.044406 -117.3861) (xy 19.910806 -115.2525) (xy 16.080994 -115.2525) (xy 11.7475 -119.585994)
				(xy 11.7475 -131.259072) (xy 11.906758 -131.41833) (xy 25.223724 -131.41833) (xy 25.912318 -132.106924)
				(xy 25.912318 -133.435598) (xy 27.612086 -135.135366) (xy 35.29838 -135.135366) (xy 40.533066 -140.370052)
				(arc
					(start 42.978324 -140.370052)
					(mid 43.051171 -140.384636)
					(end 43.112944 -140.425932)
				)
				(arc
					(start 43.39717 -140.710158)
					(mid 43.438522 -140.771907)
					(end 43.45305 -140.844778)
				)
				(xy 43.45305 -141.100556) (xy 44.6405 -142.288006) (xy 44.6405 -144.193006) (xy 45.1485 -144.701006)
				(xy 45.1485 -147.398994)
				(arc
					(start 44.58462 -147.96262)
					(mid 44.522871 -148.003972)
					(end 44.45 -148.0185)
				)
				(xy 42.845228 -148.0185) (xy 42.685716 -148.178012) (xy 42.685716 -149.190202) (xy 42.182034 -149.693884)
				(xy 41.131998 -149.693884) (xy 41.03116 -149.794722) (xy 41.03116 -150.039578) (xy 40.64762 -150.423118)
				(xy 40.277542 -150.423118) (xy 39.588694 -151.111966) (xy 39.588694 -151.765)
				(arc
					(start 36.711382 -154.642058)
					(mid 36.649633 -154.68341)
					(end 36.576762 -154.697938)
				)
				(arc
					(start 32.16783 -154.697938)
					(mid 32.094983 -154.683354)
					(end 32.03321 -154.642058)
				)
				(xy 31.618682 -154.227784) (xy 25.819354 -154.227784) (xy 25.451562 -154.595576) (xy 25.451562 -157.329886)
				(xy 21.519642 -161.261806) (xy 12.21613 -161.261806) (xy 11.7475 -161.730436) (xy 11.7475 -169.720006)
				(xy 15.6845 -173.657006) (xy 15.6845 -171.879006) (xy 16.558006 -171.0055) (xy 22.938994 -171.0055)
				(xy 24.877522 -172.944028) (xy 31.227522 -172.944028) (xy 37.612574 -179.32908) (xy 38.906196 -179.32908)
				(xy 40.028622 -180.451506) (xy 40.028622 -181.745128) (xy 46.433994 -188.1505) (xy 74.343006 -188.1505)
				(xy 74.9935 -187.500006) (xy 74.9935 -186.230006) (xy 75.486006 -185.7375) (xy 79.804006 -185.7375)
				(xy 80.7085 -184.833006) (xy 80.7085 -179.499006) (xy 84.0105 -176.197006) (xy 84.0105 -172.036994)
				(xy 80.947006 -168.9735) (xy 78.026006 -168.9735) (xy 77.645006 -168.5925) (xy 76.121006 -168.5925)
				(xy 75.6285 -168.099994) (xy 75.6285 -165.021006) (xy 76.502006 -164.1475) (xy 84.807806 -164.1475)
				(xy 85.976206 -162.9791) (xy 97.482406 -162.9791) (xy 98.2345 -162.227006) (xy 98.2345 -147.11172)
				(xy 96.8375 -145.71472) (xy 96.8375 -141.602206) (xy 98.8187 -139.621006) (xy 98.8187 -136.222994)
				(xy 97.4725 -134.876794) (xy 97.4725 -47.449994) (xy 97.203006 -47.1805)
			)
		)
		(polygon
			(pts
				(arc
					(start 84.602828 -92.195396)
					(mid 84.983828 -92.576396)
					(end 85.364828 -92.195396)
				)
				(arc
					(start 85.364828 -91.306142)
					(mid 84.983701 -90.925396)
					(end 84.602828 -91.306396)
				)
			)
		)
		(polygon
			(pts
				(arc
					(start 84.602828 -85.781134)
					(mid 84.983828 -86.162134)
					(end 85.364828 -85.781134)
				)
				(arc
					(start 85.364828 -84.89188)
					(mid 84.983701 -84.511134)
					(end 84.602828 -84.892134)
				)
			)
		)
		(polygon
			(pts
				(arc
					(start 84.605622 -79.396336)
					(mid 84.986622 -79.777336)
					(end 85.367622 -79.396336)
				)
				(arc
					(start 85.367622 -78.507082)
					(mid 84.986495 -78.126336)
					(end 84.605622 -78.507336)
				)
			)
		)
		(polygon
			(pts
				(arc
					(start 84.482178 -72.987916)
					(mid 84.863178 -73.368916)
					(end 85.244178 -72.987916)
				)
				(arc
					(start 85.244178 -72.098662)
					(mid 84.863051 -71.717916)
					(end 84.482178 -72.098916)
				)
			)
		)
	)
	(zone
		(net "GND")
		(layer "In3.Cu")
		(hatch none 0.5)
		(connect_pads
			(clearance 0.5)
		)
		(min_thickness 0.25)
		(fill yes
			(thermal_gap 0.5)
			(thermal_bridge_width 0.5)
			(island_removal_mode 0)
		)
		(polygon
			(pts
				(xy 115.775994 -14.9225) (xy 104.9655 -25.732994)
				(arc
					(start 104.9655 -46.404022)
					(mid 105.212373 -46.548042)
					(end 105.43286 -46.729904)
				)
				(xy 121.116852 -46.729904) (xy 121.116852 -15.132812) (xy 120.90654 -14.9225)
			)
		)
		(polygon
			(pts
				(arc
					(start 119.2149 -44.200318)
					(mid 119.700167 -44.685204)
					(end 120.18518 -44.200064)
				)
				(arc
					(start 120.18518 -42.800016)
					(mid 119.70004 -42.314876)
					(end 119.2149 -42.800016)
				)
			)
		)
		(polygon
			(pts
				(arc
					(start 117.414802 -38.20033)
					(mid 117.900069 -38.685216)
					(end 118.385082 -38.200076)
				)
				(arc
					(start 118.385082 -36.800028)
					(mid 117.899942 -36.314888)
					(end 117.414802 -36.800028)
				)
			)
		)
		(polygon
			(pts
				(arc
					(start 113.81486 -38.20033)
					(mid 114.300127 -38.685216)
					(end 114.78514 -38.200076)
				)
				(arc
					(start 114.78514 -36.800028)
					(mid 114.3 -36.314888)
					(end 113.81486 -36.800028)
				)
			)
		)
		(polygon
			(pts
				(arc
					(start 110.214918 -38.20033)
					(mid 110.700185 -38.685216)
					(end 111.185198 -38.200076)
				)
				(arc
					(start 111.185198 -36.800028)
					(mid 110.700058 -36.314888)
					(end 110.214918 -36.800028)
				)
			)
		)
		(polygon
			(pts
				(arc
					(start 106.614722 -38.20033)
					(mid 107.099989 -38.685216)
					(end 107.585002 -38.200076)
				)
				(arc
					(start 107.585002 -36.800028)
					(mid 107.099862 -36.314888)
					(end 106.614722 -36.800028)
				)
			)
		)
		(polygon
			(pts
				(arc
					(start 119.2149 -37.000434)
					(mid 119.700167 -37.48532)
					(end 120.18518 -37.00018)
				)
				(arc
					(start 120.18518 -35.600132)
					(mid 119.70004 -35.114992)
					(end 119.2149 -35.600132)
				)
			)
		)
		(polygon
			(pts
				(arc
					(start 115.614704 -37.000434)
					(mid 116.099971 -37.48532)
					(end 116.584984 -37.00018)
				)
				(arc
					(start 116.584984 -35.600132)
					(mid 116.099844 -35.114992)
					(end 115.614704 -35.600132)
				)
			)
		)
		(polygon
			(pts
				(arc
					(start 112.014762 -37.000434)
					(mid 112.500029 -37.48532)
					(end 112.985042 -37.00018)
				)
				(arc
					(start 112.985042 -35.600132)
					(mid 112.499902 -35.114992)
					(end 112.014762 -35.600132)
				)
			)
		)
		(polygon
			(pts
				(arc
					(start 108.41482 -37.000434)
					(mid 108.900087 -37.48532)
					(end 109.3851 -37.00018)
				)
				(arc
					(start 109.3851 -35.600132)
					(mid 108.89996 -35.114992)
					(end 108.41482 -35.600132)
				)
			)
		)
		(polygon
			(pts
				(arc
					(start 117.414802 -34.600134)
					(mid 117.899942 -35.085274)
					(end 118.385082 -34.600134)
				)
				(arc
					(start 118.385082 -33.199832)
					(mid 117.899815 -32.714946)
					(end 117.414802 -33.200086)
				)
			)
		)
		(polygon
			(pts
				(arc
					(start 113.81486 -34.600134)
					(mid 114.3 -35.085274)
					(end 114.78514 -34.600134)
				)
				(arc
					(start 114.78514 -33.199832)
					(mid 114.299873 -32.714946)
					(end 113.81486 -33.200086)
				)
			)
		)
		(polygon
			(pts
				(arc
					(start 110.214918 -34.600134)
					(mid 110.700058 -35.085274)
					(end 111.185198 -34.600134)
				)
				(arc
					(start 111.185198 -33.199832)
					(mid 110.699931 -32.714946)
					(end 110.214918 -33.200086)
				)
			)
		)
		(polygon
			(pts
				(arc
					(start 106.614722 -34.600134)
					(mid 107.099862 -35.085274)
					(end 107.585002 -34.600134)
				)
				(arc
					(start 107.585002 -33.199832)
					(mid 107.099735 -32.714946)
					(end 106.614722 -33.200086)
				)
			)
		)
		(polygon
			(pts
				(arc
					(start 119.2149 -33.400238)
					(mid 119.700167 -33.885124)
					(end 120.18518 -33.399984)
				)
				(arc
					(start 120.18518 -32.00019)
					(mid 119.70004 -31.51505)
					(end 119.2149 -32.00019)
				)
			)
		)
		(polygon
			(pts
				(arc
					(start 115.614704 -33.400238)
					(mid 116.099971 -33.885124)
					(end 116.584984 -33.399984)
				)
				(arc
					(start 116.584984 -32.00019)
					(mid 116.099844 -31.51505)
					(end 115.614704 -32.00019)
				)
			)
		)
		(polygon
			(pts
				(arc
					(start 112.014762 -33.400238)
					(mid 112.500029 -33.885124)
					(end 112.985042 -33.399984)
				)
				(arc
					(start 112.985042 -32.00019)
					(mid 112.499902 -31.51505)
					(end 112.014762 -32.00019)
				)
			)
		)
		(polygon
			(pts
				(arc
					(start 108.41482 -33.400238)
					(mid 108.900087 -33.885124)
					(end 109.3851 -33.399984)
				)
				(arc
					(start 109.3851 -32.00019)
					(mid 108.89996 -31.51505)
					(end 108.41482 -32.00019)
				)
			)
		)
	)
	(zone
		(layers "In3.Cu" "In4.Cu")
		(hatch none 0.5)
		(connect_pads
			(clearance 0)
		)
		(min_thickness 0.25)
		(keepout
			(tracks not_allowed)
			(vias allowed)
			(pads allowed)
			(copperpour not_allowed)
			(footprints allowed)
		)
		(placement
			(enabled no)
			(sheetname "")
		)
		(fill yes
			(thermal_gap 0.5)
			(thermal_bridge_width 0.5)
			(island_removal_mode 0)
		)
		(polygon
			(pts
				(arc
					(start 206.815436 -6.199886)
					(mid 205.184756 -6.199886)
					(end 206.815436 -6.199886)
				)
			)
		)
	)
	(zone
		(layers "In3.Cu" "In4.Cu")
		(hatch none 0.5)
		(connect_pads
			(clearance 0)
		)
		(min_thickness 0.25)
		(keepout
			(tracks not_allowed)
			(vias allowed)
			(pads allowed)
			(copperpour not_allowed)
			(footprints allowed)
		)
		(placement
			(enabled no)
			(sheetname "")
		)
		(fill yes
			(thermal_gap 0.5)
			(thermal_bridge_width 0.5)
			(island_removal_mode 0)
		)
		(polygon
			(pts
				(arc
					(start 0.999998 -0.762)
					(mid 0.831708 -0.831708)
					(end 0.762 -0.999998)
				)
				(arc
					(start 0.762 -183.76392)
					(mid 0.768367 -183.818601)
					(end 0.787146 -183.870346)
				)
				(arc
					(start 5.40512 -193.106548)
					(mid 5.492861 -193.202556)
					(end 5.617972 -193.23812)
				)
				(arc
					(start 98.0821 -193.23812)
					(mid 98.207223 -193.202575)
					(end 98.294952 -193.106548)
				)
				(arc
					(start 102.912926 -183.870346)
					(mid 102.930602 -183.822784)
					(end 102.937818 -183.772556)
				)
				(xy 102.677722 -183.772556) (xy 98.072194 -192.98412) (xy 5.627878 -192.98412) (xy 1.02235 -183.772556)
				(xy 1.0033 -183.772556) (xy 1.0033 -183.747156) (xy 1.016 -183.747156) (xy 1.016 -1.016) (xy 29.514038 -1.016)
				(arc
					(start 29.514038 -109.050074)
					(mid 30.10451 -110.4756)
					(end 31.530036 -111.066072)
				)
				(arc
					(start 72.030082 -111.066072)
					(mid 73.455608 -110.4756)
					(end 74.04608 -109.050074)
				)
				(xy 74.04608 -1.016) (xy 233.984038 -1.016) (xy 233.984038 -183.76011) (xy 229.37216 -192.98412)
				(xy 216.016078 -192.98412)
				(arc
					(start 216.016078 -160.999932)
					(mid 215.425606 -159.574406)
					(end 214.00008 -158.983934)
				)
				(xy 149.927818 -158.983934) (xy 145.31594 -149.759924)
				(arc
					(start 145.31594 -47.999904)
					(mid 144.344212 -46.584889)
					(end 142.674848 -46.983904)
				)
				(arc
					(start 105.325164 -46.983904)
					(mid 103.655899 -46.585145)
					(end 102.684072 -47.999904)
				)
				(xy 102.684072 -183.747156) (xy 102.938072 -183.747156)
				(arc
					(start 102.938072 -47.999904)
					(mid 103.798188 -46.803514)
					(end 105.206038 -47.237904)
				)
				(arc
					(start 142.793974 -47.237904)
					(mid 144.201748 -46.80374)
					(end 145.06194 -47.999904)
				)
				(arc
					(start 145.06194 -149.763734)
					(mid 145.068307 -149.818415)
					(end 145.087086 -149.87016)
				)
				(arc
					(start 149.70506 -159.106362)
					(mid 149.792801 -159.20237)
					(end 149.917912 -159.237934)
				)
				(arc
					(start 214.00008 -159.237934)
					(mid 215.246001 -159.754011)
					(end 215.762078 -160.999932)
				)
				(arc
					(start 215.762078 -193.000122)
					(mid 215.831786 -193.168412)
					(end 216.000076 -193.23812)
				)
				(arc
					(start 229.382066 -193.23812)
					(mid 229.507189 -193.202575)
					(end 229.594918 -193.106548)
				)
				(arc
					(start 234.212892 -183.870346)
					(mid 234.23165 -183.818596)
					(end 234.238038 -183.76392)
				)
				(arc
					(start 234.238038 -0.999998)
					(mid 234.16833 -0.831708)
					(end 234.00004 -0.762)
				)
				(arc
					(start 74.030078 -0.762)
					(mid 73.861788 -0.831708)
					(end 73.79208 -0.999998)
				)
				(arc
					(start 73.79208 -109.050074)
					(mid 73.276003 -110.295995)
					(end 72.030082 -110.812072)
				)
				(arc
					(start 31.530036 -110.812072)
					(mid 30.284115 -110.295995)
					(end 29.768038 -109.050074)
				)
				(arc
					(start 29.768038 -0.999998)
					(mid 29.69833 -0.831708)
					(end 29.53004 -0.762)
				)
			)
		)
	)
	(zone
		(layers "In3.Cu" "In4.Cu")
		(hatch none 0.5)
		(connect_pads
			(clearance 0)
		)
		(min_thickness 0.25)
		(keepout
			(tracks not_allowed)
			(vias allowed)
			(pads allowed)
			(copperpour not_allowed)
			(footprints allowed)
		)
		(placement
			(enabled no)
			(sheetname "")
		)
		(fill yes
			(thermal_gap 0.5)
			(thermal_bridge_width 0.5)
			(island_removal_mode 0)
		)
		(polygon
			(pts
				(arc
					(start 15.141448 -6.249924)
					(mid 13.358368 -6.249924)
					(end 15.141448 -6.249924)
				)
			)
		)
	)
	(zone
		(layers "In3.Cu" "In4.Cu")
		(hatch none 0.5)
		(connect_pads
			(clearance 0)
		)
		(min_thickness 0.25)
		(keepout
			(tracks not_allowed)
			(vias allowed)
			(pads allowed)
			(copperpour not_allowed)
			(footprints allowed)
		)
		(placement
			(enabled no)
			(sheetname "")
		)
		(fill yes
			(thermal_gap 0.5)
			(thermal_bridge_width 0.5)
			(island_removal_mode 0)
		)
		(polygon
			(pts
				(arc
					(start 27.141424 -8.750046)
					(mid 25.358344 -8.750046)
					(end 27.141424 -8.750046)
				)
			)
		)
	)
	(zone
		(net "P3V3_M2")
		(layer "In4.Cu")
		(hatch none 0.5)
		(connect_pads
			(clearance 0.5)
		)
		(min_thickness 0.25)
		(fill yes
			(thermal_gap 0.5)
			(thermal_bridge_width 0.5)
			(island_removal_mode 0)
		)
		(polygon
			(pts
				(xy 211.323682 -68.261484) (xy 201.315066 -78.2701)
				(arc
					(start 201.315066 -114.164872)
					(mid 201.300482 -114.237719)
					(end 201.259186 -114.299492)
				)
				(arc
					(start 200.779634 -114.779044)
					(mid 200.717885 -114.820396)
					(end 200.645014 -114.834924)
				)
				(xy 172.196506 -114.834924) (xy 170.7388 -116.29263) (xy 170.7388 -125.478032) (xy 171.627292 -126.366524)
				(xy 174.498762 -126.366524) (xy 178.661568 -130.52933) (xy 188.096906 -130.52933) (xy 189.607698 -132.040122)
				(xy 197.132956 -132.040122) (xy 198.967344 -130.205734) (xy 211.989162 -130.205734) (xy 212.733636 -130.950208)
				(xy 215.165432 -130.950208) (xy 216.624662 -129.490978) (xy 216.624662 -82.483452) (xy 222.338138 -76.769976)
				(xy 222.338138 -69.00672) (xy 221.592902 -68.261484)
			)
		)
	)
	(zone
		(net "P1V15_STBY")
		(layer "In4.Cu")
		(hatch none 0.5)
		(connect_pads
			(clearance 0.5)
		)
		(min_thickness 0.25)
		(fill yes
			(thermal_gap 0.5)
			(thermal_bridge_width 0.5)
			(island_removal_mode 0)
		)
		(polygon
			(pts
				(xy 40.607234 -132.33146) (xy 37.026596 -135.912098) (xy 37.026596 -140.590016) (xy 37.641784 -141.205204)
				(xy 43.949112 -141.205204) (xy 44.85132 -142.107412) (xy 44.85132 -149.159214)
				(arc
					(start 43.748452 -150.261828)
					(mid 43.686703 -150.30318)
					(end 43.613832 -150.317708)
				)
				(xy 32.107124 -150.317708) (xy 28.443936 -153.980896) (xy 28.443936 -161.3281) (xy 32.663384 -165.547548)
				(xy 65.148206 -165.547548) (xy 78.6257 -152.070054) (xy 78.6257 -138.889994) (xy 72.067166 -132.33146)
			)
		)
	)
	(zone
		(net "P5V_STBY")
		(layer "In4.Cu")
		(hatch none 0.5)
		(connect_pads
			(clearance 0.5)
		)
		(min_thickness 0.25)
		(fill yes
			(thermal_gap 0.5)
			(thermal_bridge_width 0.5)
			(island_removal_mode 0)
		)
		(polygon
			(pts
				(arc
					(start 78.229968 -1.27)
					(mid 78.211132 -1.310313)
					(end 78.183486 -1.345184)
				)
				(xy 77.867764 -1.66116) (xy 77.867764 -30.616906) (xy 81.742534 -34.491676) (xy 81.742534 -42.021506)
				(xy 80.599026 -43.165014) (xy 80.599026 -50.695352) (xy 81.171796 -51.268122) (xy 86.383114 -51.268122)
				(xy 87.741506 -49.90973) (xy 87.741506 -43.987974) (xy 89.215468 -42.514012) (xy 89.215468 -36.896294)
				(xy 93.356938 -32.754824) (xy 93.356938 -31.525464) (xy 92.28709 -30.455616) (xy 87.722456 -30.455616)
				(arc
					(start 84.544662 -27.277568)
					(mid 84.50331 -27.215819)
					(end 84.488782 -27.142948)
				)
				(xy 84.488782 -11.224514) (xy 89.88933 -5.823966) (xy 150.632414 -5.823966) (xy 152.618948 -7.8105)
				(xy 169.230294 -7.8105) (xy 174.056294 -12.6365) (xy 200.053956 -12.6365) (xy 217.071956 -29.6545)
				(xy 229.435406 -29.6545) (xy 230.415592 -28.674314) (xy 230.415592 -19.509486) (xy 229.638606 -18.7325)
				(xy 216.734136 -18.7325) (xy 206.168244 -8.166608) (xy 203.172314 -8.166608) (xy 199.234806 -4.2291)
				(xy 177.340006 -4.2291) (xy 175.9585 -2.847594) (xy 175.9585 -1.653794) (xy 175.574706 -1.27)
			)
		)
	)
	(zone
		(net "DDR_VREF")
		(layer "In4.Cu")
		(hatch none 0.5)
		(connect_pads
			(clearance 0.5)
		)
		(min_thickness 0.25)
		(fill yes
			(thermal_gap 0.5)
			(thermal_bridge_width 0.5)
			(island_removal_mode 0)
		)
		(polygon
			(pts
				(xy 17.68856 -133.870446) (xy 15.40256 -136.156446) (xy 15.40256 -139.805918) (xy 15.618714 -140.022072)
				(xy 16.039846 -140.022072) (xy 16.417798 -139.64412) (xy 16.417798 -135.711184) (xy 17.8562 -134.272782)
				(xy 26.73858 -134.272782) (xy 38.410642 -145.944844) (xy 43.169332 -145.944844) (xy 43.461432 -146.236944)
				(xy 43.461432 -147.505928) (xy 43.562524 -147.60702) (xy 43.951652 -147.60702) (xy 44.47032 -147.088352)
				(xy 44.47032 -146.045936) (xy 43.976036 -145.551652) (xy 38.605206 -145.551652) (xy 26.924 -133.870446)
			)
		)
	)
	(zone
		(net "GND")
		(layer "In4.Cu")
		(hatch none 0.5)
		(connect_pads
			(clearance 0.5)
		)
		(min_thickness 0.25)
		(fill yes
			(thermal_gap 0.5)
			(thermal_bridge_width 0.5)
			(island_removal_mode 0)
		)
		(polygon
			(pts
				(xy 1.27 -1.27) (xy 1.27 -183.700166) (xy 5.785104 -192.73012) (xy 97.914968 -192.73012) (xy 102.430072 -183.700166)
				(arc
					(start 102.430072 -47.999904)
					(mid 103.510621 -46.369619)
					(end 105.43286 -46.729904)
				)
				(arc
					(start 142.567152 -46.729904)
					(mid 144.489165 -46.369827)
					(end 145.56994 -47.99965)
				)
				(xy 145.56994 -47.999904) (xy 145.56994 -149.69998) (xy 150.08479 -158.729934)
				(arc
					(start 214.00008 -158.729934)
					(mid 215.605211 -159.394801)
					(end 216.270078 -160.999932)
				)
				(xy 216.270078 -192.73012) (xy 229.214934 -192.73012) (xy 233.730038 -183.700166) (xy 233.730038 -1.27)
				(xy 176.672494 -1.27) (xy 176.3395 -1.602994) (xy 176.3395 -2.689606) (xy 177.497994 -3.8481) (xy 199.392794 -3.8481)
				(xy 203.330302 -7.785608) (xy 206.326232 -7.785608) (xy 206.381858 -7.841234) (xy 206.381858 -7.841488)
				(xy 216.892124 -18.3515) (xy 229.796594 -18.3515) (xy 230.796592 -19.351498) (xy 230.796592 -28.832302)
				(xy 229.593394 -30.0355) (xy 216.913968 -30.0355) (xy 199.895968 -13.0175) (xy 173.898306 -13.0175)
				(xy 169.072306 -8.1915) (xy 152.46096 -8.1915) (xy 150.474426 -6.204966) (xy 90.047318 -6.204966)
				(xy 84.869782 -11.382502) (xy 84.869782 -27.063954) (xy 87.880444 -30.074616) (xy 92.445078 -30.074616)
				(xy 93.737938 -31.367476) (xy 93.737938 -32.912812) (xy 89.596468 -37.054282) (xy 89.596468 -42.672)
				(xy 88.122506 -44.145962)
				(arc
					(start 88.122506 -49.988724)
					(mid 88.107922 -50.061571)
					(end 88.066626 -50.123344)
				)
				(arc
					(start 86.596728 -51.593242)
					(mid 86.534979 -51.634594)
					(end 86.462108 -51.649122)
				)
				(xy 81.013808 -51.649122)
				(arc
					(start 80.273906 -50.908966)
					(mid 80.232554 -50.847217)
					(end 80.218026 -50.774346)
				)
				(xy 80.218026 -43.007026) (xy 81.361534 -41.863518) (xy 81.361534 -34.649664)
				(arc
					(start 77.542644 -30.83052)
					(mid 77.501292 -30.768771)
					(end 77.486764 -30.6959)
				)
				(xy 77.486764 -1.711452) (xy 77.461618 -1.686306) (xy 77.461618 -1.636268)
				(arc
					(start 77.158596 -1.332992)
					(mid 77.134474 -1.303602)
					(end 77.116686 -1.27)
				)
				(xy 74.30008 -1.27)
				(arc
					(start 74.30008 -109.050074)
					(mid 73.635213 -110.655205)
					(end 72.030082 -111.320072)
				)
				(arc
					(start 31.530036 -111.320072)
					(mid 29.924905 -110.655205)
					(end 29.260038 -109.050074)
				)
				(xy 29.260038 -1.27)
			)
		)
		(polygon
			(pts
				(arc
					(start 205.187296 -140.640308)
					(mid 204.648308 -140.640308)
					(end 204.648308 -141.179296)
				)
				(arc
					(start 205.276958 -141.807692)
					(mid 205.815756 -141.807883)
					(end 205.815946 -141.268958)
				)
			)
		)
		(polygon
			(pts
				(arc
					(start 200.488296 -140.640308)
					(mid 199.949308 -140.640308)
					(end 199.949308 -141.179296)
				)
				(arc
					(start 200.577958 -141.807692)
					(mid 201.116756 -141.807883)
					(end 201.116946 -141.268958)
				)
			)
		)
		(polygon
			(pts
				(arc
					(start 202.901296 -140.513308)
					(mid 202.362308 -140.513308)
					(end 202.362308 -141.052296)
				)
				(arc
					(start 202.990958 -141.680692)
					(mid 203.529756 -141.680883)
					(end 203.529946 -141.141958)
				)
			)
		)
		(polygon
			(pts
				(arc
					(start 198.075296 -140.386308)
					(mid 197.536308 -140.386308)
					(end 197.536308 -140.925296)
				)
				(arc
					(start 198.164958 -141.553692)
					(mid 198.703756 -141.553883)
					(end 198.703946 -141.014958)
				)
			)
		)
		(polygon
			(pts
				(arc
					(start 209.886296 -140.259308)
					(mid 209.347308 -140.259308)
					(end 209.347308 -140.798296)
				)
				(arc
					(start 209.975958 -141.426692)
					(mid 210.514756 -141.426883)
					(end 210.514946 -140.887958)
				)
			)
		)
		(polygon
			(pts
				(arc
					(start 195.408296 -140.132308)
					(mid 194.869308 -140.132308)
					(end 194.869308 -140.671296)
				)
				(arc
					(start 195.497958 -141.299692)
					(mid 196.036756 -141.299883)
					(end 196.036946 -140.760958)
				)
			)
		)
		(polygon
			(pts
				(arc
					(start 174.563786 -139.963398)
					(mid 174.024798 -139.963398)
					(end 174.024798 -140.502386)
				)
				(arc
					(start 174.653448 -141.130782)
					(mid 175.192246 -141.130973)
					(end 175.192436 -140.592048)
				)
			)
		)
		(polygon
			(pts
				(arc
					(start 180.274722 -139.89939)
					(mid 179.735734 -139.89939)
					(end 179.735734 -140.438378)
				)
				(arc
					(start 180.364384 -141.066774)
					(mid 180.903182 -141.066965)
					(end 180.903372 -140.52804)
				)
			)
		)
		(polygon
			(pts
				(arc
					(start 177.930556 -139.704318)
					(mid 177.391568 -139.704318)
					(end 177.391568 -140.243306)
				)
				(arc
					(start 178.020218 -140.871702)
					(mid 178.559016 -140.871893)
					(end 178.559206 -140.332968)
				)
			)
		)
		(polygon
			(pts
				(arc
					(start 185.354722 -139.41679)
					(mid 184.815734 -139.41679)
					(end 184.815734 -139.955778)
				)
				(arc
					(start 185.444384 -140.584174)
					(mid 185.983182 -140.584365)
					(end 185.983372 -140.04544)
				)
			)
		)
		(polygon
			(pts
				(arc
					(start 182.59806 -139.39393)
					(mid 182.059072 -139.39393)
					(end 182.059072 -139.932918)
				)
				(arc
					(start 182.687722 -140.561314)
					(mid 183.22652 -140.561505)
					(end 183.22671 -140.02258)
				)
			)
		)
		(polygon
			(pts
				(arc
					(start 206.711296 -138.989308)
					(mid 206.172308 -138.989308)
					(end 206.172308 -139.528296)
				)
				(arc
					(start 206.800958 -140.156692)
					(mid 207.339756 -140.156883)
					(end 207.339946 -139.617958)
				)
			)
		)
		(polygon
			(pts
				(arc
					(start 192.360296 -138.989308)
					(mid 191.821308 -138.989308)
					(end 191.821308 -139.528296)
				)
				(arc
					(start 192.449958 -140.156692)
					(mid 192.988756 -140.156883)
					(end 192.988946 -139.617958)
				)
			)
		)
		(polygon
			(pts
				(arc
					(start 213.602824 -138.607546)
					(mid 213.063836 -138.607546)
					(end 213.063836 -139.146534)
				)
				(arc
					(start 213.692486 -139.77493)
					(mid 214.231284 -139.775121)
					(end 214.231474 -139.236196)
				)
			)
		)
		(polygon
			(pts
				(arc
					(start 170.70959 -138.05154)
					(mid 170.170602 -138.05154)
					(end 170.170602 -138.590528)
				)
				(arc
					(start 170.799252 -139.218924)
					(mid 171.33805 -139.219115)
					(end 171.33824 -138.68019)
				)
			)
		)
		(polygon
			(pts
				(arc
					(start 174.213266 -137.655554)
					(mid 173.674278 -137.655554)
					(end 173.674278 -138.194542)
				)
				(arc
					(start 174.302928 -138.822938)
					(mid 174.841726 -138.823129)
					(end 174.841916 -138.284204)
				)
			)
		)
		(polygon
			(pts
				(arc
					(start 167.381428 -136.636506)
					(mid 166.84244 -136.636506)
					(end 166.84244 -137.175494)
				)
				(arc
					(start 167.47109 -137.80389)
					(mid 168.009888 -137.804081)
					(end 168.010078 -137.265156)
				)
			)
		)
		(polygon
			(pts
				(arc
					(start 183.905398 -133.354826)
					(mid 184.286144 -132.973699)
					(end 183.905144 -132.592826)
				)
				(arc
					(start 183.016144 -132.592826)
					(mid 182.635144 -132.973826)
					(end 183.016144 -133.354826)
				)
			)
		)
		(polygon
			(pts
				(xy 72.145144 -131.95046)
				(arc
					(start 40.529002 -131.95046)
					(mid 40.455182 -131.965237)
					(end 40.392604 -132.007102)
				)
				(xy 36.645596 -135.75411) (xy 36.645596 -140.748004) (xy 37.483796 -141.586204) (xy 43.791124 -141.586204)
				(xy 44.47032 -142.2654) (xy 44.47032 -144.674336) (xy 43.974004 -145.170652) (xy 38.763194 -145.170652)
				(xy 27.081988 -133.489446) (xy 17.530572 -133.489446) (xy 15.02156 -135.998458) (xy 15.02156 -139.963906)
				(xy 15.460726 -140.403072) (xy 16.197834 -140.403072) (xy 16.798798 -139.802108) (xy 16.798798 -135.869172)
				(xy 18.014188 -134.653782) (xy 26.580592 -134.653782) (xy 38.252654 -146.325844) (xy 43.011344 -146.325844)
				(xy 43.080432 -146.394932) (xy 43.080432 -147.663916) (xy 43.404536 -147.98802) (xy 43.960796 -147.98802)
				(xy 44.47032 -148.497544) (xy 44.47032 -149.001226) (xy 43.534838 -149.936708) (xy 31.949136 -149.936708)
				(xy 28.062936 -153.822908) (xy 28.062936 -161.486088) (xy 32.505396 -165.928548) (xy 65.306194 -165.928548)
				(xy 79.0067 -152.228042) (xy 79.0067 -138.732006)
				(arc
					(start 72.281796 -132.007102)
					(mid 72.220402 -131.965696)
					(end 72.147938 -131.95046)
				)
			)
		)
		(polygon
			(pts
				(arc
					(start 83.741768 -94.492572)
					(mid 83.358228 -94.109032)
					(end 82.974688 -94.492572)
				)
				(arc
					(start 82.974688 -95.381826)
					(mid 83.358355 -95.765112)
					(end 83.741768 -95.381572)
				)
			)
		)
		(polygon
			(pts
				(arc
					(start 77.667358 -92.911168)
					(mid 77.283818 -92.527628)
					(end 76.900278 -92.911168)
				)
				(arc
					(start 76.900278 -93.800422)
					(mid 77.283945 -94.183708)
					(end 77.667358 -93.800168)
				)
			)
		)
		(polygon
			(pts
				(arc
					(start 85.367368 -91.306396)
					(mid 84.983828 -90.922856)
					(end 84.600288 -91.306396)
				)
				(arc
					(start 84.600288 -92.19565)
					(mid 84.983955 -92.578936)
					(end 85.367368 -92.195396)
				)
			)
		)
		(polygon
			(pts
				(arc
					(start 78.505558 -89.710768)
					(mid 78.122018 -89.327228)
					(end 77.738478 -89.710768)
				)
				(arc
					(start 77.738478 -90.600022)
					(mid 78.122145 -90.983308)
					(end 78.505558 -90.599768)
				)
			)
		)
		(polygon
			(pts
				(arc
					(start 83.743038 -88.091264)
					(mid 83.359498 -87.707724)
					(end 82.975958 -88.091264)
				)
				(arc
					(start 82.975958 -88.980518)
					(mid 83.359625 -89.363804)
					(end 83.743038 -88.980264)
				)
			)
		)
		(polygon
			(pts
				(arc
					(start 77.667358 -86.510368)
					(mid 77.283818 -86.126828)
					(end 76.900278 -86.510368)
				)
				(arc
					(start 76.900278 -87.399622)
					(mid 77.283945 -87.782908)
					(end 77.667358 -87.399368)
				)
			)
		)
		(polygon
			(pts
				(arc
					(start 85.367368 -84.892134)
					(mid 84.983828 -84.508594)
					(end 84.600288 -84.892134)
				)
				(arc
					(start 84.600288 -85.781388)
					(mid 84.983955 -86.164674)
					(end 85.367368 -85.781134)
				)
			)
		)
		(polygon
			(pts
				(arc
					(start 78.505558 -83.309968)
					(mid 78.122018 -82.926428)
					(end 77.738478 -83.309968)
				)
				(arc
					(start 77.738478 -84.199222)
					(mid 78.122145 -84.582508)
					(end 78.505558 -84.198968)
				)
			)
		)
		(polygon
			(pts
				(arc
					(start 83.741768 -81.692496)
					(mid 83.358228 -81.308956)
					(end 82.974688 -81.692496)
				)
				(arc
					(start 82.974688 -82.58175)
					(mid 83.358355 -82.965036)
					(end 83.741768 -82.581496)
				)
			)
		)
		(polygon
			(pts
				(arc
					(start 77.667358 -80.109568)
					(mid 77.283818 -79.726028)
					(end 76.900278 -80.109568)
				)
				(arc
					(start 76.900278 -80.998822)
					(mid 77.283945 -81.382108)
					(end 77.667358 -80.998568)
				)
			)
		)
		(polygon
			(pts
				(arc
					(start 85.370162 -78.507336)
					(mid 84.986622 -78.123796)
					(end 84.603082 -78.507336)
				)
				(arc
					(start 84.603082 -79.39659)
					(mid 84.986749 -79.779876)
					(end 85.370162 -79.396336)
				)
			)
		)
		(polygon
			(pts
				(arc
					(start 78.505558 -76.909168)
					(mid 78.122018 -76.525628)
					(end 77.738478 -76.909168)
				)
				(arc
					(start 77.738478 -77.798422)
					(mid 78.122145 -78.181708)
					(end 78.505558 -77.798168)
				)
			)
		)
		(polygon
			(pts
				(arc
					(start 83.741768 -75.305158)
					(mid 83.358228 -74.921618)
					(end 82.974688 -75.305158)
				)
				(arc
					(start 82.974688 -76.194412)
					(mid 83.358355 -76.577698)
					(end 83.741768 -76.194158)
				)
			)
		)
		(polygon
			(pts
				(arc
					(start 77.667358 -73.708768)
					(mid 77.283818 -73.325228)
					(end 76.900278 -73.708768)
				)
				(arc
					(start 76.900278 -74.598022)
					(mid 77.283945 -74.981308)
					(end 77.667358 -74.597768)
				)
			)
		)
		(polygon
			(pts
				(arc
					(start 85.246718 -72.098916)
					(mid 84.863178 -71.715376)
					(end 84.479638 -72.098916)
				)
				(arc
					(start 84.479638 -72.98817)
					(mid 84.863305 -73.371456)
					(end 85.246718 -72.987916)
				)
			)
		)
		(polygon
			(pts
				(arc
					(start 78.505558 -70.508368)
					(mid 78.122018 -70.124828)
					(end 77.738478 -70.508368)
				)
				(arc
					(start 77.738478 -71.397622)
					(mid 78.122145 -71.780908)
					(end 78.505558 -71.397368)
				)
			)
		)
		(polygon
			(pts
				(xy 221.681548 -67.880484) (xy 221.66199 -67.880484) (xy 211.165694 -67.880484) (xy 211.110068 -67.93611)
				(xy 211.110068 -67.936364)
				(arc
					(start 200.989946 -78.056486)
					(mid 200.948594 -78.118235)
					(end 200.934066 -78.191106)
				)
				(xy 200.934066 -114.085878) (xy 200.56602 -114.453924)
				(arc
					(start 172.117512 -114.453924)
					(mid 172.044665 -114.468508)
					(end 171.982892 -114.509804)
				)
				(arc
					(start 170.41368 -116.079016)
					(mid 170.372328 -116.140765)
					(end 170.3578 -116.213636)
				)
				(xy 170.3578 -125.63602) (xy 171.469304 -126.747524) (xy 174.340774 -126.747524)
				(arc
					(start 178.447954 -130.85445)
					(mid 178.509703 -130.895802)
					(end 178.582574 -130.91033)
				)
				(xy 187.938918 -130.91033) (xy 189.44971 -132.421122) (xy 197.290944 -132.421122) (xy 199.125332 -130.586734)
				(xy 211.831174 -130.586734) (xy 212.575648 -131.331208) (xy 215.32342 -131.331208) (xy 217.005662 -129.648966)
				(xy 217.005662 -82.64144) (xy 222.719138 -76.927964) (xy 222.719138 -68.848732) (xy 221.813628 -67.943222)
				(xy 221.799658 -67.929506) (xy 221.75089 -67.880484)
			)
		)
		(polygon
			(pts
				(arc
					(start 77.738732 -67.312032)
					(mid 77.355192 -66.928492)
					(end 76.971652 -67.312032)
				)
				(arc
					(start 76.971652 -68.201286)
					(mid 77.355319 -68.584572)
					(end 77.738732 -68.201032)
				)
			)
		)
		(polygon
			(pts
				(arc
					(start 141.785086 -42.800016)
					(mid 141.299946 -42.314876)
					(end 140.814806 -42.800016)
				)
				(arc
					(start 140.814806 -44.200318)
					(mid 141.300073 -44.685204)
					(end 141.785086 -44.200064)
				)
			)
		)
		(polygon
			(pts
				(arc
					(start 134.585202 -42.800016)
					(mid 134.100062 -42.314876)
					(end 133.614922 -42.800016)
				)
				(arc
					(start 133.614922 -44.200318)
					(mid 134.100189 -44.685204)
					(end 134.585202 -44.200064)
				)
			)
		)
		(polygon
			(pts
				(arc
					(start 120.18518 -42.800016)
					(mid 119.70004 -42.314876)
					(end 119.2149 -42.800016)
				)
				(arc
					(start 119.2149 -44.200318)
					(mid 119.700167 -44.685204)
					(end 120.18518 -44.200064)
				)
			)
		)
		(polygon
			(pts
				(arc
					(start 139.984988 -36.800028)
					(mid 139.499848 -36.314888)
					(end 139.014708 -36.800028)
				)
				(arc
					(start 139.014708 -38.20033)
					(mid 139.499975 -38.685216)
					(end 139.984988 -38.200076)
				)
			)
		)
		(polygon
			(pts
				(arc
					(start 136.385046 -36.800028)
					(mid 135.899906 -36.314888)
					(end 135.414766 -36.800028)
				)
				(arc
					(start 135.414766 -38.20033)
					(mid 135.900033 -38.685216)
					(end 136.385046 -38.200076)
				)
			)
		)
		(polygon
			(pts
				(arc
					(start 132.785104 -36.800028)
					(mid 132.299964 -36.314888)
					(end 131.814824 -36.800028)
				)
				(arc
					(start 131.814824 -38.20033)
					(mid 132.300091 -38.685216)
					(end 132.785104 -38.200076)
				)
			)
		)
		(polygon
			(pts
				(arc
					(start 129.185162 -36.800028)
					(mid 128.700022 -36.314888)
					(end 128.214882 -36.800028)
				)
				(arc
					(start 128.214882 -38.20033)
					(mid 128.700149 -38.685216)
					(end 129.185162 -38.200076)
				)
			)
		)
		(polygon
			(pts
				(arc
					(start 118.385082 -36.800028)
					(mid 117.899942 -36.314888)
					(end 117.414802 -36.800028)
				)
				(arc
					(start 117.414802 -38.20033)
					(mid 117.900069 -38.685216)
					(end 118.385082 -38.200076)
				)
			)
		)
		(polygon
			(pts
				(arc
					(start 114.78514 -36.800028)
					(mid 114.3 -36.314888)
					(end 113.81486 -36.800028)
				)
				(arc
					(start 113.81486 -38.20033)
					(mid 114.300127 -38.685216)
					(end 114.78514 -38.200076)
				)
			)
		)
		(polygon
			(pts
				(arc
					(start 111.185198 -36.800028)
					(mid 110.700058 -36.314888)
					(end 110.214918 -36.800028)
				)
				(arc
					(start 110.214918 -38.20033)
					(mid 110.700185 -38.685216)
					(end 111.185198 -38.200076)
				)
			)
		)
		(polygon
			(pts
				(arc
					(start 107.585002 -36.800028)
					(mid 107.099862 -36.314888)
					(end 106.614722 -36.800028)
				)
				(arc
					(start 106.614722 -38.20033)
					(mid 107.099989 -38.685216)
					(end 107.585002 -38.200076)
				)
			)
		)
		(polygon
			(pts
				(arc
					(start 141.785086 -35.600132)
					(mid 141.299946 -35.114992)
					(end 140.814806 -35.600132)
				)
				(arc
					(start 140.814806 -37.000434)
					(mid 141.300073 -37.48532)
					(end 141.785086 -37.00018)
				)
			)
		)
		(polygon
			(pts
				(arc
					(start 138.185144 -35.600132)
					(mid 137.700004 -35.114992)
					(end 137.214864 -35.600132)
				)
				(arc
					(start 137.214864 -37.000434)
					(mid 137.700131 -37.48532)
					(end 138.185144 -37.00018)
				)
			)
		)
		(polygon
			(pts
				(arc
					(start 134.585202 -35.600132)
					(mid 134.100062 -35.114992)
					(end 133.614922 -35.600132)
				)
				(arc
					(start 133.614922 -37.000434)
					(mid 134.100189 -37.48532)
					(end 134.585202 -37.00018)
				)
			)
		)
		(polygon
			(pts
				(arc
					(start 130.985006 -35.600132)
					(mid 130.499866 -35.114992)
					(end 130.014726 -35.600132)
				)
				(arc
					(start 130.014726 -37.000434)
					(mid 130.499993 -37.48532)
					(end 130.985006 -37.00018)
				)
			)
		)
		(polygon
			(pts
				(arc
					(start 120.18518 -35.600132)
					(mid 119.70004 -35.114992)
					(end 119.2149 -35.600132)
				)
				(arc
					(start 119.2149 -37.000434)
					(mid 119.700167 -37.48532)
					(end 120.18518 -37.00018)
				)
			)
		)
		(polygon
			(pts
				(arc
					(start 116.584984 -35.600132)
					(mid 116.099844 -35.114992)
					(end 115.614704 -35.600132)
				)
				(arc
					(start 115.614704 -37.000434)
					(mid 116.099971 -37.48532)
					(end 116.584984 -37.00018)
				)
			)
		)
		(polygon
			(pts
				(arc
					(start 112.985042 -35.600132)
					(mid 112.499902 -35.114992)
					(end 112.014762 -35.600132)
				)
				(arc
					(start 112.014762 -37.000434)
					(mid 112.500029 -37.48532)
					(end 112.985042 -37.00018)
				)
			)
		)
		(polygon
			(pts
				(arc
					(start 109.3851 -35.600132)
					(mid 108.89996 -35.114992)
					(end 108.41482 -35.600132)
				)
				(arc
					(start 108.41482 -37.000434)
					(mid 108.900087 -37.48532)
					(end 109.3851 -37.00018)
				)
			)
		)
		(polygon
			(pts
				(arc
					(start 139.984988 -33.199832)
					(mid 139.499721 -32.714946)
					(end 139.014708 -33.200086)
				)
				(arc
					(start 139.014708 -34.600134)
					(mid 139.499848 -35.085274)
					(end 139.984988 -34.600134)
				)
			)
		)
		(polygon
			(pts
				(arc
					(start 136.385046 -33.199832)
					(mid 135.899779 -32.714946)
					(end 135.414766 -33.200086)
				)
				(arc
					(start 135.414766 -34.600134)
					(mid 135.899906 -35.085274)
					(end 136.385046 -34.600134)
				)
			)
		)
		(polygon
			(pts
				(arc
					(start 132.785104 -33.199832)
					(mid 132.299837 -32.714946)
					(end 131.814824 -33.200086)
				)
				(arc
					(start 131.814824 -34.600134)
					(mid 132.299964 -35.085274)
					(end 132.785104 -34.600134)
				)
			)
		)
		(polygon
			(pts
				(arc
					(start 129.185162 -33.199832)
					(mid 128.699895 -32.714946)
					(end 128.214882 -33.200086)
				)
				(arc
					(start 128.214882 -34.600134)
					(mid 128.700022 -35.085274)
					(end 129.185162 -34.600134)
				)
			)
		)
		(polygon
			(pts
				(arc
					(start 118.385082 -33.199832)
					(mid 117.899815 -32.714946)
					(end 117.414802 -33.200086)
				)
				(arc
					(start 117.414802 -34.600134)
					(mid 117.899942 -35.085274)
					(end 118.385082 -34.600134)
				)
			)
		)
		(polygon
			(pts
				(arc
					(start 114.78514 -33.199832)
					(mid 114.299873 -32.714946)
					(end 113.81486 -33.200086)
				)
				(arc
					(start 113.81486 -34.600134)
					(mid 114.3 -35.085274)
					(end 114.78514 -34.600134)
				)
			)
		)
		(polygon
			(pts
				(arc
					(start 111.185198 -33.199832)
					(mid 110.699931 -32.714946)
					(end 110.214918 -33.200086)
				)
				(arc
					(start 110.214918 -34.600134)
					(mid 110.700058 -35.085274)
					(end 111.185198 -34.600134)
				)
			)
		)
		(polygon
			(pts
				(arc
					(start 107.585002 -33.199832)
					(mid 107.099735 -32.714946)
					(end 106.614722 -33.200086)
				)
				(arc
					(start 106.614722 -34.600134)
					(mid 107.099862 -35.085274)
					(end 107.585002 -34.600134)
				)
			)
		)
		(polygon
			(pts
				(arc
					(start 141.785086 -32.00019)
					(mid 141.299946 -31.51505)
					(end 140.814806 -32.00019)
				)
				(arc
					(start 140.814806 -33.400238)
					(mid 141.300073 -33.885124)
					(end 141.785086 -33.399984)
				)
			)
		)
		(polygon
			(pts
				(arc
					(start 138.185144 -32.00019)
					(mid 137.700004 -31.51505)
					(end 137.214864 -32.00019)
				)
				(arc
					(start 137.214864 -33.400238)
					(mid 137.700131 -33.885124)
					(end 138.185144 -33.399984)
				)
			)
		)
		(polygon
			(pts
				(arc
					(start 134.585202 -32.00019)
					(mid 134.100062 -31.51505)
					(end 133.614922 -32.00019)
				)
				(arc
					(start 133.614922 -33.400238)
					(mid 134.100189 -33.885124)
					(end 134.585202 -33.399984)
				)
			)
		)
		(polygon
			(pts
				(arc
					(start 130.985006 -32.00019)
					(mid 130.499866 -31.51505)
					(end 130.014726 -32.00019)
				)
				(arc
					(start 130.014726 -33.400238)
					(mid 130.499993 -33.885124)
					(end 130.985006 -33.399984)
				)
			)
		)
		(polygon
			(pts
				(arc
					(start 120.18518 -32.00019)
					(mid 119.70004 -31.51505)
					(end 119.2149 -32.00019)
				)
				(arc
					(start 119.2149 -33.400238)
					(mid 119.700167 -33.885124)
					(end 120.18518 -33.399984)
				)
			)
		)
		(polygon
			(pts
				(arc
					(start 116.584984 -32.00019)
					(mid 116.099844 -31.51505)
					(end 115.614704 -32.00019)
				)
				(arc
					(start 115.614704 -33.400238)
					(mid 116.099971 -33.885124)
					(end 116.584984 -33.399984)
				)
			)
		)
		(polygon
			(pts
				(arc
					(start 112.985042 -32.00019)
					(mid 112.499902 -31.51505)
					(end 112.014762 -32.00019)
				)
				(arc
					(start 112.014762 -33.400238)
					(mid 112.500029 -33.885124)
					(end 112.985042 -33.399984)
				)
			)
		)
		(polygon
			(pts
				(arc
					(start 109.3851 -32.00019)
					(mid 108.89996 -31.51505)
					(end 108.41482 -32.00019)
				)
				(arc
					(start 108.41482 -33.400238)
					(mid 108.900087 -33.885124)
					(end 109.3851 -33.399984)
				)
			)
		)
		(polygon
			(pts
				(arc
					(start 129.535428 -26.592276)
					(mid 129.916174 -26.211149)
					(end 129.535174 -25.830276)
				)
				(arc
					(start 128.467866 -25.830276)
					(mid 128.086866 -26.211276)
					(end 128.467866 -26.592276)
				)
			)
		)
	)
	(zone
		(layer "In5.Cu")
		(hatch none 0.5)
		(connect_pads
			(clearance 0)
		)
		(min_thickness 0.25)
		(keepout
			(tracks not_allowed)
			(vias allowed)
			(pads allowed)
			(copperpour not_allowed)
			(footprints allowed)
		)
		(placement
			(enabled no)
			(sheetname "")
		)
		(fill
			(thermal_gap 0.5)
			(thermal_bridge_width 0.5)
			(island_removal_mode 0)
		)
		(polygon
			(pts
				(arc
					(start 139.984988 -36.800028)
					(mid 139.499848 -36.314888)
					(end 139.014708 -36.800028)
				)
				(xy 139.014708 -37.252402)
				(arc
					(start 139.345924 -37.252402)
					(mid 139.395029 -37.232825)
					(end 139.417298 -37.184838)
				)
				(arc
					(start 139.417298 -37.184838)
					(mid 139.500879 -36.406357)
					(end 139.582398 -37.185092)
				)
				(xy 139.582398 -37.215318)
				(arc
					(start 139.57935 -37.218112)
					(mid 139.513051 -37.348155)
					(end 139.383008 -37.414454)
				)
				(xy 139.380214 -37.417502) (xy 139.014708 -37.417502) (xy 139.014708 -37.582602) (xy 139.380214 -37.582602)
				(arc
					(start 139.383008 -37.58565)
					(mid 139.513051 -37.651949)
					(end 139.57935 -37.781992)
				)
				(xy 139.582398 -37.784786)
				(arc
					(start 139.582398 -37.815012)
					(mid 139.500879 -38.593783)
					(end 139.417298 -37.815266)
				)
				(arc
					(start 139.417298 -37.815266)
					(mid 139.395099 -37.767206)
					(end 139.345924 -37.747702)
				)
				(xy 139.014708 -37.747702)
				(arc
					(start 139.014708 -38.199822)
					(mid 139.499721 -38.685216)
					(end 139.984988 -38.200076)
				)
			)
		)
	)
	(zone
		(layer "In5.Cu")
		(hatch none 0.5)
		(connect_pads
			(clearance 0)
		)
		(min_thickness 0.25)
		(keepout
			(tracks not_allowed)
			(vias allowed)
			(pads allowed)
			(copperpour not_allowed)
			(footprints allowed)
		)
		(placement
			(enabled no)
			(sheetname "")
		)
		(fill
			(thermal_gap 0.5)
			(thermal_bridge_width 0.5)
			(island_removal_mode 0)
		)
		(polygon
			(pts
				(xy 31.2166 -132.8293) (xy 31.2166 -130.2131) (xy 35.0266 -130.2131) (xy 35.0266 -132.8293)
			)
		)
	)
	(zone
		(layer "In5.Cu")
		(hatch none 0.5)
		(connect_pads
			(clearance 0)
		)
		(min_thickness 0.25)
		(keepout
			(tracks not_allowed)
			(vias allowed)
			(pads allowed)
			(copperpour not_allowed)
			(footprints allowed)
		)
		(placement
			(enabled no)
			(sheetname "")
		)
		(fill
			(thermal_gap 0.5)
			(thermal_bridge_width 0.5)
			(island_removal_mode 0)
		)
		(polygon
			(pts
				(arc
					(start 109.3851 -35.600132)
					(mid 108.89996 -35.114992)
					(end 108.41482 -35.600132)
				)
				(xy 108.41482 -36.052506)
				(arc
					(start 108.746036 -36.052506)
					(mid 108.795141 -36.032929)
					(end 108.81741 -35.984942)
				)
				(arc
					(start 108.81741 -35.984942)
					(mid 108.900991 -35.206461)
					(end 108.98251 -35.985196)
				)
				(xy 108.98251 -36.015422)
				(arc
					(start 108.979462 -36.018216)
					(mid 108.913163 -36.148259)
					(end 108.78312 -36.214558)
				)
				(xy 108.780326 -36.217606) (xy 108.41482 -36.217606) (xy 108.41482 -36.382706) (xy 108.780326 -36.382706)
				(arc
					(start 108.78312 -36.385754)
					(mid 108.913163 -36.452053)
					(end 108.979462 -36.582096)
				)
				(xy 108.98251 -36.58489)
				(arc
					(start 108.98251 -36.615116)
					(mid 108.900991 -37.393887)
					(end 108.81741 -36.61537)
				)
				(arc
					(start 108.81741 -36.61537)
					(mid 108.795211 -36.56731)
					(end 108.746036 -36.547806)
				)
				(xy 108.41482 -36.547806)
				(arc
					(start 108.41482 -36.999926)
					(mid 108.899833 -37.48532)
					(end 109.3851 -37.00018)
				)
			)
		)
	)
	(zone
		(layer "In5.Cu")
		(hatch none 0.5)
		(connect_pads
			(clearance 0)
		)
		(min_thickness 0.25)
		(keepout
			(tracks not_allowed)
			(vias allowed)
			(pads allowed)
			(copperpour not_allowed)
			(footprints allowed)
		)
		(placement
			(enabled no)
			(sheetname "")
		)
		(fill
			(thermal_gap 0.5)
			(thermal_bridge_width 0.5)
			(island_removal_mode 0)
		)
		(polygon
			(pts
				(arc
					(start 85.244178 -72.09917)
					(mid 84.863305 -71.717916)
					(end 84.482178 -72.098916)
				)
				(arc
					(start 84.482178 -72.987916)
					(mid 84.863178 -73.368916)
					(end 85.244178 -72.987916)
				)
				(xy 85.244178 -72.791066) (xy 85.176868 -72.791066)
				(arc
					(start 85.100922 -72.867012)
					(mid 84.674578 -73.176516)
					(end 84.984082 -72.750172)
				)
				(xy 85.060028 -72.674226) (xy 85.108288 -72.625966) (xy 85.176868 -72.625966) (xy 85.244178 -72.625966)
				(xy 85.244178 -72.460866) (xy 85.176868 -72.460866) (xy 85.108288 -72.460866) (xy 85.060028 -72.412606)
				(arc
					(start 84.984082 -72.33666)
					(mid 84.674578 -71.910316)
					(end 85.100922 -72.21982)
				)
				(xy 85.176868 -72.295766) (xy 85.244178 -72.295766)
			)
		)
	)
	(zone
		(layer "In5.Cu")
		(hatch none 0.5)
		(connect_pads
			(clearance 0)
		)
		(min_thickness 0.25)
		(keepout
			(tracks not_allowed)
			(vias allowed)
			(pads allowed)
			(copperpour not_allowed)
			(footprints allowed)
		)
		(placement
			(enabled no)
			(sheetname "")
		)
		(fill
			(thermal_gap 0.5)
			(thermal_bridge_width 0.5)
			(island_removal_mode 0)
		)
		(polygon
			(pts
				(arc
					(start 132.785104 -36.800028)
					(mid 132.299964 -36.314888)
					(end 131.814824 -36.800028)
				)
				(xy 131.814824 -37.252402)
				(arc
					(start 132.14604 -37.252402)
					(mid 132.195145 -37.232825)
					(end 132.217414 -37.184838)
				)
				(arc
					(start 132.217414 -37.184838)
					(mid 132.300995 -36.406357)
					(end 132.382514 -37.185092)
				)
				(xy 132.382514 -37.215318)
				(arc
					(start 132.379466 -37.218112)
					(mid 132.313167 -37.348155)
					(end 132.183124 -37.414454)
				)
				(xy 132.18033 -37.417502) (xy 131.814824 -37.417502) (xy 131.814824 -37.582602) (xy 132.18033 -37.582602)
				(arc
					(start 132.183124 -37.58565)
					(mid 132.313167 -37.651949)
					(end 132.379466 -37.781992)
				)
				(xy 132.382514 -37.784786)
				(arc
					(start 132.382514 -37.815012)
					(mid 132.300995 -38.593783)
					(end 132.217414 -37.815266)
				)
				(arc
					(start 132.217414 -37.815266)
					(mid 132.195215 -37.767206)
					(end 132.14604 -37.747702)
				)
				(xy 131.814824 -37.747702)
				(arc
					(start 131.814824 -38.199822)
					(mid 132.299837 -38.685216)
					(end 132.785104 -38.200076)
				)
			)
		)
	)
	(zone
		(net "GND")
		(layer "In5.Cu")
		(hatch none 0.5)
		(connect_pads
			(clearance 0.5)
		)
		(min_thickness 0.25)
		(fill yes
			(thermal_gap 0.5)
			(thermal_bridge_width 0.5)
			(island_removal_mode 0)
		)
		(polygon
			(pts
				(xy 179.93868 -38.21938) (xy 208.336896 -38.21938) (xy 209.139282 -37.416994) (xy 209.139282 -13.391642)
				(xy 207.48498 -11.73734) (xy 177.006758 -11.73734) (xy 174.893986 -13.850112) (xy 174.893986 -27.508962)
				(xy 174.43577 -27.967178) (xy 174.43577 -32.71647)
			)
		)
	)
	(zone
		(layer "In5.Cu")
		(hatch none 0.5)
		(connect_pads
			(clearance 0)
		)
		(min_thickness 0.25)
		(keepout
			(tracks not_allowed)
			(vias allowed)
			(pads allowed)
			(copperpour not_allowed)
			(footprints allowed)
		)
		(placement
			(enabled no)
			(sheetname "")
		)
		(fill
			(thermal_gap 0.5)
			(thermal_bridge_width 0.5)
			(island_removal_mode 0)
		)
		(polygon
			(pts
				(arc
					(start 128.467866 -25.830276)
					(mid 128.086866 -26.211276)
					(end 128.467866 -26.592276)
				)
				(arc
					(start 129.53492 -26.592276)
					(mid 129.916174 -26.211403)
					(end 129.535174 -25.830276)
				)
				(xy 129.24917 -25.830276)
				(arc
					(start 129.24917 -25.92578)
					(mid 129.264756 -26.003776)
					(end 129.309114 -26.069798)
				)
				(arc
					(start 129.309114 -26.069798)
					(mid 129.795763 -26.267957)
					(end 129.27076 -26.246074)
				)
				(arc
					(start 129.27076 -26.246074)
					(mid 129.143607 -26.126529)
					(end 129.085848 -25.961848)
				)
				(xy 129.08407 -25.96007) (xy 129.08407 -25.830276) (xy 128.91897 -25.830276) (xy 128.91897 -25.96007)
				(arc
					(start 128.917192 -25.961848)
					(mid 128.859405 -26.126511)
					(end 128.73228 -26.246074)
				)
				(arc
					(start 128.73228 -26.246074)
					(mid 128.207266 -26.26796)
					(end 128.693926 -26.069798)
				)
				(arc
					(start 128.693926 -26.069798)
					(mid 128.738292 -26.003779)
					(end 128.75387 -25.92578)
				)
				(xy 128.75387 -25.830276)
			)
		)
	)
	(zone
		(layer "In5.Cu")
		(hatch none 0.5)
		(connect_pads
			(clearance 0)
		)
		(min_thickness 0.25)
		(keepout
			(tracks not_allowed)
			(vias allowed)
			(pads allowed)
			(copperpour not_allowed)
			(footprints allowed)
		)
		(placement
			(enabled no)
			(sheetname "")
		)
		(fill
			(thermal_gap 0.5)
			(thermal_bridge_width 0.5)
			(island_removal_mode 0)
		)
		(polygon
			(pts
				(arc
					(start 83.739228 -81.69275)
					(mid 83.358355 -81.311496)
					(end 82.977228 -81.692496)
				)
				(arc
					(start 82.977228 -82.581496)
					(mid 83.358228 -82.962496)
					(end 83.739228 -82.581496)
				)
				(xy 83.739228 -82.37855) (xy 83.678014 -82.37855)
				(arc
					(start 83.595972 -82.460592)
					(mid 83.169628 -82.770096)
					(end 83.479132 -82.343752)
				)
				(xy 83.561174 -82.26171) (xy 83.609434 -82.21345) (xy 83.678014 -82.21345) (xy 83.739228 -82.21345)
				(xy 83.739228 -82.04835) (xy 83.665822 -82.04835) (xy 83.597242 -82.04835) (xy 83.548982 -82.00009)
				(arc
					(start 83.479132 -81.93024)
					(mid 83.169628 -81.503896)
					(end 83.595972 -81.8134)
				)
				(xy 83.665822 -81.88325) (xy 83.739228 -81.88325)
			)
		)
	)
	(zone
		(layer "In5.Cu")
		(hatch none 0.5)
		(connect_pads
			(clearance 0)
		)
		(min_thickness 0.25)
		(keepout
			(tracks not_allowed)
			(vias allowed)
			(pads allowed)
			(copperpour not_allowed)
			(footprints allowed)
		)
		(placement
			(enabled no)
			(sheetname "")
		)
		(fill
			(thermal_gap 0.5)
			(thermal_bridge_width 0.5)
			(island_removal_mode 0)
		)
		(polygon
			(pts
				(arc
					(start 138.185144 -35.600132)
					(mid 137.700004 -35.114992)
					(end 137.214864 -35.600132)
				)
				(xy 137.214864 -36.052506)
				(arc
					(start 137.54608 -36.052506)
					(mid 137.595185 -36.032929)
					(end 137.617454 -35.984942)
				)
				(arc
					(start 137.617454 -35.984942)
					(mid 137.701035 -35.206461)
					(end 137.782554 -35.985196)
				)
				(xy 137.782554 -36.015422)
				(arc
					(start 137.779506 -36.018216)
					(mid 137.713207 -36.148259)
					(end 137.583164 -36.214558)
				)
				(xy 137.58037 -36.217606) (xy 137.214864 -36.217606) (xy 137.214864 -36.382706) (xy 137.58037 -36.382706)
				(arc
					(start 137.583164 -36.385754)
					(mid 137.713207 -36.452053)
					(end 137.779506 -36.582096)
				)
				(xy 137.782554 -36.58489)
				(arc
					(start 137.782554 -36.615116)
					(mid 137.701035 -37.393887)
					(end 137.617454 -36.61537)
				)
				(arc
					(start 137.617454 -36.61537)
					(mid 137.595255 -36.56731)
					(end 137.54608 -36.547806)
				)
				(xy 137.214864 -36.547806)
				(arc
					(start 137.214864 -36.999926)
					(mid 137.699877 -37.48532)
					(end 138.185144 -37.00018)
				)
			)
		)
	)
	(zone
		(layer "In5.Cu")
		(hatch none 0.5)
		(connect_pads
			(clearance 0)
		)
		(min_thickness 0.25)
		(keepout
			(tracks not_allowed)
			(vias allowed)
			(pads allowed)
			(copperpour not_allowed)
			(footprints allowed)
		)
		(placement
			(enabled no)
			(sheetname "")
		)
		(fill
			(thermal_gap 0.5)
			(thermal_bridge_width 0.5)
			(island_removal_mode 0)
		)
		(polygon
			(pts
				(arc
					(start 120.18518 -35.600132)
					(mid 119.70004 -35.114992)
					(end 119.2149 -35.600132)
				)
				(xy 119.2149 -36.052506)
				(arc
					(start 119.546116 -36.052506)
					(mid 119.595221 -36.032929)
					(end 119.61749 -35.984942)
				)
				(arc
					(start 119.61749 -35.984942)
					(mid 119.701071 -35.206461)
					(end 119.78259 -35.985196)
				)
				(xy 119.78259 -36.015422)
				(arc
					(start 119.779542 -36.018216)
					(mid 119.713243 -36.148259)
					(end 119.5832 -36.214558)
				)
				(xy 119.580406 -36.217606) (xy 119.2149 -36.217606) (xy 119.2149 -36.382706) (xy 119.580406 -36.382706)
				(arc
					(start 119.5832 -36.385754)
					(mid 119.713243 -36.452053)
					(end 119.779542 -36.582096)
				)
				(xy 119.78259 -36.58489)
				(arc
					(start 119.78259 -36.615116)
					(mid 119.701071 -37.393887)
					(end 119.61749 -36.61537)
				)
				(arc
					(start 119.61749 -36.61537)
					(mid 119.595291 -36.56731)
					(end 119.546116 -36.547806)
				)
				(xy 119.2149 -36.547806)
				(arc
					(start 119.2149 -36.999926)
					(mid 119.699913 -37.48532)
					(end 120.18518 -37.00018)
				)
			)
		)
	)
	(zone
		(layer "In5.Cu")
		(hatch none 0.5)
		(connect_pads
			(clearance 0)
		)
		(min_thickness 0.25)
		(keepout
			(tracks not_allowed)
			(vias allowed)
			(pads allowed)
			(copperpour not_allowed)
			(footprints allowed)
		)
		(placement
			(enabled no)
			(sheetname "")
		)
		(fill
			(thermal_gap 0.5)
			(thermal_bridge_width 0.5)
			(island_removal_mode 0)
		)
		(polygon
			(pts
				(arc
					(start 141.785086 -42.800016)
					(mid 141.299946 -42.314876)
					(end 140.814806 -42.800016)
				)
				(arc
					(start 140.814806 -44.19981)
					(mid 141.299819 -44.685204)
					(end 141.785086 -44.200064)
				)
				(xy 141.785086 -43.74769)
				(arc
					(start 141.45387 -43.74769)
					(mid 141.404765 -43.767267)
					(end 141.382496 -43.815254)
				)
				(arc
					(start 141.382496 -43.815254)
					(mid 141.298915 -44.593735)
					(end 141.217396 -43.815)
				)
				(xy 141.217396 -43.784774)
				(arc
					(start 141.220444 -43.78198)
					(mid 141.286743 -43.651937)
					(end 141.416786 -43.585638)
				)
				(xy 141.41958 -43.58259) (xy 141.785086 -43.58259) (xy 141.785086 -43.41749) (xy 141.41958 -43.41749)
				(arc
					(start 141.416786 -43.414442)
					(mid 141.286743 -43.348143)
					(end 141.220444 -43.2181)
				)
				(xy 141.217396 -43.215306)
				(arc
					(start 141.217396 -43.18508)
					(mid 141.298915 -42.406309)
					(end 141.382496 -43.184826)
				)
				(arc
					(start 141.382496 -43.184826)
					(mid 141.404695 -43.232886)
					(end 141.45387 -43.25239)
				)
				(xy 141.785086 -43.25239)
			)
		)
	)
	(zone
		(layer "In5.Cu")
		(hatch none 0.5)
		(connect_pads
			(clearance 0)
		)
		(min_thickness 0.25)
		(keepout
			(tracks not_allowed)
			(vias allowed)
			(pads allowed)
			(copperpour not_allowed)
			(footprints allowed)
		)
		(placement
			(enabled no)
			(sheetname "")
		)
		(fill
			(thermal_gap 0.5)
			(thermal_bridge_width 0.5)
			(island_removal_mode 0)
		)
		(polygon
			(pts
				(arc
					(start 130.985006 -35.600132)
					(mid 130.499866 -35.114992)
					(end 130.014726 -35.600132)
				)
				(xy 130.014726 -36.052506)
				(arc
					(start 130.345942 -36.052506)
					(mid 130.395047 -36.032929)
					(end 130.417316 -35.984942)
				)
				(arc
					(start 130.417316 -35.984942)
					(mid 130.500897 -35.206461)
					(end 130.582416 -35.985196)
				)
				(xy 130.582416 -36.015422)
				(arc
					(start 130.579368 -36.018216)
					(mid 130.513069 -36.148259)
					(end 130.383026 -36.214558)
				)
				(xy 130.380232 -36.217606) (xy 130.014726 -36.217606) (xy 130.014726 -36.382706) (xy 130.380232 -36.382706)
				(arc
					(start 130.383026 -36.385754)
					(mid 130.513069 -36.452053)
					(end 130.579368 -36.582096)
				)
				(xy 130.582416 -36.58489)
				(arc
					(start 130.582416 -36.615116)
					(mid 130.500897 -37.393887)
					(end 130.417316 -36.61537)
				)
				(arc
					(start 130.417316 -36.61537)
					(mid 130.395117 -36.56731)
					(end 130.345942 -36.547806)
				)
				(xy 130.014726 -36.547806)
				(arc
					(start 130.014726 -36.999926)
					(mid 130.499739 -37.48532)
					(end 130.985006 -37.00018)
				)
			)
		)
	)
	(zone
		(layer "In5.Cu")
		(hatch none 0.5)
		(connect_pads
			(clearance 0)
		)
		(min_thickness 0.25)
		(keepout
			(tracks not_allowed)
			(vias allowed)
			(pads allowed)
			(copperpour not_allowed)
			(footprints allowed)
		)
		(placement
			(enabled no)
			(sheetname "")
		)
		(fill
			(thermal_gap 0.5)
			(thermal_bridge_width 0.5)
			(island_removal_mode 0)
		)
		(polygon
			(pts
				(arc
					(start 107.585002 -36.800028)
					(mid 107.099862 -36.314888)
					(end 106.614722 -36.800028)
				)
				(xy 106.614722 -37.252402)
				(arc
					(start 106.945938 -37.252402)
					(mid 106.995043 -37.232825)
					(end 107.017312 -37.184838)
				)
				(arc
					(start 107.017312 -37.184838)
					(mid 107.100893 -36.406357)
					(end 107.182412 -37.185092)
				)
				(xy 107.182412 -37.215318)
				(arc
					(start 107.179364 -37.218112)
					(mid 107.113065 -37.348155)
					(end 106.983022 -37.414454)
				)
				(xy 106.980228 -37.417502) (xy 106.614722 -37.417502) (xy 106.614722 -37.582602) (xy 106.980228 -37.582602)
				(arc
					(start 106.983022 -37.58565)
					(mid 107.113065 -37.651949)
					(end 107.179364 -37.781992)
				)
				(xy 107.182412 -37.784786)
				(arc
					(start 107.182412 -37.815012)
					(mid 107.100893 -38.593783)
					(end 107.017312 -37.815266)
				)
				(arc
					(start 107.017312 -37.815266)
					(mid 106.995113 -37.767206)
					(end 106.945938 -37.747702)
				)
				(xy 106.614722 -37.747702)
				(arc
					(start 106.614722 -38.199822)
					(mid 107.099735 -38.685216)
					(end 107.585002 -38.200076)
				)
			)
		)
	)
	(zone
		(layer "In5.Cu")
		(hatch none 0.5)
		(connect_pads
			(clearance 0)
		)
		(min_thickness 0.25)
		(keepout
			(tracks not_allowed)
			(vias allowed)
			(pads allowed)
			(copperpour not_allowed)
			(footprints allowed)
		)
		(placement
			(enabled no)
			(sheetname "")
		)
		(fill
			(thermal_gap 0.5)
			(thermal_bridge_width 0.5)
			(island_removal_mode 0)
		)
		(polygon
			(pts
				(arc
					(start 141.785086 -35.600132)
					(mid 141.299946 -35.114992)
					(end 140.814806 -35.600132)
				)
				(xy 140.814806 -36.052506)
				(arc
					(start 141.146022 -36.052506)
					(mid 141.195127 -36.032929)
					(end 141.217396 -35.984942)
				)
				(arc
					(start 141.217396 -35.984942)
					(mid 141.300977 -35.206461)
					(end 141.382496 -35.985196)
				)
				(xy 141.382496 -36.015422)
				(arc
					(start 141.379448 -36.018216)
					(mid 141.313149 -36.148259)
					(end 141.183106 -36.214558)
				)
				(xy 141.180312 -36.217606) (xy 140.814806 -36.217606) (xy 140.814806 -36.382706) (xy 141.180312 -36.382706)
				(arc
					(start 141.183106 -36.385754)
					(mid 141.313149 -36.452053)
					(end 141.379448 -36.582096)
				)
				(xy 141.382496 -36.58489)
				(arc
					(start 141.382496 -36.615116)
					(mid 141.300977 -37.393887)
					(end 141.217396 -36.61537)
				)
				(arc
					(start 141.217396 -36.61537)
					(mid 141.195197 -36.56731)
					(end 141.146022 -36.547806)
				)
				(xy 140.814806 -36.547806)
				(arc
					(start 140.814806 -36.999926)
					(mid 141.299819 -37.48532)
					(end 141.785086 -37.00018)
				)
			)
		)
	)
	(zone
		(layer "In5.Cu")
		(hatch none 0.5)
		(connect_pads
			(clearance 0)
		)
		(min_thickness 0.25)
		(keepout
			(tracks not_allowed)
			(vias allowed)
			(pads allowed)
			(copperpour not_allowed)
			(footprints allowed)
		)
		(placement
			(enabled no)
			(sheetname "")
		)
		(fill
			(thermal_gap 0.5)
			(thermal_bridge_width 0.5)
			(island_removal_mode 0)
		)
		(polygon
			(pts
				(arc
					(start 85.364828 -84.892388)
					(mid 84.983955 -84.511134)
					(end 84.602828 -84.892134)
				)
				(arc
					(start 84.602828 -85.781134)
					(mid 84.983828 -86.162134)
					(end 85.364828 -85.781134)
				)
				(xy 85.364828 -85.584284) (xy 85.297518 -85.584284)
				(arc
					(start 85.221572 -85.66023)
					(mid 84.795228 -85.969734)
					(end 85.104732 -85.54339)
				)
				(xy 85.180678 -85.467444) (xy 85.228938 -85.419184) (xy 85.297518 -85.419184) (xy 85.364828 -85.419184)
				(xy 85.364828 -85.254084) (xy 85.297518 -85.254084) (xy 85.228938 -85.254084) (xy 85.180678 -85.205824)
				(arc
					(start 85.104732 -85.129878)
					(mid 84.795228 -84.703534)
					(end 85.221572 -85.013038)
				)
				(xy 85.297518 -85.088984) (xy 85.364828 -85.088984)
			)
		)
	)
	(zone
		(layer "In5.Cu")
		(hatch none 0.5)
		(connect_pads
			(clearance 0)
		)
		(min_thickness 0.25)
		(keepout
			(tracks not_allowed)
			(vias allowed)
			(pads allowed)
			(copperpour not_allowed)
			(footprints allowed)
		)
		(placement
			(enabled no)
			(sheetname "")
		)
		(fill
			(thermal_gap 0.5)
			(thermal_bridge_width 0.5)
			(island_removal_mode 0)
		)
		(polygon
			(pts
				(arc
					(start 83.740498 -88.091518)
					(mid 83.359625 -87.710264)
					(end 82.978498 -88.091264)
				)
				(arc
					(start 82.978498 -88.980264)
					(mid 83.359498 -89.361264)
					(end 83.740498 -88.980264)
				)
				(xy 83.740498 -88.77935) (xy 83.677252 -88.77935)
				(arc
					(start 83.597242 -88.85936)
					(mid 83.170898 -89.168864)
					(end 83.480402 -88.74252)
				)
				(xy 83.560412 -88.66251) (xy 83.608672 -88.61425) (xy 83.677252 -88.61425) (xy 83.740498 -88.61425)
				(xy 83.740498 -88.44915) (xy 83.669124 -88.44915) (xy 83.600544 -88.44915) (xy 83.552284 -88.40089)
				(arc
					(start 83.480402 -88.329008)
					(mid 83.170898 -87.902664)
					(end 83.597242 -88.212168)
				)
				(xy 83.669124 -88.28405) (xy 83.740498 -88.28405)
			)
		)
	)
	(zone
		(net "GND")
		(layer "In5.Cu")
		(hatch none 0.5)
		(connect_pads
			(clearance 0.5)
		)
		(min_thickness 0.25)
		(fill yes
			(thermal_gap 0.5)
			(thermal_bridge_width 0.5)
			(island_removal_mode 0)
		)
		(polygon
			(pts
				(xy 208.958688 -42.231818) (xy 207.566514 -40.839644) (xy 205.994254 -39.267384) (xy 180.05298 -39.267384)
				(xy 175.984916 -43.335448) (xy 175.984916 -93.354906) (xy 180.097938 -97.467928) (xy 183.305958 -97.467928)
				(xy 184.616344 -98.778314) (xy 199.74941 -98.778314) (xy 202.329288 -96.198436) (xy 202.862688 -96.198436)
				(xy 208.958688 -90.102436)
			)
		)
	)
	(zone
		(layer "In5.Cu")
		(hatch none 0.5)
		(connect_pads
			(clearance 0)
		)
		(min_thickness 0.25)
		(keepout
			(tracks not_allowed)
			(vias allowed)
			(pads allowed)
			(copperpour not_allowed)
			(footprints allowed)
		)
		(placement
			(enabled no)
			(sheetname "")
		)
		(fill
			(thermal_gap 0.5)
			(thermal_bridge_width 0.5)
			(island_removal_mode 0)
		)
		(polygon
			(pts
				(arc
					(start 85.364828 -91.30665)
					(mid 84.983955 -90.925396)
					(end 84.602828 -91.306396)
				)
				(arc
					(start 84.602828 -92.195396)
					(mid 84.983828 -92.576396)
					(end 85.364828 -92.195396)
				)
				(xy 85.364828 -91.998546) (xy 85.297518 -91.998546)
				(arc
					(start 85.221572 -92.074492)
					(mid 84.795228 -92.383996)
					(end 85.104732 -91.957652)
				)
				(xy 85.180678 -91.881706) (xy 85.228938 -91.833446) (xy 85.297518 -91.833446) (xy 85.364828 -91.833446)
				(xy 85.364828 -91.668346) (xy 85.297518 -91.668346) (xy 85.228938 -91.668346) (xy 85.180678 -91.620086)
				(arc
					(start 85.104732 -91.54414)
					(mid 84.795228 -91.117796)
					(end 85.221572 -91.4273)
				)
				(xy 85.297518 -91.503246) (xy 85.364828 -91.503246)
			)
		)
	)
	(zone
		(layer "In5.Cu")
		(hatch none 0.5)
		(connect_pads
			(clearance 0)
		)
		(min_thickness 0.25)
		(keepout
			(tracks not_allowed)
			(vias allowed)
			(pads allowed)
			(copperpour not_allowed)
			(footprints allowed)
		)
		(placement
			(enabled no)
			(sheetname "")
		)
		(fill
			(thermal_gap 0.5)
			(thermal_bridge_width 0.5)
			(island_removal_mode 0)
		)
		(polygon
			(pts
				(arc
					(start 114.78514 -36.800028)
					(mid 114.3 -36.314888)
					(end 113.81486 -36.800028)
				)
				(xy 113.81486 -37.252402)
				(arc
					(start 114.146076 -37.252402)
					(mid 114.195181 -37.232825)
					(end 114.21745 -37.184838)
				)
				(arc
					(start 114.21745 -37.184838)
					(mid 114.301031 -36.406357)
					(end 114.38255 -37.185092)
				)
				(xy 114.38255 -37.215318)
				(arc
					(start 114.379502 -37.218112)
					(mid 114.313203 -37.348155)
					(end 114.18316 -37.414454)
				)
				(xy 114.180366 -37.417502) (xy 113.81486 -37.417502) (xy 113.81486 -37.582602) (xy 114.180366 -37.582602)
				(arc
					(start 114.18316 -37.58565)
					(mid 114.313203 -37.651949)
					(end 114.379502 -37.781992)
				)
				(xy 114.38255 -37.784786)
				(arc
					(start 114.38255 -37.815012)
					(mid 114.301031 -38.593783)
					(end 114.21745 -37.815266)
				)
				(arc
					(start 114.21745 -37.815266)
					(mid 114.195251 -37.767206)
					(end 114.146076 -37.747702)
				)
				(xy 113.81486 -37.747702)
				(arc
					(start 113.81486 -38.199822)
					(mid 114.299873 -38.685216)
					(end 114.78514 -38.200076)
				)
			)
		)
	)
	(zone
		(layer "In5.Cu")
		(hatch none 0.5)
		(connect_pads
			(clearance 0)
		)
		(min_thickness 0.25)
		(keepout
			(tracks not_allowed)
			(vias allowed)
			(pads allowed)
			(copperpour not_allowed)
			(footprints allowed)
		)
		(placement
			(enabled no)
			(sheetname "")
		)
		(fill
			(thermal_gap 0.5)
			(thermal_bridge_width 0.5)
			(island_removal_mode 0)
		)
		(polygon
			(pts
				(arc
					(start 116.584984 -35.600132)
					(mid 116.099844 -35.114992)
					(end 115.614704 -35.600132)
				)
				(xy 115.614704 -36.052506)
				(arc
					(start 115.94592 -36.052506)
					(mid 115.995025 -36.032929)
					(end 116.017294 -35.984942)
				)
				(arc
					(start 116.017294 -35.984942)
					(mid 116.100875 -35.206461)
					(end 116.182394 -35.985196)
				)
				(xy 116.182394 -36.015422)
				(arc
					(start 116.179346 -36.018216)
					(mid 116.113047 -36.148259)
					(end 115.983004 -36.214558)
				)
				(xy 115.98021 -36.217606) (xy 115.614704 -36.217606) (xy 115.614704 -36.382706) (xy 115.98021 -36.382706)
				(arc
					(start 115.983004 -36.385754)
					(mid 116.113047 -36.452053)
					(end 116.179346 -36.582096)
				)
				(xy 116.182394 -36.58489)
				(arc
					(start 116.182394 -36.615116)
					(mid 116.100875 -37.393887)
					(end 116.017294 -36.61537)
				)
				(arc
					(start 116.017294 -36.61537)
					(mid 115.995095 -36.56731)
					(end 115.94592 -36.547806)
				)
				(xy 115.614704 -36.547806)
				(arc
					(start 115.614704 -36.999926)
					(mid 116.099717 -37.48532)
					(end 116.584984 -37.00018)
				)
			)
		)
	)
	(zone
		(layer "In5.Cu")
		(hatch none 0.5)
		(connect_pads
			(clearance 0)
		)
		(min_thickness 0.25)
		(keepout
			(tracks not_allowed)
			(vias allowed)
			(pads allowed)
			(copperpour not_allowed)
			(footprints allowed)
		)
		(placement
			(enabled no)
			(sheetname "")
		)
		(fill
			(thermal_gap 0.5)
			(thermal_bridge_width 0.5)
			(island_removal_mode 0)
		)
		(polygon
			(pts
				(arc
					(start 136.385046 -36.800028)
					(mid 135.899906 -36.314888)
					(end 135.414766 -36.800028)
				)
				(xy 135.414766 -37.252402)
				(arc
					(start 135.745982 -37.252402)
					(mid 135.795087 -37.232825)
					(end 135.817356 -37.184838)
				)
				(arc
					(start 135.817356 -37.184838)
					(mid 135.900937 -36.406357)
					(end 135.982456 -37.185092)
				)
				(xy 135.982456 -37.215318)
				(arc
					(start 135.979408 -37.218112)
					(mid 135.913109 -37.348155)
					(end 135.783066 -37.414454)
				)
				(xy 135.780272 -37.417502) (xy 135.414766 -37.417502) (xy 135.414766 -37.582602) (xy 135.780272 -37.582602)
				(arc
					(start 135.783066 -37.58565)
					(mid 135.913109 -37.651949)
					(end 135.979408 -37.781992)
				)
				(xy 135.982456 -37.784786)
				(arc
					(start 135.982456 -37.815012)
					(mid 135.900937 -38.593783)
					(end 135.817356 -37.815266)
				)
				(arc
					(start 135.817356 -37.815266)
					(mid 135.795157 -37.767206)
					(end 135.745982 -37.747702)
				)
				(xy 135.414766 -37.747702)
				(arc
					(start 135.414766 -38.199822)
					(mid 135.899779 -38.685216)
					(end 136.385046 -38.200076)
				)
			)
		)
	)
	(zone
		(layer "In5.Cu")
		(hatch none 0.5)
		(connect_pads
			(clearance 0)
		)
		(min_thickness 0.25)
		(keepout
			(tracks not_allowed)
			(vias allowed)
			(pads allowed)
			(copperpour not_allowed)
			(footprints allowed)
		)
		(placement
			(enabled no)
			(sheetname "")
		)
		(fill
			(thermal_gap 0.5)
			(thermal_bridge_width 0.5)
			(island_removal_mode 0)
		)
		(polygon
			(pts
				(arc
					(start 83.739228 -94.492826)
					(mid 83.358355 -94.111572)
					(end 82.977228 -94.492572)
				)
				(arc
					(start 82.977228 -95.381572)
					(mid 83.358228 -95.762572)
					(end 83.739228 -95.381572)
				)
				(xy 83.739228 -95.184722) (xy 83.671918 -95.184722)
				(arc
					(start 83.595972 -95.260668)
					(mid 83.169628 -95.570172)
					(end 83.479132 -95.143828)
				)
				(xy 83.555078 -95.067882) (xy 83.603338 -95.019622) (xy 83.671918 -95.019622) (xy 83.739228 -95.019622)
				(xy 83.739228 -94.854522) (xy 83.671918 -94.854522) (xy 83.603338 -94.854522) (xy 83.555078 -94.806262)
				(arc
					(start 83.479132 -94.730316)
					(mid 83.169628 -94.303972)
					(end 83.595972 -94.613476)
				)
				(xy 83.671918 -94.689422) (xy 83.739228 -94.689422)
			)
		)
	)
	(zone
		(layer "In5.Cu")
		(hatch none 0.5)
		(connect_pads
			(clearance 0)
		)
		(min_thickness 0.25)
		(keepout
			(tracks not_allowed)
			(vias allowed)
			(pads allowed)
			(copperpour not_allowed)
			(footprints allowed)
		)
		(placement
			(enabled no)
			(sheetname "")
		)
		(fill
			(thermal_gap 0.5)
			(thermal_bridge_width 0.5)
			(island_removal_mode 0)
		)
		(polygon
			(pts
				(arc
					(start 129.185162 -36.800028)
					(mid 128.700022 -36.314888)
					(end 128.214882 -36.800028)
				)
				(xy 128.214882 -37.252402)
				(arc
					(start 128.546098 -37.252402)
					(mid 128.595203 -37.232825)
					(end 128.617472 -37.184838)
				)
				(arc
					(start 128.617472 -37.184838)
					(mid 128.701053 -36.406357)
					(end 128.782572 -37.185092)
				)
				(xy 128.782572 -37.215318)
				(arc
					(start 128.779524 -37.218112)
					(mid 128.713225 -37.348155)
					(end 128.583182 -37.414454)
				)
				(xy 128.580388 -37.417502) (xy 128.214882 -37.417502) (xy 128.214882 -37.582602) (xy 128.580388 -37.582602)
				(arc
					(start 128.583182 -37.58565)
					(mid 128.713225 -37.651949)
					(end 128.779524 -37.781992)
				)
				(xy 128.782572 -37.784786)
				(arc
					(start 128.782572 -37.815012)
					(mid 128.701053 -38.593783)
					(end 128.617472 -37.815266)
				)
				(arc
					(start 128.617472 -37.815266)
					(mid 128.595273 -37.767206)
					(end 128.546098 -37.747702)
				)
				(xy 128.214882 -37.747702)
				(arc
					(start 128.214882 -38.199822)
					(mid 128.699895 -38.685216)
					(end 129.185162 -38.200076)
				)
			)
		)
	)
	(zone
		(layer "In5.Cu")
		(hatch none 0.5)
		(connect_pads
			(clearance 0)
		)
		(min_thickness 0.25)
		(keepout
			(tracks not_allowed)
			(vias allowed)
			(pads allowed)
			(copperpour not_allowed)
			(footprints allowed)
		)
		(placement
			(enabled no)
			(sheetname "")
		)
		(fill
			(thermal_gap 0.5)
			(thermal_bridge_width 0.5)
			(island_removal_mode 0)
		)
		(polygon
			(pts
				(arc
					(start 85.367622 -78.50759)
					(mid 84.986749 -78.126336)
					(end 84.605622 -78.507336)
				)
				(arc
					(start 84.605622 -79.396336)
					(mid 84.986622 -79.777336)
					(end 85.367622 -79.396336)
				)
				(xy 85.367622 -79.199486) (xy 85.300312 -79.199486)
				(arc
					(start 85.224366 -79.275432)
					(mid 84.798022 -79.584936)
					(end 85.107526 -79.158592)
				)
				(xy 85.183472 -79.082646) (xy 85.231732 -79.034386) (xy 85.300312 -79.034386) (xy 85.367622 -79.034386)
				(xy 85.367622 -78.869286) (xy 85.300312 -78.869286) (xy 85.231732 -78.869286) (xy 85.183472 -78.821026)
				(arc
					(start 85.107526 -78.74508)
					(mid 84.798022 -78.318736)
					(end 85.224366 -78.62824)
				)
				(xy 85.300312 -78.704186) (xy 85.367622 -78.704186)
			)
		)
	)
	(zone
		(layer "In5.Cu")
		(hatch none 0.5)
		(connect_pads
			(clearance 0)
		)
		(min_thickness 0.25)
		(keepout
			(tracks not_allowed)
			(vias allowed)
			(pads allowed)
			(copperpour not_allowed)
			(footprints allowed)
		)
		(placement
			(enabled no)
			(sheetname "")
		)
		(fill
			(thermal_gap 0.5)
			(thermal_bridge_width 0.5)
			(island_removal_mode 0)
		)
		(polygon
			(pts
				(arc
					(start 112.985042 -35.600132)
					(mid 112.499902 -35.114992)
					(end 112.014762 -35.600132)
				)
				(xy 112.014762 -36.052506)
				(arc
					(start 112.345978 -36.052506)
					(mid 112.395083 -36.032929)
					(end 112.417352 -35.984942)
				)
				(arc
					(start 112.417352 -35.984942)
					(mid 112.500933 -35.206461)
					(end 112.582452 -35.985196)
				)
				(xy 112.582452 -36.015422)
				(arc
					(start 112.579404 -36.018216)
					(mid 112.513105 -36.148259)
					(end 112.383062 -36.214558)
				)
				(xy 112.380268 -36.217606) (xy 112.014762 -36.217606) (xy 112.014762 -36.382706) (xy 112.380268 -36.382706)
				(arc
					(start 112.383062 -36.385754)
					(mid 112.513105 -36.452053)
					(end 112.579404 -36.582096)
				)
				(xy 112.582452 -36.58489)
				(arc
					(start 112.582452 -36.615116)
					(mid 112.500933 -37.393887)
					(end 112.417352 -36.61537)
				)
				(arc
					(start 112.417352 -36.61537)
					(mid 112.395153 -36.56731)
					(end 112.345978 -36.547806)
				)
				(xy 112.014762 -36.547806)
				(arc
					(start 112.014762 -36.999926)
					(mid 112.499775 -37.48532)
					(end 112.985042 -37.00018)
				)
			)
		)
	)
	(zone
		(layer "In5.Cu")
		(hatch none 0.5)
		(connect_pads
			(clearance 0)
		)
		(min_thickness 0.25)
		(keepout
			(tracks not_allowed)
			(vias allowed)
			(pads allowed)
			(copperpour not_allowed)
			(footprints allowed)
		)
		(placement
			(enabled no)
			(sheetname "")
		)
		(fill
			(thermal_gap 0.5)
			(thermal_bridge_width 0.5)
			(island_removal_mode 0)
		)
		(polygon
			(pts
				(arc
					(start 83.739228 -75.305412)
					(mid 83.358355 -74.924158)
					(end 82.977228 -75.305158)
				)
				(arc
					(start 82.977228 -76.194158)
					(mid 83.358228 -76.575158)
					(end 83.739228 -76.194158)
				)
				(xy 83.739228 -76.00442) (xy 83.664806 -76.00442)
				(arc
					(start 83.595972 -76.073254)
					(mid 83.169628 -76.382758)
					(end 83.479132 -75.956414)
				)
				(xy 83.547966 -75.88758) (xy 83.596226 -75.83932) (xy 83.664806 -75.83932) (xy 83.739228 -75.83932)
				(xy 83.739228 -75.67422) (xy 83.67903 -75.67422) (xy 83.61045 -75.67422) (xy 83.56219 -75.62596)
				(arc
					(start 83.479132 -75.542902)
					(mid 83.169628 -75.116558)
					(end 83.595972 -75.426062)
				)
				(xy 83.67903 -75.50912) (xy 83.739228 -75.50912)
			)
		)
	)
	(zone
		(layer "In5.Cu")
		(hatch none 0.5)
		(connect_pads
			(clearance 0)
		)
		(min_thickness 0.25)
		(keepout
			(tracks not_allowed)
			(vias allowed)
			(pads allowed)
			(copperpour not_allowed)
			(footprints allowed)
		)
		(placement
			(enabled no)
			(sheetname "")
		)
		(fill
			(thermal_gap 0.5)
			(thermal_bridge_width 0.5)
			(island_removal_mode 0)
		)
		(polygon
			(pts
				(arc
					(start 111.185198 -36.800028)
					(mid 110.700058 -36.314888)
					(end 110.214918 -36.800028)
				)
				(xy 110.214918 -37.252402)
				(arc
					(start 110.546134 -37.252402)
					(mid 110.595239 -37.232825)
					(end 110.617508 -37.184838)
				)
				(arc
					(start 110.617508 -37.184838)
					(mid 110.701089 -36.406357)
					(end 110.782608 -37.185092)
				)
				(xy 110.782608 -37.215318)
				(arc
					(start 110.77956 -37.218112)
					(mid 110.713261 -37.348155)
					(end 110.583218 -37.414454)
				)
				(xy 110.580424 -37.417502) (xy 110.214918 -37.417502) (xy 110.214918 -37.582602) (xy 110.580424 -37.582602)
				(arc
					(start 110.583218 -37.58565)
					(mid 110.713261 -37.651949)
					(end 110.77956 -37.781992)
				)
				(xy 110.782608 -37.784786)
				(arc
					(start 110.782608 -37.815012)
					(mid 110.701089 -38.593783)
					(end 110.617508 -37.815266)
				)
				(arc
					(start 110.617508 -37.815266)
					(mid 110.595309 -37.767206)
					(end 110.546134 -37.747702)
				)
				(xy 110.214918 -37.747702)
				(arc
					(start 110.214918 -38.199822)
					(mid 110.699931 -38.685216)
					(end 111.185198 -38.200076)
				)
			)
		)
	)
	(zone
		(net "GND")
		(layer "In5.Cu")
		(hatch none 0.5)
		(connect_pads
			(clearance 0.5)
		)
		(min_thickness 0.25)
		(fill yes
			(thermal_gap 0.5)
			(thermal_bridge_width 0.5)
			(island_removal_mode 0)
		)
		(polygon
			(pts
				(xy 100.906072 -178.38039) (xy 100.906072 -182.753) (xy 102.937056 -182.753) (xy 102.937056 -178.38039)
			)
		)
	)
	(zone
		(layer "In5.Cu")
		(hatch none 0.5)
		(connect_pads
			(clearance 0)
		)
		(min_thickness 0.25)
		(keepout
			(tracks not_allowed)
			(vias allowed)
			(pads allowed)
			(copperpour not_allowed)
			(footprints allowed)
		)
		(placement
			(enabled no)
			(sheetname "")
		)
		(fill
			(thermal_gap 0.5)
			(thermal_bridge_width 0.5)
			(island_removal_mode 0)
		)
		(polygon
			(pts
				(arc
					(start 134.585202 -35.600132)
					(mid 134.100062 -35.114992)
					(end 133.614922 -35.600132)
				)
				(xy 133.614922 -36.052506)
				(arc
					(start 133.946138 -36.052506)
					(mid 133.995243 -36.032929)
					(end 134.017512 -35.984942)
				)
				(arc
					(start 134.017512 -35.984942)
					(mid 134.101093 -35.206461)
					(end 134.182612 -35.985196)
				)
				(xy 134.182612 -36.015422)
				(arc
					(start 134.179564 -36.018216)
					(mid 134.113265 -36.148259)
					(end 133.983222 -36.214558)
				)
				(xy 133.980428 -36.217606) (xy 133.614922 -36.217606) (xy 133.614922 -36.382706) (xy 133.980428 -36.382706)
				(arc
					(start 133.983222 -36.385754)
					(mid 134.113265 -36.452053)
					(end 134.179564 -36.582096)
				)
				(xy 134.182612 -36.58489)
				(arc
					(start 134.182612 -36.615116)
					(mid 134.101093 -37.393887)
					(end 134.017512 -36.61537)
				)
				(arc
					(start 134.017512 -36.61537)
					(mid 133.995313 -36.56731)
					(end 133.946138 -36.547806)
				)
				(xy 133.614922 -36.547806)
				(arc
					(start 133.614922 -36.999926)
					(mid 134.099935 -37.48532)
					(end 134.585202 -37.00018)
				)
			)
		)
	)
	(zone
		(layer "In5.Cu")
		(hatch none 0.5)
		(connect_pads
			(clearance 0)
		)
		(min_thickness 0.25)
		(keepout
			(tracks not_allowed)
			(vias allowed)
			(pads allowed)
			(copperpour not_allowed)
			(footprints allowed)
		)
		(placement
			(enabled no)
			(sheetname "")
		)
		(fill
			(thermal_gap 0.5)
			(thermal_bridge_width 0.5)
			(island_removal_mode 0)
		)
		(polygon
			(pts
				(arc
					(start 118.385082 -36.800028)
					(mid 117.899942 -36.314888)
					(end 117.414802 -36.800028)
				)
				(xy 117.414802 -37.252402)
				(arc
					(start 117.746018 -37.252402)
					(mid 117.795123 -37.232825)
					(end 117.817392 -37.184838)
				)
				(arc
					(start 117.817392 -37.184838)
					(mid 117.900973 -36.406357)
					(end 117.982492 -37.185092)
				)
				(xy 117.982492 -37.215318)
				(arc
					(start 117.979444 -37.218112)
					(mid 117.913145 -37.348155)
					(end 117.783102 -37.414454)
				)
				(xy 117.780308 -37.417502) (xy 117.414802 -37.417502) (xy 117.414802 -37.582602) (xy 117.780308 -37.582602)
				(arc
					(start 117.783102 -37.58565)
					(mid 117.913145 -37.651949)
					(end 117.979444 -37.781992)
				)
				(xy 117.982492 -37.784786)
				(arc
					(start 117.982492 -37.815012)
					(mid 117.900973 -38.593783)
					(end 117.817392 -37.815266)
				)
				(arc
					(start 117.817392 -37.815266)
					(mid 117.795193 -37.767206)
					(end 117.746018 -37.747702)
				)
				(xy 117.414802 -37.747702)
				(arc
					(start 117.414802 -38.199822)
					(mid 117.899815 -38.685216)
					(end 118.385082 -38.200076)
				)
			)
		)
	)
	(zone
		(net "GND")
		(layer "In6.Cu")
		(hatch none 0.5)
		(connect_pads
			(clearance 0.5)
		)
		(min_thickness 0.25)
		(fill yes
			(thermal_gap 0.5)
			(thermal_bridge_width 0.5)
			(island_removal_mode 0)
		)
		(polygon
			(pts
				(arc
					(start 0.999998 -0.763016)
					(mid 0.832426 -0.832426)
					(end 0.763016 -0.999998)
				)
				(arc
					(start 0.763016 -183.76392)
					(mid 0.769411 -183.818347)
					(end 0.788162 -183.869838)
				)
				(arc
					(start 5.406136 -193.10604)
					(mid 5.493436 -193.201687)
					(end 5.617972 -193.237104)
				)
				(arc
					(start 98.0821 -193.237104)
					(mid 98.206591 -193.201614)
					(end 98.293936 -193.10604)
				)
				(arc
					(start 102.91191 -183.869838)
					(mid 102.930633 -183.818341)
					(end 102.937056 -183.76392)
				)
				(arc
					(start 102.937056 -47.999904)
					(mid 103.797626 -46.802631)
					(end 105.206546 -47.236888)
				)
				(arc
					(start 142.793466 -47.236888)
					(mid 144.202311 -46.802855)
					(end 145.062956 -47.999904)
				)
				(arc
					(start 145.062956 -149.763734)
					(mid 145.069351 -149.818161)
					(end 145.088102 -149.869652)
				)
				(arc
					(start 149.706076 -159.105854)
					(mid 149.793376 -159.201501)
					(end 149.917912 -159.236918)
				)
				(arc
					(start 214.00008 -159.236918)
					(mid 215.246719 -159.753293)
					(end 215.763094 -160.999932)
				)
				(arc
					(start 215.763094 -193.000122)
					(mid 215.832504 -193.167694)
					(end 216.000076 -193.237104)
				)
				(arc
					(start 229.382066 -193.237104)
					(mid 229.506557 -193.201614)
					(end 229.593902 -193.10604)
				)
				(arc
					(start 234.211876 -183.869838)
					(mid 234.230599 -183.818341)
					(end 234.237022 -183.76392)
				)
				(arc
					(start 234.237022 -0.999998)
					(mid 234.167612 -0.832426)
					(end 234.00004 -0.763016)
				)
				(arc
					(start 74.030078 -0.763016)
					(mid 73.862506 -0.832426)
					(end 73.793096 -0.999998)
				)
				(arc
					(start 73.793096 -109.050074)
					(mid 73.276721 -110.296713)
					(end 72.030082 -110.813088)
				)
				(arc
					(start 31.530036 -110.813088)
					(mid 30.283397 -110.296713)
					(end 29.767022 -109.050074)
				)
				(arc
					(start 29.767022 -0.999998)
					(mid 29.697612 -0.832426)
					(end 29.53004 -0.763016)
				)
			)
		)
		(polygon
			(pts
				(arc
					(start 205.187296 -140.640308)
					(mid 204.648308 -140.640308)
					(end 204.648308 -141.179296)
				)
				(arc
					(start 205.276958 -141.807692)
					(mid 205.815756 -141.807883)
					(end 205.815946 -141.268958)
				)
			)
		)
		(polygon
			(pts
				(arc
					(start 200.488296 -140.640308)
					(mid 199.949308 -140.640308)
					(end 199.949308 -141.179296)
				)
				(arc
					(start 200.577958 -141.807692)
					(mid 201.116756 -141.807883)
					(end 201.116946 -141.268958)
				)
			)
		)
		(polygon
			(pts
				(arc
					(start 202.901296 -140.513308)
					(mid 202.362308 -140.513308)
					(end 202.362308 -141.052296)
				)
				(arc
					(start 202.990958 -141.680692)
					(mid 203.529756 -141.680883)
					(end 203.529946 -141.141958)
				)
			)
		)
		(polygon
			(pts
				(arc
					(start 198.075296 -140.386308)
					(mid 197.536308 -140.386308)
					(end 197.536308 -140.925296)
				)
				(arc
					(start 198.164958 -141.553692)
					(mid 198.703756 -141.553883)
					(end 198.703946 -141.014958)
				)
			)
		)
		(polygon
			(pts
				(arc
					(start 209.886296 -140.259308)
					(mid 209.347308 -140.259308)
					(end 209.347308 -140.798296)
				)
				(arc
					(start 209.975958 -141.426692)
					(mid 210.514756 -141.426883)
					(end 210.514946 -140.887958)
				)
			)
		)
		(polygon
			(pts
				(arc
					(start 195.408296 -140.132308)
					(mid 194.869308 -140.132308)
					(end 194.869308 -140.671296)
				)
				(arc
					(start 195.497958 -141.299692)
					(mid 196.036756 -141.299883)
					(end 196.036946 -140.760958)
				)
			)
		)
		(polygon
			(pts
				(arc
					(start 174.563786 -139.963398)
					(mid 174.024798 -139.963398)
					(end 174.024798 -140.502386)
				)
				(arc
					(start 174.653448 -141.130782)
					(mid 175.192246 -141.130973)
					(end 175.192436 -140.592048)
				)
			)
		)
		(polygon
			(pts
				(arc
					(start 180.274722 -139.89939)
					(mid 179.735734 -139.89939)
					(end 179.735734 -140.438378)
				)
				(arc
					(start 180.364384 -141.066774)
					(mid 180.903182 -141.066965)
					(end 180.903372 -140.52804)
				)
			)
		)
		(polygon
			(pts
				(arc
					(start 177.930556 -139.704318)
					(mid 177.391568 -139.704318)
					(end 177.391568 -140.243306)
				)
				(arc
					(start 178.020218 -140.871702)
					(mid 178.559016 -140.871893)
					(end 178.559206 -140.332968)
				)
			)
		)
		(polygon
			(pts
				(arc
					(start 185.354722 -139.41679)
					(mid 184.815734 -139.41679)
					(end 184.815734 -139.955778)
				)
				(arc
					(start 185.444384 -140.584174)
					(mid 185.983182 -140.584365)
					(end 185.983372 -140.04544)
				)
			)
		)
		(polygon
			(pts
				(arc
					(start 182.59806 -139.39393)
					(mid 182.059072 -139.39393)
					(end 182.059072 -139.932918)
				)
				(arc
					(start 182.687722 -140.561314)
					(mid 183.22652 -140.561505)
					(end 183.22671 -140.02258)
				)
			)
		)
		(polygon
			(pts
				(arc
					(start 206.711296 -138.989308)
					(mid 206.172308 -138.989308)
					(end 206.172308 -139.528296)
				)
				(arc
					(start 206.800958 -140.156692)
					(mid 207.339756 -140.156883)
					(end 207.339946 -139.617958)
				)
			)
		)
		(polygon
			(pts
				(arc
					(start 192.360296 -138.989308)
					(mid 191.821308 -138.989308)
					(end 191.821308 -139.528296)
				)
				(arc
					(start 192.449958 -140.156692)
					(mid 192.988756 -140.156883)
					(end 192.988946 -139.617958)
				)
			)
		)
		(polygon
			(pts
				(arc
					(start 213.602824 -138.607546)
					(mid 213.063836 -138.607546)
					(end 213.063836 -139.146534)
				)
				(arc
					(start 213.692486 -139.77493)
					(mid 214.231284 -139.775121)
					(end 214.231474 -139.236196)
				)
			)
		)
		(polygon
			(pts
				(arc
					(start 170.70959 -138.05154)
					(mid 170.170602 -138.05154)
					(end 170.170602 -138.590528)
				)
				(arc
					(start 170.799252 -139.218924)
					(mid 171.33805 -139.219115)
					(end 171.33824 -138.68019)
				)
			)
		)
		(polygon
			(pts
				(arc
					(start 174.213266 -137.655554)
					(mid 173.674278 -137.655554)
					(end 173.674278 -138.194542)
				)
				(arc
					(start 174.302928 -138.822938)
					(mid 174.841726 -138.823129)
					(end 174.841916 -138.284204)
				)
			)
		)
		(polygon
			(pts
				(arc
					(start 167.381428 -136.636506)
					(mid 166.84244 -136.636506)
					(end 166.84244 -137.175494)
				)
				(arc
					(start 167.47109 -137.80389)
					(mid 168.009888 -137.804081)
					(end 168.010078 -137.265156)
				)
			)
		)
		(polygon
			(pts
				(arc
					(start 183.905398 -133.354826)
					(mid 184.286144 -132.973699)
					(end 183.905144 -132.592826)
				)
				(arc
					(start 183.016144 -132.592826)
					(mid 182.635144 -132.973826)
					(end 183.016144 -133.354826)
				)
			)
		)
		(polygon
			(pts
				(arc
					(start 83.741768 -94.492572)
					(mid 83.358228 -94.109032)
					(end 82.974688 -94.492572)
				)
				(arc
					(start 82.974688 -95.381826)
					(mid 83.358355 -95.765112)
					(end 83.741768 -95.381572)
				)
			)
		)
		(polygon
			(pts
				(arc
					(start 77.667358 -92.911168)
					(mid 77.283818 -92.527628)
					(end 76.900278 -92.911168)
				)
				(arc
					(start 76.900278 -93.800422)
					(mid 77.283945 -94.183708)
					(end 77.667358 -93.800168)
				)
			)
		)
		(polygon
			(pts
				(arc
					(start 85.367368 -91.306396)
					(mid 84.983828 -90.922856)
					(end 84.600288 -91.306396)
				)
				(arc
					(start 84.600288 -92.19565)
					(mid 84.983955 -92.578936)
					(end 85.367368 -92.195396)
				)
			)
		)
		(polygon
			(pts
				(arc
					(start 78.505558 -89.710768)
					(mid 78.122018 -89.327228)
					(end 77.738478 -89.710768)
				)
				(arc
					(start 77.738478 -90.600022)
					(mid 78.122145 -90.983308)
					(end 78.505558 -90.599768)
				)
			)
		)
		(polygon
			(pts
				(arc
					(start 83.743038 -88.091264)
					(mid 83.359498 -87.707724)
					(end 82.975958 -88.091264)
				)
				(arc
					(start 82.975958 -88.980518)
					(mid 83.359625 -89.363804)
					(end 83.743038 -88.980264)
				)
			)
		)
		(polygon
			(pts
				(arc
					(start 77.667358 -86.510368)
					(mid 77.283818 -86.126828)
					(end 76.900278 -86.510368)
				)
				(arc
					(start 76.900278 -87.399622)
					(mid 77.283945 -87.782908)
					(end 77.667358 -87.399368)
				)
			)
		)
		(polygon
			(pts
				(arc
					(start 85.367368 -84.892134)
					(mid 84.983828 -84.508594)
					(end 84.600288 -84.892134)
				)
				(arc
					(start 84.600288 -85.781388)
					(mid 84.983955 -86.164674)
					(end 85.367368 -85.781134)
				)
			)
		)
		(polygon
			(pts
				(arc
					(start 78.505558 -83.309968)
					(mid 78.122018 -82.926428)
					(end 77.738478 -83.309968)
				)
				(arc
					(start 77.738478 -84.199222)
					(mid 78.122145 -84.582508)
					(end 78.505558 -84.198968)
				)
			)
		)
		(polygon
			(pts
				(arc
					(start 83.741768 -81.692496)
					(mid 83.358228 -81.308956)
					(end 82.974688 -81.692496)
				)
				(arc
					(start 82.974688 -82.58175)
					(mid 83.358355 -82.965036)
					(end 83.741768 -82.581496)
				)
			)
		)
		(polygon
			(pts
				(arc
					(start 77.667358 -80.109568)
					(mid 77.283818 -79.726028)
					(end 76.900278 -80.109568)
				)
				(arc
					(start 76.900278 -80.998822)
					(mid 77.283945 -81.382108)
					(end 77.667358 -80.998568)
				)
			)
		)
		(polygon
			(pts
				(arc
					(start 85.370162 -78.507336)
					(mid 84.986622 -78.123796)
					(end 84.603082 -78.507336)
				)
				(arc
					(start 84.603082 -79.39659)
					(mid 84.986749 -79.779876)
					(end 85.370162 -79.396336)
				)
			)
		)
		(polygon
			(pts
				(arc
					(start 78.505558 -76.909168)
					(mid 78.122018 -76.525628)
					(end 77.738478 -76.909168)
				)
				(arc
					(start 77.738478 -77.798422)
					(mid 78.122145 -78.181708)
					(end 78.505558 -77.798168)
				)
			)
		)
		(polygon
			(pts
				(arc
					(start 83.741768 -75.305158)
					(mid 83.358228 -74.921618)
					(end 82.974688 -75.305158)
				)
				(arc
					(start 82.974688 -76.194412)
					(mid 83.358355 -76.577698)
					(end 83.741768 -76.194158)
				)
			)
		)
		(polygon
			(pts
				(arc
					(start 77.667358 -73.708768)
					(mid 77.283818 -73.325228)
					(end 76.900278 -73.708768)
				)
				(arc
					(start 76.900278 -74.598022)
					(mid 77.283945 -74.981308)
					(end 77.667358 -74.597768)
				)
			)
		)
		(polygon
			(pts
				(arc
					(start 85.246718 -72.098916)
					(mid 84.863178 -71.715376)
					(end 84.479638 -72.098916)
				)
				(arc
					(start 84.479638 -72.98817)
					(mid 84.863305 -73.371456)
					(end 85.246718 -72.987916)
				)
			)
		)
		(polygon
			(pts
				(arc
					(start 78.505558 -70.508368)
					(mid 78.122018 -70.124828)
					(end 77.738478 -70.508368)
				)
				(arc
					(start 77.738478 -71.397622)
					(mid 78.122145 -71.780908)
					(end 78.505558 -71.397368)
				)
			)
		)
		(polygon
			(pts
				(arc
					(start 77.738732 -67.312032)
					(mid 77.355192 -66.928492)
					(end 76.971652 -67.312032)
				)
				(arc
					(start 76.971652 -68.201286)
					(mid 77.355319 -68.584572)
					(end 77.738732 -68.201032)
				)
			)
		)
		(polygon
			(pts
				(arc
					(start 141.785086 -42.800016)
					(mid 141.299946 -42.314876)
					(end 140.814806 -42.800016)
				)
				(arc
					(start 140.814806 -44.200318)
					(mid 141.300073 -44.685204)
					(end 141.785086 -44.200064)
				)
			)
		)
		(polygon
			(pts
				(arc
					(start 134.585202 -42.800016)
					(mid 134.100062 -42.314876)
					(end 133.614922 -42.800016)
				)
				(arc
					(start 133.614922 -44.200318)
					(mid 134.100189 -44.685204)
					(end 134.585202 -44.200064)
				)
			)
		)
		(polygon
			(pts
				(arc
					(start 120.18518 -42.800016)
					(mid 119.70004 -42.314876)
					(end 119.2149 -42.800016)
				)
				(arc
					(start 119.2149 -44.200318)
					(mid 119.700167 -44.685204)
					(end 120.18518 -44.200064)
				)
			)
		)
		(polygon
			(pts
				(arc
					(start 139.984988 -36.800028)
					(mid 139.499848 -36.314888)
					(end 139.014708 -36.800028)
				)
				(arc
					(start 139.014708 -38.20033)
					(mid 139.499975 -38.685216)
					(end 139.984988 -38.200076)
				)
			)
		)
		(polygon
			(pts
				(arc
					(start 136.385046 -36.800028)
					(mid 135.899906 -36.314888)
					(end 135.414766 -36.800028)
				)
				(arc
					(start 135.414766 -38.20033)
					(mid 135.900033 -38.685216)
					(end 136.385046 -38.200076)
				)
			)
		)
		(polygon
			(pts
				(arc
					(start 132.785104 -36.800028)
					(mid 132.299964 -36.314888)
					(end 131.814824 -36.800028)
				)
				(arc
					(start 131.814824 -38.20033)
					(mid 132.300091 -38.685216)
					(end 132.785104 -38.200076)
				)
			)
		)
		(polygon
			(pts
				(arc
					(start 129.185162 -36.800028)
					(mid 128.700022 -36.314888)
					(end 128.214882 -36.800028)
				)
				(arc
					(start 128.214882 -38.20033)
					(mid 128.700149 -38.685216)
					(end 129.185162 -38.200076)
				)
			)
		)
		(polygon
			(pts
				(arc
					(start 118.385082 -36.800028)
					(mid 117.899942 -36.314888)
					(end 117.414802 -36.800028)
				)
				(arc
					(start 117.414802 -38.20033)
					(mid 117.900069 -38.685216)
					(end 118.385082 -38.200076)
				)
			)
		)
		(polygon
			(pts
				(arc
					(start 114.78514 -36.800028)
					(mid 114.3 -36.314888)
					(end 113.81486 -36.800028)
				)
				(arc
					(start 113.81486 -38.20033)
					(mid 114.300127 -38.685216)
					(end 114.78514 -38.200076)
				)
			)
		)
		(polygon
			(pts
				(arc
					(start 111.185198 -36.800028)
					(mid 110.700058 -36.314888)
					(end 110.214918 -36.800028)
				)
				(arc
					(start 110.214918 -38.20033)
					(mid 110.700185 -38.685216)
					(end 111.185198 -38.200076)
				)
			)
		)
		(polygon
			(pts
				(arc
					(start 107.585002 -36.800028)
					(mid 107.099862 -36.314888)
					(end 106.614722 -36.800028)
				)
				(arc
					(start 106.614722 -38.20033)
					(mid 107.099989 -38.685216)
					(end 107.585002 -38.200076)
				)
			)
		)
		(polygon
			(pts
				(arc
					(start 141.785086 -35.600132)
					(mid 141.299946 -35.114992)
					(end 140.814806 -35.600132)
				)
				(arc
					(start 140.814806 -37.000434)
					(mid 141.300073 -37.48532)
					(end 141.785086 -37.00018)
				)
			)
		)
		(polygon
			(pts
				(arc
					(start 138.185144 -35.600132)
					(mid 137.700004 -35.114992)
					(end 137.214864 -35.600132)
				)
				(arc
					(start 137.214864 -37.000434)
					(mid 137.700131 -37.48532)
					(end 138.185144 -37.00018)
				)
			)
		)
		(polygon
			(pts
				(arc
					(start 134.585202 -35.600132)
					(mid 134.100062 -35.114992)
					(end 133.614922 -35.600132)
				)
				(arc
					(start 133.614922 -37.000434)
					(mid 134.100189 -37.48532)
					(end 134.585202 -37.00018)
				)
			)
		)
		(polygon
			(pts
				(arc
					(start 130.985006 -35.600132)
					(mid 130.499866 -35.114992)
					(end 130.014726 -35.600132)
				)
				(arc
					(start 130.014726 -37.000434)
					(mid 130.499993 -37.48532)
					(end 130.985006 -37.00018)
				)
			)
		)
		(polygon
			(pts
				(arc
					(start 120.18518 -35.600132)
					(mid 119.70004 -35.114992)
					(end 119.2149 -35.600132)
				)
				(arc
					(start 119.2149 -37.000434)
					(mid 119.700167 -37.48532)
					(end 120.18518 -37.00018)
				)
			)
		)
		(polygon
			(pts
				(arc
					(start 116.584984 -35.600132)
					(mid 116.099844 -35.114992)
					(end 115.614704 -35.600132)
				)
				(arc
					(start 115.614704 -37.000434)
					(mid 116.099971 -37.48532)
					(end 116.584984 -37.00018)
				)
			)
		)
		(polygon
			(pts
				(arc
					(start 112.985042 -35.600132)
					(mid 112.499902 -35.114992)
					(end 112.014762 -35.600132)
				)
				(arc
					(start 112.014762 -37.000434)
					(mid 112.500029 -37.48532)
					(end 112.985042 -37.00018)
				)
			)
		)
		(polygon
			(pts
				(arc
					(start 109.3851 -35.600132)
					(mid 108.89996 -35.114992)
					(end 108.41482 -35.600132)
				)
				(arc
					(start 108.41482 -37.000434)
					(mid 108.900087 -37.48532)
					(end 109.3851 -37.00018)
				)
			)
		)
		(polygon
			(pts
				(arc
					(start 139.984988 -33.199832)
					(mid 139.499721 -32.714946)
					(end 139.014708 -33.200086)
				)
				(arc
					(start 139.014708 -34.600134)
					(mid 139.499848 -35.085274)
					(end 139.984988 -34.600134)
				)
			)
		)
		(polygon
			(pts
				(arc
					(start 136.385046 -33.199832)
					(mid 135.899779 -32.714946)
					(end 135.414766 -33.200086)
				)
				(arc
					(start 135.414766 -34.600134)
					(mid 135.899906 -35.085274)
					(end 136.385046 -34.600134)
				)
			)
		)
		(polygon
			(pts
				(arc
					(start 132.785104 -33.199832)
					(mid 132.299837 -32.714946)
					(end 131.814824 -33.200086)
				)
				(arc
					(start 131.814824 -34.600134)
					(mid 132.299964 -35.085274)
					(end 132.785104 -34.600134)
				)
			)
		)
		(polygon
			(pts
				(arc
					(start 129.185162 -33.199832)
					(mid 128.699895 -32.714946)
					(end 128.214882 -33.200086)
				)
				(arc
					(start 128.214882 -34.600134)
					(mid 128.700022 -35.085274)
					(end 129.185162 -34.600134)
				)
			)
		)
		(polygon
			(pts
				(arc
					(start 118.385082 -33.199832)
					(mid 117.899815 -32.714946)
					(end 117.414802 -33.200086)
				)
				(arc
					(start 117.414802 -34.600134)
					(mid 117.899942 -35.085274)
					(end 118.385082 -34.600134)
				)
			)
		)
		(polygon
			(pts
				(arc
					(start 114.78514 -33.199832)
					(mid 114.299873 -32.714946)
					(end 113.81486 -33.200086)
				)
				(arc
					(start 113.81486 -34.600134)
					(mid 114.3 -35.085274)
					(end 114.78514 -34.600134)
				)
			)
		)
		(polygon
			(pts
				(arc
					(start 111.185198 -33.199832)
					(mid 110.699931 -32.714946)
					(end 110.214918 -33.200086)
				)
				(arc
					(start 110.214918 -34.600134)
					(mid 110.700058 -35.085274)
					(end 111.185198 -34.600134)
				)
			)
		)
		(polygon
			(pts
				(arc
					(start 107.585002 -33.199832)
					(mid 107.099735 -32.714946)
					(end 106.614722 -33.200086)
				)
				(arc
					(start 106.614722 -34.600134)
					(mid 107.099862 -35.085274)
					(end 107.585002 -34.600134)
				)
			)
		)
		(polygon
			(pts
				(arc
					(start 141.785086 -32.00019)
					(mid 141.299946 -31.51505)
					(end 140.814806 -32.00019)
				)
				(arc
					(start 140.814806 -33.400238)
					(mid 141.300073 -33.885124)
					(end 141.785086 -33.399984)
				)
			)
		)
		(polygon
			(pts
				(arc
					(start 138.185144 -32.00019)
					(mid 137.700004 -31.51505)
					(end 137.214864 -32.00019)
				)
				(arc
					(start 137.214864 -33.400238)
					(mid 137.700131 -33.885124)
					(end 138.185144 -33.399984)
				)
			)
		)
		(polygon
			(pts
				(arc
					(start 134.585202 -32.00019)
					(mid 134.100062 -31.51505)
					(end 133.614922 -32.00019)
				)
				(arc
					(start 133.614922 -33.400238)
					(mid 134.100189 -33.885124)
					(end 134.585202 -33.399984)
				)
			)
		)
		(polygon
			(pts
				(arc
					(start 130.985006 -32.00019)
					(mid 130.499866 -31.51505)
					(end 130.014726 -32.00019)
				)
				(arc
					(start 130.014726 -33.400238)
					(mid 130.499993 -33.885124)
					(end 130.985006 -33.399984)
				)
			)
		)
		(polygon
			(pts
				(arc
					(start 120.18518 -32.00019)
					(mid 119.70004 -31.51505)
					(end 119.2149 -32.00019)
				)
				(arc
					(start 119.2149 -33.400238)
					(mid 119.700167 -33.885124)
					(end 120.18518 -33.399984)
				)
			)
		)
		(polygon
			(pts
				(arc
					(start 116.584984 -32.00019)
					(mid 116.099844 -31.51505)
					(end 115.614704 -32.00019)
				)
				(arc
					(start 115.614704 -33.400238)
					(mid 116.099971 -33.885124)
					(end 116.584984 -33.399984)
				)
			)
		)
		(polygon
			(pts
				(arc
					(start 112.985042 -32.00019)
					(mid 112.499902 -31.51505)
					(end 112.014762 -32.00019)
				)
				(arc
					(start 112.014762 -33.400238)
					(mid 112.500029 -33.885124)
					(end 112.985042 -33.399984)
				)
			)
		)
		(polygon
			(pts
				(arc
					(start 109.3851 -32.00019)
					(mid 108.89996 -31.51505)
					(end 108.41482 -32.00019)
				)
				(arc
					(start 108.41482 -33.400238)
					(mid 108.900087 -33.885124)
					(end 109.3851 -33.399984)
				)
			)
		)
		(polygon
			(pts
				(arc
					(start 129.535428 -26.592276)
					(mid 129.916174 -26.211149)
					(end 129.535174 -25.830276)
				)
				(arc
					(start 128.467866 -25.830276)
					(mid 128.086866 -26.211276)
					(end 128.467866 -26.592276)
				)
			)
		)
	)
	(zone
		(layer "Cmts.User")
		(hatch none 0.5)
		(connect_pads
			(clearance 0)
		)
		(min_thickness 0.25)
		(keepout
			(tracks allowed)
			(vias allowed)
			(pads allowed)
			(copperpour allowed)
			(footprints allowed)
		)
		(placement
			(enabled no)
			(sheetname "")
		)
		(fill
			(thermal_gap 0.5)
			(thermal_bridge_width 0.5)
			(island_removal_mode 0)
		)
		(polygon
			(pts
				(xy 129.966974 -37.575744) (xy 129.966974 -35.119056) (xy 131.042664 -35.119056) (xy 131.042664 -37.575744)
			)
		)
	)
	(zone
		(layer "Cmts.User")
		(hatch none 0.5)
		(connect_pads
			(clearance 0)
		)
		(min_thickness 0.25)
		(keepout
			(tracks allowed)
			(vias allowed)
			(pads allowed)
			(copperpour allowed)
			(footprints allowed)
		)
		(placement
			(enabled no)
			(sheetname "")
		)
		(fill
			(thermal_gap 0.5)
			(thermal_bridge_width 0.5)
			(island_removal_mode 0)
		)
		(polygon
			(pts
				(xy 180.001164 -139.416282) (xy 181.401212 -140.81633) (xy 180.683408 -141.534134) (xy 179.28336 -140.134086)
			)
		)
	)
	(zone
		(layer "Cmts.User")
		(hatch none 0.5)
		(connect_pads
			(clearance 0)
		)
		(min_thickness 0.25)
		(keepout
			(tracks allowed)
			(vias allowed)
			(pads allowed)
			(copperpour allowed)
			(footprints allowed)
		)
		(placement
			(enabled no)
			(sheetname "")
		)
		(fill
			(thermal_gap 0.5)
			(thermal_bridge_width 0.5)
			(island_removal_mode 0)
		)
		(polygon
			(pts
				(xy 15.0876 -150.3172) (xy 15.0876 -132.842) (xy 24.638 -132.842) (xy 24.638 -150.3172)
			)
		)
	)
	(zone
		(layer "Cmts.User")
		(hatch none 0.5)
		(connect_pads
			(clearance 0)
		)
		(min_thickness 0.25)
		(keepout
			(tracks allowed)
			(vias allowed)
			(pads allowed)
			(copperpour allowed)
			(footprints allowed)
		)
		(placement
			(enabled no)
			(sheetname "")
		)
		(fill
			(thermal_gap 0.5)
			(thermal_bridge_width 0.5)
			(island_removal_mode 0)
		)
		(polygon
			(pts
				(xy 115.58016 -33.913064) (xy 115.58016 -31.456376) (xy 116.65585 -31.456376) (xy 116.65585 -33.913064)
			)
		)
	)
	(zone
		(layer "Cmts.User")
		(hatch none 0.5)
		(connect_pads
			(clearance 0)
		)
		(min_thickness 0.25)
		(keepout
			(tracks allowed)
			(vias allowed)
			(pads allowed)
			(copperpour allowed)
			(footprints allowed)
		)
		(placement
			(enabled no)
			(sheetname "")
		)
		(fill
			(thermal_gap 0.5)
			(thermal_bridge_width 0.5)
			(island_removal_mode 0)
		)
		(polygon
			(pts
				(xy 76.8985 -69.13372) (xy 76.8985 -66.677032) (xy 77.97419 -66.677032) (xy 77.97419 -69.13372)
			)
		)
	)
	(zone
		(layer "Cmts.User")
		(hatch none 0.5)
		(connect_pads
			(clearance 0)
		)
		(min_thickness 0.25)
		(keepout
			(tracks allowed)
			(vias allowed)
			(pads allowed)
			(copperpour allowed)
			(footprints allowed)
		)
		(placement
			(enabled no)
			(sheetname "")
		)
		(fill
			(thermal_gap 0.5)
			(thermal_bridge_width 0.5)
			(island_removal_mode 0)
		)
		(polygon
			(pts
				(xy 213.31936 -138.126724) (xy 214.719408 -139.526772) (xy 214.001604 -140.244322) (xy 212.601556 -138.844274)
			)
		)
	)
	(zone
		(layer "Cmts.User")
		(hatch none 0.5)
		(connect_pads
			(clearance 0)
		)
		(min_thickness 0.25)
		(keepout
			(tracks allowed)
			(vias allowed)
			(pads allowed)
			(copperpour allowed)
			(footprints allowed)
		)
		(placement
			(enabled no)
			(sheetname "")
		)
		(fill
			(thermal_gap 0.5)
			(thermal_bridge_width 0.5)
			(island_removal_mode 0)
		)
		(polygon
			(pts
				(xy 209.596736 -139.79525) (xy 210.996784 -141.195298) (xy 210.27898 -141.913102) (xy 208.878932 -140.513054)
			)
		)
	)
	(zone
		(layer "Cmts.User")
		(hatch none 0.5)
		(connect_pads
			(clearance 0)
		)
		(min_thickness 0.25)
		(keepout
			(tracks allowed)
			(vias allowed)
			(pads allowed)
			(copperpour allowed)
			(footprints allowed)
		)
		(placement
			(enabled no)
			(sheetname "")
		)
		(fill
			(thermal_gap 0.5)
			(thermal_bridge_width 0.5)
			(island_removal_mode 0)
		)
		(polygon
			(pts
				(xy 140.740638 -37.511228) (xy 140.740638 -35.05454) (xy 141.816328 -35.05454) (xy 141.816328 -37.511228)
			)
		)
	)
	(zone
		(layer "Cmts.User")
		(hatch none 0.5)
		(connect_pads
			(clearance 0)
		)
		(min_thickness 0.25)
		(keepout
			(tracks allowed)
			(vias allowed)
			(pads allowed)
			(copperpour allowed)
			(footprints allowed)
		)
		(placement
			(enabled no)
			(sheetname "")
		)
		(fill
			(thermal_gap 0.5)
			(thermal_bridge_width 0.5)
			(island_removal_mode 0)
		)
		(polygon
			(pts
				(xy 110.217458 -35.069272) (xy 110.217458 -32.612584) (xy 111.293148 -32.612584) (xy 111.293148 -35.069272)
			)
		)
	)
	(zone
		(layer "Cmts.User")
		(hatch none 0.5)
		(connect_pads
			(clearance 0)
		)
		(min_thickness 0.25)
		(keepout
			(tracks allowed)
			(vias allowed)
			(pads allowed)
			(copperpour allowed)
			(footprints allowed)
		)
		(placement
			(enabled no)
			(sheetname "")
		)
		(fill
			(thermal_gap 0.5)
			(thermal_bridge_width 0.5)
			(island_removal_mode 0)
		)
		(polygon
			(pts
				(xy 133.547612 -33.930844) (xy 133.547612 -31.474156) (xy 134.623302 -31.474156) (xy 134.623302 -33.930844)
			)
		)
	)
	(zone
		(layer "Cmts.User")
		(hatch none 0.5)
		(connect_pads
			(clearance 0)
		)
		(min_thickness 0.25)
		(keepout
			(tracks allowed)
			(vias allowed)
			(pads allowed)
			(copperpour allowed)
			(footprints allowed)
		)
		(placement
			(enabled no)
			(sheetname "")
		)
		(fill
			(thermal_gap 0.5)
			(thermal_bridge_width 0.5)
			(island_removal_mode 0)
		)
		(polygon
			(pts
				(xy 36.190936 -156.4386) (xy 36.190936 -133.5786) (xy 59.152536 -133.5786) (xy 59.152536 -141.224)
				(xy 60.5028 -142.574264) (xy 60.5028 -145.669) (xy 59.814968 -146.356832) (xy 59.814968 -150.065232)
				(xy 61.3664 -151.616664) (xy 61.3664 -155.1432) (xy 60.071 -156.4386) (xy 59.152536 -156.4386)
			)
		)
	)
	(zone
		(layer "Cmts.User")
		(hatch none 0.5)
		(connect_pads
			(clearance 0)
		)
		(min_thickness 0.25)
		(keepout
			(tracks allowed)
			(vias allowed)
			(pads allowed)
			(copperpour allowed)
			(footprints allowed)
		)
		(placement
			(enabled no)
			(sheetname "")
		)
		(fill
			(thermal_gap 0.5)
			(thermal_bridge_width 0.5)
			(island_removal_mode 0)
		)
		(polygon
			(pts
				(xy 111.903256 -33.913064) (xy 111.903256 -31.456376) (xy 112.978946 -31.456376) (xy 112.978946 -33.913064)
			)
		)
	)
	(zone
		(layer "Cmts.User")
		(hatch none 0.5)
		(connect_pads
			(clearance 0)
		)
		(min_thickness 0.25)
		(keepout
			(tracks allowed)
			(vias allowed)
			(pads allowed)
			(copperpour allowed)
			(footprints allowed)
		)
		(placement
			(enabled no)
			(sheetname "")
		)
		(fill
			(thermal_gap 0.5)
			(thermal_bridge_width 0.5)
			(island_removal_mode 0)
		)
		(polygon
			(pts
				(xy 108.38688 -33.800796) (xy 108.38688 -31.344108) (xy 109.46257 -31.344108) (xy 109.46257 -33.800796)
			)
		)
	)
	(zone
		(layer "Cmts.User")
		(hatch none 0.5)
		(connect_pads
			(clearance 0)
		)
		(min_thickness 0.25)
		(keepout
			(tracks allowed)
			(vias allowed)
			(pads allowed)
			(copperpour allowed)
			(footprints allowed)
		)
		(placement
			(enabled no)
			(sheetname "")
		)
		(fill
			(thermal_gap 0.5)
			(thermal_bridge_width 0.5)
			(island_removal_mode 0)
		)
		(polygon
			(pts
				(xy 76.7588 -75.408282) (xy 76.7588 -72.951594) (xy 77.879448 -72.951594) (xy 77.879448 -75.408282)
			)
		)
	)
	(zone
		(layer "Cmts.User")
		(hatch none 0.5)
		(connect_pads
			(clearance 0)
		)
		(min_thickness 0.25)
		(keepout
			(tracks allowed)
			(vias allowed)
			(pads allowed)
			(copperpour allowed)
			(footprints allowed)
		)
		(placement
			(enabled no)
			(sheetname "")
		)
		(fill
			(thermal_gap 0.5)
			(thermal_bridge_width 0.5)
			(island_removal_mode 0)
		)
		(polygon
			(pts
				(xy 170.403012 -137.589514) (xy 171.80306 -138.989562) (xy 171.085256 -139.707366) (xy 169.685208 -138.307318)
			)
		)
	)
	(zone
		(layer "Cmts.User")
		(hatch none 0.5)
		(connect_pads
			(clearance 0)
		)
		(min_thickness 0.25)
		(keepout
			(tracks allowed)
			(vias allowed)
			(pads allowed)
			(copperpour allowed)
			(footprints allowed)
		)
		(placement
			(enabled no)
			(sheetname "")
		)
		(fill
			(thermal_gap 0.5)
			(thermal_bridge_width 0.5)
			(island_removal_mode 0)
		)
		(polygon
			(pts
				(xy 84.481162 -80.252062) (xy 84.481162 -77.795374) (xy 85.556852 -77.795374) (xy 85.556852 -80.252062)
			)
		)
	)
	(zone
		(layer "Cmts.User")
		(hatch none 0.5)
		(connect_pads
			(clearance 0)
		)
		(min_thickness 0.25)
		(keepout
			(tracks allowed)
			(vias allowed)
			(pads allowed)
			(copperpour allowed)
			(footprints allowed)
		)
		(placement
			(enabled no)
			(sheetname "")
		)
		(fill
			(thermal_gap 0.5)
			(thermal_bridge_width 0.5)
			(island_removal_mode 0)
		)
		(polygon
			(pts
				(xy 82.892646 -96.260666) (xy 82.892646 -93.803978) (xy 83.968336 -93.803978) (xy 83.968336 -96.260666)
			)
		)
	)
	(zone
		(layer "Cmts.User")
		(hatch none 0.5)
		(connect_pads
			(clearance 0)
		)
		(min_thickness 0.25)
		(keepout
			(tracks allowed)
			(vias allowed)
			(pads allowed)
			(copperpour allowed)
			(footprints allowed)
		)
		(placement
			(enabled no)
			(sheetname "")
		)
		(fill
			(thermal_gap 0.5)
			(thermal_bridge_width 0.5)
			(island_removal_mode 0)
		)
		(polygon
			(pts
				(xy 133.563614 -37.527484) (xy 133.563614 -35.070796) (xy 134.639304 -35.070796) (xy 134.639304 -37.527484)
			)
		)
	)
	(zone
		(layer "Cmts.User")
		(hatch none 0.5)
		(connect_pads
			(clearance 0)
		)
		(min_thickness 0.25)
		(keepout
			(tracks allowed)
			(vias allowed)
			(pads allowed)
			(copperpour allowed)
			(footprints allowed)
		)
		(placement
			(enabled no)
			(sheetname "")
		)
		(fill
			(thermal_gap 0.5)
			(thermal_bridge_width 0.5)
			(island_removal_mode 0)
		)
		(polygon
			(pts
				(xy 82.879184 -83.43011) (xy 82.879184 -80.973422) (xy 83.954874 -80.973422) (xy 83.954874 -83.43011)
			)
		)
	)
	(zone
		(layer "Cmts.User")
		(hatch none 0.5)
		(connect_pads
			(clearance 0)
		)
		(min_thickness 0.25)
		(keepout
			(tracks allowed)
			(vias allowed)
			(pads allowed)
			(copperpour allowed)
			(footprints allowed)
		)
		(placement
			(enabled no)
			(sheetname "")
		)
		(fill
			(thermal_gap 0.5)
			(thermal_bridge_width 0.5)
			(island_removal_mode 0)
		)
		(polygon
			(pts
				(xy 119.177054 -37.479224) (xy 119.177054 -35.022536) (xy 120.252744 -35.022536) (xy 120.252744 -37.479224)
			)
		)
	)
	(zone
		(layer "Cmts.User")
		(hatch none 0.5)
		(connect_pads
			(clearance 0)
		)
		(min_thickness 0.25)
		(keepout
			(tracks allowed)
			(vias allowed)
			(pads allowed)
			(copperpour allowed)
			(footprints allowed)
		)
		(placement
			(enabled no)
			(sheetname "")
		)
		(fill
			(thermal_gap 0.5)
			(thermal_bridge_width 0.5)
			(island_removal_mode 0)
		)
		(polygon
			(pts
				(xy 197.77583 -139.907264) (xy 199.175878 -141.307312) (xy 198.458074 -142.025116) (xy 197.058026 -140.625068)
			)
		)
	)
	(zone
		(layer "Cmts.User")
		(hatch none 0.5)
		(connect_pads
			(clearance 0)
		)
		(min_thickness 0.25)
		(keepout
			(tracks allowed)
			(vias allowed)
			(pads allowed)
			(copperpour allowed)
			(footprints allowed)
		)
		(placement
			(enabled no)
			(sheetname "")
		)
		(fill
			(thermal_gap 0.5)
			(thermal_bridge_width 0.5)
			(island_removal_mode 0)
		)
		(polygon
			(pts
				(xy 131.749292 -35.135058) (xy 131.749292 -32.67837) (xy 132.824982 -32.67837) (xy 132.824982 -35.135058)
			)
		)
	)
	(zone
		(layer "Cmts.User")
		(hatch none 0.5)
		(connect_pads
			(clearance 0)
		)
		(min_thickness 0.25)
		(keepout
			(tracks allowed)
			(vias allowed)
			(pads allowed)
			(copperpour allowed)
			(footprints allowed)
		)
		(placement
			(enabled no)
			(sheetname "")
		)
		(fill
			(thermal_gap 0.5)
			(thermal_bridge_width 0.5)
			(island_removal_mode 0)
		)
		(polygon
			(pts
				(xy 206.43469 -138.511534) (xy 207.834738 -139.911582) (xy 207.116934 -140.629386) (xy 205.716886 -139.229338)
			)
		)
	)
	(zone
		(layer "Cmts.User")
		(hatch none 0.5)
		(connect_pads
			(clearance 0)
		)
		(min_thickness 0.25)
		(keepout
			(tracks allowed)
			(vias allowed)
			(pads allowed)
			(copperpour allowed)
			(footprints allowed)
		)
		(placement
			(enabled no)
			(sheetname "")
		)
		(fill
			(thermal_gap 0.5)
			(thermal_bridge_width 0.5)
			(island_removal_mode 0)
		)
		(polygon
			(pts
				(xy 119.191278 -44.719748) (xy 119.191278 -42.26306) (xy 120.266968 -42.26306) (xy 120.266968 -44.719748)
			)
		)
	)
	(zone
		(layer "Cmts.User")
		(hatch none 0.5)
		(connect_pads
			(clearance 0)
		)
		(min_thickness 0.25)
		(keepout
			(tracks allowed)
			(vias allowed)
			(pads allowed)
			(copperpour allowed)
			(footprints allowed)
		)
		(placement
			(enabled no)
			(sheetname "")
		)
		(fill
			(thermal_gap 0.5)
			(thermal_bridge_width 0.5)
			(island_removal_mode 0)
		)
		(polygon
			(pts
				(xy 76.829158 -81.834482) (xy 76.829158 -79.377794) (xy 77.904848 -79.377794) (xy 77.904848 -81.834482)
			)
		)
	)
	(zone
		(layer "Cmts.User")
		(hatch none 0.5)
		(connect_pads
			(clearance 0)
		)
		(min_thickness 0.25)
		(keepout
			(tracks allowed)
			(vias allowed)
			(pads allowed)
			(copperpour allowed)
			(footprints allowed)
		)
		(placement
			(enabled no)
			(sheetname "")
		)
		(fill
			(thermal_gap 0.5)
			(thermal_bridge_width 0.5)
			(island_removal_mode 0)
		)
		(polygon
			(pts
				(xy 200.179686 -140.19149) (xy 201.579734 -141.591538) (xy 200.86193 -142.309342) (xy 199.461882 -140.909294)
			)
		)
	)
	(zone
		(layer "Cmts.User")
		(hatch none 0.5)
		(connect_pads
			(clearance 0)
		)
		(min_thickness 0.25)
		(keepout
			(tracks allowed)
			(vias allowed)
			(pads allowed)
			(copperpour allowed)
			(footprints allowed)
		)
		(placement
			(enabled no)
			(sheetname "")
		)
		(fill
			(thermal_gap 0.5)
			(thermal_bridge_width 0.5)
			(island_removal_mode 0)
		)
		(polygon
			(pts
				(xy 177.640234 -139.226544) (xy 179.040282 -140.626592) (xy 178.322478 -141.344396) (xy 176.92243 -139.944348)
			)
		)
	)
	(zone
		(layer "Cmts.User")
		(hatch none 0.5)
		(connect_pads
			(clearance 0)
		)
		(min_thickness 0.25)
		(keepout
			(tracks allowed)
			(vias allowed)
			(pads allowed)
			(copperpour allowed)
			(footprints allowed)
		)
		(placement
			(enabled no)
			(sheetname "")
		)
		(fill
			(thermal_gap 0.5)
			(thermal_bridge_width 0.5)
			(island_removal_mode 0)
		)
		(polygon
			(pts
				(xy 174.25416 -139.493752) (xy 175.654208 -140.8938) (xy 174.936404 -141.611604) (xy 173.536356 -140.211556)
			)
		)
	)
	(zone
		(layer "Cmts.User")
		(hatch none 0.5)
		(connect_pads
			(clearance 0)
		)
		(min_thickness 0.25)
		(keepout
			(tracks allowed)
			(vias allowed)
			(pads allowed)
			(copperpour allowed)
			(footprints allowed)
		)
		(placement
			(enabled no)
			(sheetname "")
		)
		(fill
			(thermal_gap 0.5)
			(thermal_bridge_width 0.5)
			(island_removal_mode 0)
		)
		(polygon
			(pts
				(xy 167.09644 -136.180068) (xy 168.496488 -137.580116) (xy 167.778684 -138.29792) (xy 166.378636 -136.897872)
			)
		)
	)
	(zone
		(layer "Cmts.User")
		(hatch none 0.5)
		(connect_pads
			(clearance 0)
		)
		(min_thickness 0.25)
		(keepout
			(tracks allowed)
			(vias allowed)
			(pads allowed)
			(copperpour allowed)
			(footprints allowed)
		)
		(placement
			(enabled no)
			(sheetname "")
		)
		(fill
			(thermal_gap 0.5)
			(thermal_bridge_width 0.5)
			(island_removal_mode 0)
		)
		(polygon
			(pts
				(xy 84.49437 -86.67369) (xy 84.49437 -84.217002) (xy 85.57006 -84.217002) (xy 85.57006 -86.67369)
			)
		)
	)
	(zone
		(layer "Cmts.User")
		(hatch none 0.5)
		(connect_pads
			(clearance 0)
		)
		(min_thickness 0.25)
		(keepout
			(tracks allowed)
			(vias allowed)
			(pads allowed)
			(copperpour allowed)
			(footprints allowed)
		)
		(placement
			(enabled no)
			(sheetname "")
		)
		(fill
			(thermal_gap 0.5)
			(thermal_bridge_width 0.5)
			(island_removal_mode 0)
		)
		(polygon
			(pts
				(xy 119.14505 -33.978596) (xy 119.14505 -31.521908) (xy 120.22074 -31.521908) (xy 120.22074 -33.978596)
			)
		)
	)
	(zone
		(layer "Cmts.User")
		(hatch none 0.5)
		(connect_pads
			(clearance 0)
		)
		(min_thickness 0.25)
		(keepout
			(tracks allowed)
			(vias allowed)
			(pads allowed)
			(copperpour allowed)
			(footprints allowed)
		)
		(placement
			(enabled no)
			(sheetname "")
		)
		(fill
			(thermal_gap 0.5)
			(thermal_bridge_width 0.5)
			(island_removal_mode 0)
		)
		(polygon
			(pts
				(xy 137.143998 -33.914588) (xy 137.143998 -31.4579) (xy 138.219688 -31.4579) (xy 138.219688 -33.914588)
			)
		)
	)
	(zone
		(layer "Cmts.User")
		(hatch none 0.5)
		(connect_pads
			(clearance 0)
		)
		(min_thickness 0.25)
		(keepout
			(tracks allowed)
			(vias allowed)
			(pads allowed)
			(copperpour allowed)
			(footprints allowed)
		)
		(placement
			(enabled no)
			(sheetname "")
		)
		(fill
			(thermal_gap 0.5)
			(thermal_bridge_width 0.5)
			(island_removal_mode 0)
		)
		(polygon
			(pts
				(xy 185.08472 -138.95959) (xy 186.484768 -140.359638) (xy 185.766964 -141.077442) (xy 184.366916 -139.677394)
			)
		)
	)
	(zone
		(layer "Cmts.User")
		(hatch none 0.5)
		(connect_pads
			(clearance 0)
		)
		(min_thickness 0.25)
		(keepout
			(tracks allowed)
			(vias allowed)
			(pads allowed)
			(copperpour allowed)
			(footprints allowed)
		)
		(placement
			(enabled no)
			(sheetname "")
		)
		(fill
			(thermal_gap 0.5)
			(thermal_bridge_width 0.5)
			(island_removal_mode 0)
		)
		(polygon
			(pts
				(xy 138.942318 -38.763702) (xy 138.942318 -36.307014) (xy 140.018008 -36.307014) (xy 140.018008 -38.763702)
			)
		)
	)
	(zone
		(layer "Cmts.User")
		(hatch none 0.5)
		(connect_pads
			(clearance 0)
		)
		(min_thickness 0.25)
		(keepout
			(tracks allowed)
			(vias allowed)
			(pads allowed)
			(copperpour allowed)
			(footprints allowed)
		)
		(placement
			(enabled no)
			(sheetname "")
		)
		(fill
			(thermal_gap 0.5)
			(thermal_bridge_width 0.5)
			(island_removal_mode 0)
		)
		(polygon
			(pts
				(xy 204.866748 -140.19149) (xy 206.266796 -141.591538) (xy 205.548992 -142.309342) (xy 204.148944 -140.909294)
			)
		)
	)
	(zone
		(layer "Cmts.User")
		(hatch none 0.5)
		(connect_pads
			(clearance 0)
		)
		(min_thickness 0.25)
		(keepout
			(tracks allowed)
			(vias allowed)
			(pads allowed)
			(copperpour allowed)
			(footprints allowed)
		)
		(placement
			(enabled no)
			(sheetname "")
		)
		(fill
			(thermal_gap 0.5)
			(thermal_bridge_width 0.5)
			(island_removal_mode 0)
		)
		(polygon
			(pts
				(xy 138.974322 -35.1028) (xy 138.974322 -32.646112) (xy 140.050012 -32.646112) (xy 140.050012 -35.1028)
			)
		)
	)
	(zone
		(layer "Cmts.User")
		(hatch none 0.5)
		(connect_pads
			(clearance 0)
		)
		(min_thickness 0.25)
		(keepout
			(tracks allowed)
			(vias allowed)
			(pads allowed)
			(copperpour allowed)
			(footprints allowed)
		)
		(placement
			(enabled no)
			(sheetname "")
		)
		(fill
			(thermal_gap 0.5)
			(thermal_bridge_width 0.5)
			(island_removal_mode 0)
		)
		(polygon
			(pts
				(xy 184.394602 -133.449822) (xy 182.414418 -133.449822) (xy 182.414672 -132.434838) (xy 184.394602 -132.434838)
			)
		)
	)
	(zone
		(layer "Cmts.User")
		(hatch none 0.5)
		(connect_pads
			(clearance 0)
		)
		(min_thickness 0.25)
		(keepout
			(tracks allowed)
			(vias allowed)
			(pads allowed)
			(copperpour allowed)
			(footprints allowed)
		)
		(placement
			(enabled no)
			(sheetname "")
		)
		(fill
			(thermal_gap 0.5)
			(thermal_bridge_width 0.5)
			(island_removal_mode 0)
		)
		(polygon
			(pts
				(xy 115.547902 -37.493702) (xy 115.547902 -35.037014) (xy 116.623592 -35.037014) (xy 116.623592 -37.493702)
			)
		)
	)
	(zone
		(layer "Cmts.User")
		(hatch none 0.5)
		(connect_pads
			(clearance 0)
		)
		(min_thickness 0.25)
		(keepout
			(tracks allowed)
			(vias allowed)
			(pads allowed)
			(copperpour allowed)
			(footprints allowed)
		)
		(placement
			(enabled no)
			(sheetname "")
		)
		(fill
			(thermal_gap 0.5)
			(thermal_bridge_width 0.5)
			(island_removal_mode 0)
		)
		(polygon
			(pts
				(xy 77.641958 -72.207882) (xy 77.641958 -69.751194) (xy 78.717648 -69.751194) (xy 78.717648 -72.207882)
			)
		)
	)
	(zone
		(layer "Cmts.User")
		(hatch none 0.5)
		(connect_pads
			(clearance 0)
		)
		(min_thickness 0.25)
		(keepout
			(tracks allowed)
			(vias allowed)
			(pads allowed)
			(copperpour allowed)
			(footprints allowed)
		)
		(placement
			(enabled no)
			(sheetname "")
		)
		(fill
			(thermal_gap 0.5)
			(thermal_bridge_width 0.5)
			(island_removal_mode 0)
		)
		(polygon
			(pts
				(xy 140.772642 -33.946846) (xy 140.772642 -31.490158) (xy 141.848332 -31.490158) (xy 141.848332 -33.946846)
			)
		)
	)
	(zone
		(layer "Cmts.User")
		(hatch none 0.5)
		(connect_pads
			(clearance 0)
		)
		(min_thickness 0.25)
		(keepout
			(tracks allowed)
			(vias allowed)
			(pads allowed)
			(copperpour allowed)
			(footprints allowed)
		)
		(placement
			(enabled no)
			(sheetname "")
		)
		(fill
			(thermal_gap 0.5)
			(thermal_bridge_width 0.5)
			(island_removal_mode 0)
		)
		(polygon
			(pts
				(xy 192.012062 -138.554714) (xy 193.41211 -139.954762) (xy 192.694306 -140.672566) (xy 191.294258 -139.272518)
			)
		)
	)
	(zone
		(layer "Cmts.User")
		(hatch none 0.5)
		(connect_pads
			(clearance 0)
		)
		(min_thickness 0.25)
		(keepout
			(tracks allowed)
			(vias allowed)
			(pads allowed)
			(copperpour allowed)
			(footprints allowed)
		)
		(placement
			(enabled no)
			(sheetname "")
		)
		(fill
			(thermal_gap 0.5)
			(thermal_bridge_width 0.5)
			(island_removal_mode 0)
		)
		(polygon
			(pts
				(xy 108.36656 -37.4777) (xy 108.36656 -35.021012) (xy 109.44225 -35.021012) (xy 109.44225 -37.4777)
			)
		)
	)
	(zone
		(layer "Cmts.User")
		(hatch none 0.5)
		(connect_pads
			(clearance 0)
		)
		(min_thickness 0.25)
		(keepout
			(tracks allowed)
			(vias allowed)
			(pads allowed)
			(copperpour allowed)
			(footprints allowed)
		)
		(placement
			(enabled no)
			(sheetname "")
		)
		(fill
			(thermal_gap 0.5)
			(thermal_bridge_width 0.5)
			(island_removal_mode 0)
		)
		(polygon
			(pts
				(xy 129.918714 -33.914842) (xy 129.918714 -31.458154) (xy 130.994404 -31.458154) (xy 130.994404 -33.914842)
			)
		)
	)
	(zone
		(layer "Cmts.User")
		(hatch none 0.5)
		(connect_pads
			(clearance 0)
		)
		(min_thickness 0.25)
		(keepout
			(tracks allowed)
			(vias allowed)
			(pads allowed)
			(copperpour allowed)
			(footprints allowed)
		)
		(placement
			(enabled no)
			(sheetname "")
		)
		(fill
			(thermal_gap 0.5)
			(thermal_bridge_width 0.5)
			(island_removal_mode 0)
		)
		(polygon
			(pts
				(xy 77.641958 -84.933282) (xy 77.641958 -82.476594) (xy 78.717648 -82.476594) (xy 78.717648 -84.933282)
			)
		)
	)
	(zone
		(layer "Cmts.User")
		(hatch none 0.5)
		(connect_pads
			(clearance 0)
		)
		(min_thickness 0.25)
		(keepout
			(tracks allowed)
			(vias allowed)
			(pads allowed)
			(copperpour allowed)
			(footprints allowed)
		)
		(placement
			(enabled no)
			(sheetname "")
		)
		(fill
			(thermal_gap 0.5)
			(thermal_bridge_width 0.5)
			(island_removal_mode 0)
		)
		(polygon
			(pts
				(xy 106.58856 -35.117278) (xy 106.58856 -32.66059) (xy 107.66425 -32.66059) (xy 107.66425 -35.117278)
			)
		)
	)
	(zone
		(layer "Cmts.User")
		(hatch none 0.5)
		(connect_pads
			(clearance 0)
		)
		(min_thickness 0.25)
		(keepout
			(tracks allowed)
			(vias allowed)
			(pads allowed)
			(copperpour allowed)
			(footprints allowed)
		)
		(placement
			(enabled no)
			(sheetname "")
		)
		(fill
			(thermal_gap 0.5)
			(thermal_bridge_width 0.5)
			(island_removal_mode 0)
		)
		(polygon
			(pts
				(xy 137.16 -37.559488) (xy 137.16 -35.1028) (xy 138.23569 -35.1028) (xy 138.23569 -37.559488)
			)
		)
	)
	(zone
		(layer "Cmts.User")
		(hatch none 0.5)
		(connect_pads
			(clearance 0)
		)
		(min_thickness 0.25)
		(keepout
			(tracks allowed)
			(vias allowed)
			(pads allowed)
			(copperpour allowed)
			(footprints allowed)
		)
		(placement
			(enabled no)
			(sheetname "")
		)
		(fill
			(thermal_gap 0.5)
			(thermal_bridge_width 0.5)
			(island_removal_mode 0)
		)
		(polygon
			(pts
				(xy 111.951262 -37.525706) (xy 111.951262 -35.069018) (xy 113.026952 -35.069018) (xy 113.026952 -37.525706)
			)
		)
	)
	(zone
		(layer "Cmts.User")
		(hatch none 0.5)
		(connect_pads
			(clearance 0)
		)
		(min_thickness 0.25)
		(keepout
			(tracks allowed)
			(vias allowed)
			(pads allowed)
			(copperpour allowed)
			(footprints allowed)
		)
		(placement
			(enabled no)
			(sheetname "")
		)
		(fill
			(thermal_gap 0.5)
			(thermal_bridge_width 0.5)
			(island_removal_mode 0)
		)
		(polygon
			(pts
				(xy 113.765838 -35.101276) (xy 113.765838 -32.644588) (xy 114.841528 -32.644588) (xy 114.841528 -35.101276)
			)
		)
	)
	(zone
		(layer "Cmts.User")
		(hatch none 0.5)
		(connect_pads
			(clearance 0)
		)
		(min_thickness 0.25)
		(keepout
			(tracks allowed)
			(vias allowed)
			(pads allowed)
			(copperpour allowed)
			(footprints allowed)
		)
		(placement
			(enabled no)
			(sheetname "")
		)
		(fill
			(thermal_gap 0.5)
			(thermal_bridge_width 0.5)
			(island_removal_mode 0)
		)
		(polygon
			(pts
				(xy 117.330728 -35.18281) (xy 117.330728 -32.726122) (xy 118.406418 -32.726122) (xy 118.406418 -35.18281)
			)
		)
	)
	(zone
		(layer "Cmts.User")
		(hatch none 0.5)
		(connect_pads
			(clearance 0)
		)
		(min_thickness 0.25)
		(keepout
			(tracks allowed)
			(vias allowed)
			(pads allowed)
			(copperpour allowed)
			(footprints allowed)
		)
		(placement
			(enabled no)
			(sheetname "")
		)
		(fill
			(thermal_gap 0.5)
			(thermal_bridge_width 0.5)
			(island_removal_mode 0)
		)
		(polygon
			(pts
				(xy 76.803758 -94.585282) (xy 76.803758 -92.128594) (xy 77.879448 -92.128594) (xy 77.879448 -94.585282)
			)
		)
	)
	(zone
		(layer "Cmts.User")
		(hatch none 0.5)
		(connect_pads
			(clearance 0)
		)
		(min_thickness 0.25)
		(keepout
			(tracks allowed)
			(vias allowed)
			(pads allowed)
			(copperpour allowed)
			(footprints allowed)
		)
		(placement
			(enabled no)
			(sheetname "")
		)
		(fill
			(thermal_gap 0.5)
			(thermal_bridge_width 0.5)
			(island_removal_mode 0)
		)
		(polygon
			(pts
				(xy 202.60056 -140.045186) (xy 204.000608 -141.445234) (xy 203.282804 -142.163038) (xy 201.882756 -140.76299)
			)
		)
	)
	(zone
		(layer "Cmts.User")
		(hatch none 0.5)
		(connect_pads
			(clearance 0)
		)
		(min_thickness 0.25)
		(keepout
			(tracks allowed)
			(vias allowed)
			(pads allowed)
			(copperpour allowed)
			(footprints allowed)
		)
		(placement
			(enabled no)
			(sheetname "")
		)
		(fill
			(thermal_gap 0.5)
			(thermal_bridge_width 0.5)
			(island_removal_mode 0)
		)
		(polygon
			(pts
				(xy 131.765294 -38.7477) (xy 131.765294 -36.291012) (xy 132.840984 -36.291012) (xy 132.840984 -38.7477)
			)
		)
	)
	(zone
		(layer "Cmts.User")
		(hatch none 0.5)
		(connect_pads
			(clearance 0)
		)
		(min_thickness 0.25)
		(keepout
			(tracks allowed)
			(vias allowed)
			(pads allowed)
			(copperpour allowed)
			(footprints allowed)
		)
		(placement
			(enabled no)
			(sheetname "")
		)
		(fill
			(thermal_gap 0.5)
			(thermal_bridge_width 0.5)
			(island_removal_mode 0)
		)
		(polygon
			(pts
				(xy 128.120394 -38.699694) (xy 128.120394 -36.243006) (xy 129.196084 -36.243006) (xy 129.196084 -38.699694)
			)
		)
	)
	(zone
		(layer "Cmts.User")
		(hatch none 0.5)
		(connect_pads
			(clearance 0)
		)
		(min_thickness 0.25)
		(keepout
			(tracks allowed)
			(vias allowed)
			(pads allowed)
			(copperpour allowed)
			(footprints allowed)
		)
		(placement
			(enabled no)
			(sheetname "")
		)
		(fill
			(thermal_gap 0.5)
			(thermal_bridge_width 0.5)
			(island_removal_mode 0)
		)
		(polygon
			(pts
				(xy 182.267098 -138.942318) (xy 183.667146 -140.342366) (xy 182.949342 -141.06017) (xy 181.549294 -139.660122)
			)
		)
	)
	(zone
		(layer "Cmts.User")
		(hatch none 0.5)
		(connect_pads
			(clearance 0)
		)
		(min_thickness 0.25)
		(keepout
			(tracks allowed)
			(vias allowed)
			(pads allowed)
			(copperpour allowed)
			(footprints allowed)
		)
		(placement
			(enabled no)
			(sheetname "")
		)
		(fill
			(thermal_gap 0.5)
			(thermal_bridge_width 0.5)
			(island_removal_mode 0)
		)
		(polygon
			(pts
				(xy 84.533994 -92.964508) (xy 84.533994 -90.50782) (xy 85.609684 -90.50782) (xy 85.609684 -92.964508)
			)
		)
	)
	(zone
		(layer "Cmts.User")
		(hatch none 0.5)
		(connect_pads
			(clearance 0)
		)
		(min_thickness 0.25)
		(keepout
			(tracks allowed)
			(vias allowed)
			(pads allowed)
			(copperpour allowed)
			(footprints allowed)
		)
		(placement
			(enabled no)
			(sheetname "")
		)
		(fill
			(thermal_gap 0.5)
			(thermal_bridge_width 0.5)
			(island_removal_mode 0)
		)
		(polygon
			(pts
				(xy 77.641958 -91.334082) (xy 77.641958 -88.877394) (xy 78.717648 -88.877394) (xy 78.717648 -91.334082)
			)
		)
	)
	(zone
		(layer "Cmts.User")
		(hatch none 0.5)
		(connect_pads
			(clearance 0)
		)
		(min_thickness 0.25)
		(keepout
			(tracks allowed)
			(vias allowed)
			(pads allowed)
			(copperpour allowed)
			(footprints allowed)
		)
		(placement
			(enabled no)
			(sheetname "")
		)
		(fill
			(thermal_gap 0.5)
			(thermal_bridge_width 0.5)
			(island_removal_mode 0)
		)
		(polygon
			(pts
				(xy 77.667358 -78.583282) (xy 77.667358 -76.126594) (xy 78.743048 -76.126594) (xy 78.743048 -78.583282)
			)
		)
	)
	(zone
		(layer "Cmts.User")
		(hatch none 0.5)
		(connect_pads
			(clearance 0)
		)
		(min_thickness 0.25)
		(keepout
			(tracks allowed)
			(vias allowed)
			(pads allowed)
			(copperpour allowed)
			(footprints allowed)
		)
		(placement
			(enabled no)
			(sheetname "")
		)
		(fill
			(thermal_gap 0.5)
			(thermal_bridge_width 0.5)
			(island_removal_mode 0)
		)
		(polygon
			(pts
				(xy 133.587236 -44.726606) (xy 133.587236 -42.269918) (xy 134.662926 -42.269918) (xy 134.662926 -44.726606)
			)
		)
	)
	(zone
		(layer "Cmts.User")
		(hatch none 0.5)
		(connect_pads
			(clearance 0)
		)
		(min_thickness 0.25)
		(keepout
			(tracks allowed)
			(vias allowed)
			(pads allowed)
			(copperpour allowed)
			(footprints allowed)
		)
		(placement
			(enabled no)
			(sheetname "")
		)
		(fill
			(thermal_gap 0.5)
			(thermal_bridge_width 0.5)
			(island_removal_mode 0)
		)
		(polygon
			(pts
				(xy 128.120394 -35.119056) (xy 128.120394 -32.662368) (xy 129.196084 -32.662368) (xy 129.196084 -35.119056)
			)
		)
	)
	(zone
		(layer "Cmts.User")
		(hatch none 0.5)
		(connect_pads
			(clearance 0)
		)
		(min_thickness 0.25)
		(keepout
			(tracks allowed)
			(vias allowed)
			(pads allowed)
			(copperpour allowed)
			(footprints allowed)
		)
		(placement
			(enabled no)
			(sheetname "")
		)
		(fill
			(thermal_gap 0.5)
			(thermal_bridge_width 0.5)
			(island_removal_mode 0)
		)
		(polygon
			(pts
				(xy 82.865976 -77.021436) (xy 82.865976 -74.564748) (xy 83.941666 -74.564748) (xy 83.941666 -77.021436)
			)
		)
	)
	(zone
		(layer "Cmts.User")
		(hatch none 0.5)
		(connect_pads
			(clearance 0)
		)
		(min_thickness 0.25)
		(keepout
			(tracks allowed)
			(vias allowed)
			(pads allowed)
			(copperpour allowed)
			(footprints allowed)
		)
		(placement
			(enabled no)
			(sheetname "")
		)
		(fill
			(thermal_gap 0.5)
			(thermal_bridge_width 0.5)
			(island_removal_mode 0)
		)
		(polygon
			(pts
				(xy 110.160816 -38.681914) (xy 110.160816 -36.225226) (xy 111.236506 -36.225226) (xy 111.236506 -38.681914)
			)
		)
	)
	(zone
		(layer "Cmts.User")
		(hatch none 0.5)
		(connect_pads
			(clearance 0)
		)
		(min_thickness 0.25)
		(keepout
			(tracks allowed)
			(vias allowed)
			(pads allowed)
			(copperpour allowed)
			(footprints allowed)
		)
		(placement
			(enabled no)
			(sheetname "")
		)
		(fill
			(thermal_gap 0.5)
			(thermal_bridge_width 0.5)
			(island_removal_mode 0)
		)
		(polygon
			(pts
				(xy 106.558842 -38.757098) (xy 106.558842 -36.30041) (xy 107.634532 -36.30041) (xy 107.634532 -38.757098)
			)
		)
	)
	(zone
		(layer "Cmts.User")
		(hatch none 0.5)
		(connect_pads
			(clearance 0)
		)
		(min_thickness 0.25)
		(keepout
			(tracks allowed)
			(vias allowed)
			(pads allowed)
			(copperpour allowed)
			(footprints allowed)
		)
		(placement
			(enabled no)
			(sheetname "")
		)
		(fill
			(thermal_gap 0.5)
			(thermal_bridge_width 0.5)
			(island_removal_mode 0)
		)
		(polygon
			(pts
				(xy 173.892464 -137.176002) (xy 175.292512 -138.57605) (xy 174.574708 -139.293854) (xy 173.17466 -137.893806)
			)
		)
	)
	(zone
		(layer "Cmts.User")
		(hatch none 0.5)
		(connect_pads
			(clearance 0)
		)
		(min_thickness 0.25)
		(keepout
			(tracks allowed)
			(vias allowed)
			(pads allowed)
			(copperpour allowed)
			(footprints allowed)
		)
		(placement
			(enabled no)
			(sheetname "")
		)
		(fill
			(thermal_gap 0.5)
			(thermal_bridge_width 0.5)
			(island_removal_mode 0)
		)
		(polygon
			(pts
				(xy 82.879184 -89.838784) (xy 82.879184 -87.382096) (xy 83.954874 -87.382096) (xy 83.954874 -89.838784)
			)
		)
	)
	(zone
		(layer "Cmts.User")
		(hatch none 0.5)
		(connect_pads
			(clearance 0)
		)
		(min_thickness 0.25)
		(keepout
			(tracks allowed)
			(vias allowed)
			(pads allowed)
			(copperpour allowed)
			(footprints allowed)
		)
		(placement
			(enabled no)
			(sheetname "")
		)
		(fill
			(thermal_gap 0.5)
			(thermal_bridge_width 0.5)
			(island_removal_mode 0)
		)
		(polygon
			(pts
				(xy 84.36737 -73.60158) (xy 84.36737 -71.144892) (xy 85.44306 -71.144892) (xy 85.44306 -73.60158)
			)
		)
	)
	(zone
		(layer "Cmts.User")
		(hatch none 0.5)
		(connect_pads
			(clearance 0)
		)
		(min_thickness 0.25)
		(keepout
			(tracks allowed)
			(vias allowed)
			(pads allowed)
			(copperpour allowed)
			(footprints allowed)
		)
		(placement
			(enabled no)
			(sheetname "")
		)
		(fill
			(thermal_gap 0.5)
			(thermal_bridge_width 0.5)
			(island_removal_mode 0)
		)
		(polygon
			(pts
				(xy 195.122038 -139.63142) (xy 196.522086 -141.031468) (xy 195.804282 -141.749272) (xy 194.404234 -140.349224)
			)
		)
	)
	(zone
		(layer "Cmts.User")
		(hatch none 0.5)
		(connect_pads
			(clearance 0)
		)
		(min_thickness 0.25)
		(keepout
			(tracks allowed)
			(vias allowed)
			(pads allowed)
			(copperpour allowed)
			(footprints allowed)
		)
		(placement
			(enabled no)
			(sheetname "")
		)
		(fill
			(thermal_gap 0.5)
			(thermal_bridge_width 0.5)
			(island_removal_mode 0)
		)
		(polygon
			(pts
				(xy 140.767816 -44.726606) (xy 140.767816 -42.269918) (xy 141.843506 -42.269918) (xy 141.843506 -44.726606)
			)
		)
	)
	(zone
		(layer "Cmts.User")
		(hatch none 0.5)
		(connect_pads
			(clearance 0)
		)
		(min_thickness 0.25)
		(keepout
			(tracks allowed)
			(vias allowed)
			(pads allowed)
			(copperpour allowed)
			(footprints allowed)
		)
		(placement
			(enabled no)
			(sheetname "")
		)
		(fill
			(thermal_gap 0.5)
			(thermal_bridge_width 0.5)
			(island_removal_mode 0)
		)
		(polygon
			(pts
				(xy 129.971292 -26.745692) (xy 127.991108 -26.745692) (xy 127.991362 -25.730708) (xy 129.971292 -25.730708)
			)
		)
	)
	(zone
		(layer "Cmts.User")
		(hatch none 0.5)
		(connect_pads
			(clearance 0)
		)
		(min_thickness 0.25)
		(keepout
			(tracks allowed)
			(vias allowed)
			(pads allowed)
			(copperpour allowed)
			(footprints allowed)
		)
		(placement
			(enabled no)
			(sheetname "")
		)
		(fill
			(thermal_gap 0.5)
			(thermal_bridge_width 0.5)
			(island_removal_mode 0)
		)
		(polygon
			(pts
				(xy 117.394736 -38.763702) (xy 117.394736 -36.307014) (xy 118.470426 -36.307014) (xy 118.470426 -38.763702)
			)
		)
	)
	(zone
		(layer "Cmts.User")
		(hatch none 0.5)
		(connect_pads
			(clearance 0)
		)
		(min_thickness 0.25)
		(keepout
			(tracks allowed)
			(vias allowed)
			(pads allowed)
			(copperpour allowed)
			(footprints allowed)
		)
		(placement
			(enabled no)
			(sheetname "")
		)
		(fill
			(thermal_gap 0.5)
			(thermal_bridge_width 0.5)
			(island_removal_mode 0)
		)
		(polygon
			(pts
				(xy 76.778358 -88.209882) (xy 76.778358 -85.753194) (xy 77.854048 -85.753194) (xy 77.854048 -88.209882)
			)
		)
	)
	(zone
		(layer "Cmts.User")
		(hatch none 0.5)
		(connect_pads
			(clearance 0)
		)
		(min_thickness 0.25)
		(keepout
			(tracks allowed)
			(vias allowed)
			(pads allowed)
			(copperpour allowed)
			(footprints allowed)
		)
		(placement
			(enabled no)
			(sheetname "")
		)
		(fill
			(thermal_gap 0.5)
			(thermal_bridge_width 0.5)
			(island_removal_mode 0)
		)
		(polygon
			(pts
				(xy 135.31342 -38.715442) (xy 135.31342 -36.258754) (xy 136.38911 -36.258754) (xy 136.38911 -38.715442)
			)
		)
	)
	(zone
		(layer "Cmts.User")
		(hatch none 0.5)
		(connect_pads
			(clearance 0)
		)
		(min_thickness 0.25)
		(keepout
			(tracks allowed)
			(vias allowed)
			(pads allowed)
			(copperpour allowed)
			(footprints allowed)
		)
		(placement
			(enabled no)
			(sheetname "")
		)
		(fill
			(thermal_gap 0.5)
			(thermal_bridge_width 0.5)
			(island_removal_mode 0)
		)
		(polygon
			(pts
				(xy 135.377682 -35.167062) (xy 135.377682 -32.710374) (xy 136.453372 -32.710374) (xy 136.453372 -35.167062)
			)
		)
	)
	(zone
		(layer "Cmts.User")
		(hatch none 0.5)
		(connect_pads
			(clearance 0)
		)
		(min_thickness 0.25)
		(keepout
			(tracks allowed)
			(vias allowed)
			(pads allowed)
			(copperpour allowed)
			(footprints allowed)
		)
		(placement
			(enabled no)
			(sheetname "")
		)
		(fill
			(thermal_gap 0.5)
			(thermal_bridge_width 0.5)
			(island_removal_mode 0)
		)
		(polygon
			(pts
				(xy 113.741454 -38.722046) (xy 113.741454 -36.265358) (xy 114.817144 -36.265358) (xy 114.817144 -38.722046)
			)
		)
	)
)
